FILE_TYPE = MULTI_PHYS_TABLE;

PART 'Q_RES'

{========================================================================================}
:VALUE        | TOLERANCE | WATTAGE  | PACK_TYPE | MATERIAL | PART_NUMBER             = STANDARD        | LIFECYCLE          | PART_NUMBER             | JEDEC_TYPE          | ALT_SYMBOLS                    | VALUE     | TOL     | WATTAGE  | CLASS      | DESCRIPTION                                        | COMPONENT_TYPE | LEAD_LENGTH | DFM_EXCLUSION | DAY        ;
{========================================================================================}
 '64.9K'      | '1%'      | '1/10W'  | '0603LF'  | 'CHIP'   | 'TMP_QCS36493F913'(!)   = 'End of Design' | 'Comp-Approve'     | 'CS36493F913'           |'R0603'| '(SMR0603AW)'                  | '64.9K'   | '1%'    | '1/10W'  | 'DISCRETE' | '64.9Kohm 0603'                                    | 'CHIP0603'     | ''          | ''            | ''        
 '64.9K'      | '1%'      | '1/10W'  | '0603LF'  | 'EMPTY'  | 'TMP_QCS36493F913'(!)   = 'End of Design' | 'Comp-Approve'     | 'CS36493F913'           |'R0603'| '(SMR0603AW)'                  | '64.9K'   | '1%'    | '1/10W'  | 'IO'       | '64.9Kohm 0603'                                    | 'CHIP0603'     | ''          | ''            | ''        
 '107K'       | '1%'      | '1/10W'  | '0603LF'  | 'CHIP'   | 'TMP_QCS41073F918'(!)   = 'End of Design' | 'Comp-Approve'     | 'CS41073F918'           |'R0603'| '(SMR0603AW)'                  | '107K'    | '1%'    | '1/10W'  | 'DISCRETE' | '107Kohm 0603'                                     | 'CHIP0603'     | ''          | ''            | ''        
 '107K'       | '1%'      | '1/10W'  | '0603LF'  | 'EMPTY'  | 'TMP_QCS41073F918'(!)   = 'End of Design' | 'Comp-Approve'     | 'CS41073F918'           |'R0603'| '(SMR0603AW)'                  | '107K'    | '1%'    | '1/10W'  | 'IO'       | '107Kohm 0603'                                     | 'CHIP0603'     | ''          | ''            | ''        
 '3.6K'       | '1%'      | '1/10W'  | '0603LF'  | 'CHIP'   | 'TMP_QCS23603F910'(!)   = ''              | ''                 | 'CS23603F910'           |'R0603'| '(SMR0603AW)'                  | '3.6K'    | '1%'    | '1/10W'  | 'DISCRETE' | '3.6Kohm 0603'                                     | 'CHIP0603'     | ''          | ''            | ''        
 '3.6K'       | '1%'      | '1/10W'  | '0603LF'  | 'EMPTY'  | 'TMP_QCS23603F910'(!)   = ''              | ''                 | 'CS23603F910'           |'R0603'| '(SMR0603AW)'                  | '3.6K'    | '1%'    | '1/10W'  | 'IO'       | '3.6Kohm 0603'                                     | 'CHIP0603'     | ''          | ''            | ''        
 '169'        | '1%'      | '1/10W'  | '0603LF'  | 'CHIP'   | 'TMP_QCS11693F913'(!)   = 'End of Design' | 'Comp-Approve'     | 'CS11693F913'           |'R0603'| '(SMR0603AW)'                  | '169'     | '1%'    | '1/10W'  | 'DISCRETE' | '169ohm 0603'                                      | 'CHIP0603'     | ''          | ''            | ''        
 '169'        | '1%'      | '1/10W'  | '0603LF'  | 'EMPTY'  | 'TMP_QCS11693F913'(!)   = 'End of Design' | 'Comp-Approve'     | 'CS11693F913'           |'R0603'| '(SMR0603AW)'                  | '169'     | '1%'    | '1/10W'  | 'IO'       | '169ohm 0603'                                      | 'CHIP0603'     | ''          | ''            | ''        
 '210'        | '1%'      | '1/10W'  | '0603LF'  | 'CHIP'   | 'TMP_QCS12103F909'(!)   = ''              | ''                 | 'CS12103F909'           |'R0603'| '(SMR0603AW)'                  | '210'     | '1%'    | '1/10W'  | 'DISCRETE' | '210ohm 0603'                                      | 'CHIP0603'     | ''          | ''            | ''        
 '210'        | '1%'      | '1/10W'  | '0603LF'  | 'EMPTY'  | 'TMP_QCS12103F909'(!)   = ''              | ''                 | 'CS12103F909'           |'R0603'| '(SMR0603AW)'                  | '210'     | '1%'    | '1/10W'  | 'IO'       | '210ohm 0603'                                      | 'CHIP0603'     | ''          | ''            | ''        
 '9.53K'      | '1%'      | '1/10W'  | '0603LF'  | 'CHIP'   | 'TMP_QCS29533F908'(!)   = ''              | ''                 | 'CS29533F908'           |'R0603'| '(SMR0603AW)'                  | '9.53K'   | '1%'    | '1/10W'  | 'DISCRETE' | '9.53Kohm 0603'                                    | 'CHIP0603'     | ''          | ''            | ''        
 '9.53K'      | '1%'      | '1/10W'  | '0603LF'  | 'EMPTY'  | 'TMP_QCS29533F908'(!)   = ''              | ''                 | 'CS29533F908'           |'R0603'| '(SMR0603AW)'                  | '9.53K'   | '1%'    | '1/10W'  | 'IO'       | '9.53Kohm 0603'                                    | 'CHIP0603'     | ''          | ''            | ''        
 '787'        | '1%'      | '1/10W'  | '0603'    | 'CHIP'   | 'TMP_QCS17873F900'(!)   = ''              | ''                 | 'CS17873F900'           |'R0603'| '(SMR0603AW)'                  | '787'     | '1%'    | '1/10W'  | 'DISCRETE' | '787ohm 0603'                                      | 'CHIP0603'     | ''          | ''            | ''        
 '787'        | '1%'      | '1/10W'  | '0603'    | 'EMPTY'  | 'TMP_QCS17873F900'(!)   = ''              | ''                 | 'CS17873F900'           |'R0603'| '(SMR0603AW)'                  | '787'     | '1%'    | '1/10W'  | 'IO'       | '787ohm 0603'                                      | 'CHIP0603'     | ''          | ''            | ''        
 '30.1'       | '1%'      | '1/10W'  | '0603LF'  | 'CHIP'   | 'TMP_QCS03013F919'(!)   = ''              | ''                 | 'CS03013F919'           |'R0603'| '(SMR0603AW)'                  | '30.1'    | '1%'    | '1/10W'  | 'DISCRETE' | '30.1ohm 0603'                                     | 'CHIP0603'     | ''          | ''            | ''        
 '30.1'       | '1%'      | '1/10W'  | '0603LF'  | 'EMPTY'  | 'TMP_QCS03013F919'(!)   = ''              | ''                 | 'CS03013F919'           |'R0603'| '(SMR0603AW)'                  | '30.1'    | '1%'    | '1/10W'  | 'IO'       | '30.1ohm 0603'                                     | 'CHIP0603'     | ''          | ''            | ''        
 '2.2'        | '1%'      | '1/10W'  | '0603LF'  | 'CHIP'   | 'TMP_QCS-2203F911'(!)   = ''              | ''                 | 'CS-2203F911'           |'R0603'| '(SMR0603AW)'                  | '2.2'     | '1%'    | '1/10W'  | 'DISCRETE' | '2.2ohm 0603'                                      | 'CHIP0603'     | ''          | ''            | ''        
 '2.2'        | '1%'      | '1/10W'  | '0603LF'  | 'EMPTY'  | 'TMP_QCS-2203F911'(!)   = ''              | ''                 | 'CS-2203F911'           |'R0603'| '(SMR0603AW)'                  | '2.2'     | '1%'    | '1/10W'  | 'IO'       | '2.2ohm 0603'                                      | 'CHIP0603'     | ''          | ''            | ''        
 '32.4K'      | '1%'      | '1/10W'  | '0603LF'  | 'CHIP'   | 'TMP_QCS33243F915'(!)   = 'End of Design' | 'Comp-Approve'     | 'CS33243F915'           |'R0603'| '(SMR0603AW)'                  | '32.4K'   | '1%'    | '1/10W'  | 'DISCRETE' | '32.4Kohm 0603'                                    | 'CHIP0603'     | ''          | ''            | ''        
 '32.4K'      | '1%'      | '1/10W'  | '0603LF'  | 'EMPTY'  | 'TMP_QCS33243F915'(!)   = 'End of Design' | 'Comp-Approve'     | 'CS33243F915'           |'R0603'| '(SMR0603AW)'                  | '32.4K'   | '1%'    | '1/10W'  | 'IO'       | '32.4Kohm 0603'                                    | 'CHIP0603'     | ''          | ''            | ''        
 '1.87K'      | '1%'      | '1/16W'  | '0402LF'  | 'CHIP'   | 'TMP_QCS21872FB17'(!)   = 'End of Design' | 'Comp-Approve'     | 'CS21872FB17'           |'R0402'| '(R0402-0201)'                 | '1.87K'   | '1%'    | '1/16W'  | 'DISCRETE' | '1.87Kohm 0402'                                    | 'CHIP0402'     | ''          | ''            | ''        
 '1.87K'      | '1%'      | '1/16W'  | '0402LF'  | 'EMPTY'  | 'TMP_QCS21872FB17'(!)   = 'End of Design' | 'Comp-Approve'     | 'CS21872FB17'           |'R0402'| '(R0402-0201)'                 | '1.87K'   | '1%'    | '1/16W'  | 'IO'       | '1.87Kohm 0402'                                    | 'CHIP0402'     | ''          | ''            | ''        
 '18K'        | '1%'      | '1/16W'  | '0402LF'  | 'CHIP'   | 'TMP_QCS31802FB10'(!)   = 'End of Design' | 'Comp-Approve'     | 'CS31802FB10'           |'R0402'| '(R0402-0201)'                 | '18K'     | '1%'    | '1/16W'  | 'DISCRETE' | '18Kohm 0402'                                      | 'CHIP0402'     | ''          | ''            | ''        
 '18K'        | '1%'      | '1/16W'  | '0402LF'  | 'EMPTY'  | 'TMP_QCS31802FB10'(!)   = 'End of Design' | 'Comp-Approve'     | 'CS31802FB10'           |'R0402'| '(R0402-0201)'                 | '18K'     | '1%'    | '1/16W'  | 'IO'       | '18Kohm 0402'                                      | 'CHIP0402'     | ''          | ''            | ''        
 '17.8K'      | '1%'      | '1/16W'  | '0402LF'  | 'CHIP'   | 'TMP_QCS31782FB10'(!)   = 'End of Design' | 'Comp-Approve'     | 'CS31782FB10'           |'R0402'| '(R0402-0201)'                 | '17.8K'   | '1%'    | '1/16W'  | 'DISCRETE' | '17.8Kohm 0402'                                    | 'CHIP0402'     | ''          | ''            | ''        
 '17.8K'      | '1%'      | '1/16W'  | '0402LF'  | 'EMPTY'  | 'TMP_QCS31782FB10'(!)   = 'End of Design' | 'Comp-Approve'     | 'CS31782FB10'           |'R0402'| '(R0402-0201)'                 | '17.8K'   | '1%'    | '1/16W'  | 'IO'       | '17.8Kohm 0402'                                    | 'CHIP0402'     | ''          | ''            | ''        
 '4.53K'      | '1%'      | '1/16W'  | '0402LF'  | 'CHIP'   | 'TMP_QCS24532FB08'(!)   = 'End of Design' | 'Comp-Approve'     | 'CS24532FB08'           |'R0402'| '(R0402-0201)'                 | '4.53K'   | '1%'    | '1/16W'  | 'DISCRETE' | '4.53Kohm 0402'                                    | 'CHIP0402'     | ''          | ''            | ''        
 '4.53K'      | '1%'      | '1/16W'  | '0402LF'  | 'EMPTY'  | 'TMP_QCS24532FB08'(!)   = 'End of Design' | 'Comp-Approve'     | 'CS24532FB08'           |'R0402'| '(R0402-0201)'                 | '4.53K'   | '1%'    | '1/16W'  | 'IO'       | '4.53Kohm 0402'                                    | 'CHIP0402'     | ''          | ''            | ''        
 '715'        | '1%'      | '1/16W'  | '0402LF'  | 'CHIP'   | 'TMP_QCS17152FB17'(!)   = 'End of Design' | 'Comp-Approve'     | 'CS17152FB17'           |'R0402'| '(R0402-0201)'                 | '715'     | '1%'    | '1/16W'  | 'DISCRETE' | '715ohm 0402'                                      | 'CHIP0402'     | ''          | ''            | ''        
 '715'        | '1%'      | '1/16W'  | '0402LF'  | 'EMPTY'  | 'TMP_QCS17152FB17'(!)   = 'End of Design' | 'Comp-Approve'     | 'CS17152FB17'           |'R0402'| '(R0402-0201)'                 | '715'     | '1%'    | '1/16W'  | 'IO'       | '715ohm 0402'                                      | 'CHIP0402'     | ''          | ''            | ''        
 '1.15K'      | '1%'      | '1/16W'  | '0402LF'  | 'CHIP'   | 'TMP_QCS21152FB12'(!)   = 'End of Design' | 'Comp-Approve'     | 'CS21152FB12'           |'R0402'| '(R0402-0201)'                 | '1.15K'   | '1%'    | '1/16W'  | 'DISCRETE' | '1.15Kohm 0402'                                    | 'CHIP0402'     | ''          | ''            | ''        
 '1.15K'      | '1%'      | '1/16W'  | '0402LF'  | 'EMPTY'  | 'TMP_QCS21152FB12'(!)   = 'End of Design' | 'Comp-Approve'     | 'CS21152FB12'           |'R0402'| '(R0402-0201)'                 | '1.15K'   | '1%'    | '1/16W'  | 'IO'       | '1.15Kohm 0402'                                    | 'CHIP0402'     | ''          | ''            | ''        
 '68.1'       | '1%'      | '1/4W'   | '1206LF'  | 'CHIP'   | 'TMP_QCS06816F200'(!)   = ''              | ''                 | 'CS06816F200'           |'R1206'| '(SMR1206AW)'                  | '68.1'    | '1%'    | '1/4W'   | 'DISCRETE' | '68.1ohm 1206'                                     | 'CHIP1206'     | ''          | ''            | ''        
 '68.1'       | '1%'      | '1/4W'   | '1206LF'  | 'EMPTY'  | 'TMP_QCS06816F200'(!)   = ''              | ''                 | 'CS06816F200'           |'R1206'| '(SMR1206AW)'                  | '68.1'    | '1%'    | '1/4W'   | 'IO'       | '68.1ohm 1206'                                     | 'CHIP1206'     | ''          | ''            | ''        
 '549'        | '1%'      | '1/4W'   | '1206LF'  | 'CHIP'   | 'TMP_QCS15496F200'(!)   = ''              | ''                 | 'CS15496F200'           |'R1206'| '(SMR1206AW)'                  | '549'     | '1%'    | '1/4W'   | 'DISCRETE' | '549ohm 1206'                                      | 'CHIP1206'     | ''          | ''            | ''        
 '549'        | '1%'      | '1/4W'   | '1206LF'  | 'EMPTY'  | 'TMP_QCS15496F200'(!)   = ''              | ''                 | 'CS15496F200'           |'R1206'| '(SMR1206AW)'                  | '549'     | '1%'    | '1/4W'   | 'IO'       | '549ohm 1206'                                      | 'CHIP1206'     | ''          | ''            | ''        
 '649'        | '1%'      | '1/4W'   | '1206LF'  | 'CHIP'   | 'TMP_QCS16496F200'(!)   = ''              | ''                 | 'CS16496F200'           |'R1206'| '(SMR1206AW)'                  | '649'     | '1%'    | '1/4W'   | 'DISCRETE' | '649ohm 1206'                                      | 'CHIP1206'     | ''          | ''            | ''        
 '649'        | '1%'      | '1/4W'   | '1206LF'  | 'EMPTY'  | 'TMP_QCS16496F200'(!)   = ''              | ''                 | 'CS16496F200'           |'R1206'| '(SMR1206AW)'                  | '649'     | '1%'    | '1/4W'   | 'IO'       | '649ohm 1206'                                      | 'CHIP1206'     | ''          | ''            | ''        
 '5.49K'      | '1%'      | '1/4W'   | '1206LF'  | 'CHIP'   | 'TMP_QCS25496F200'(!)   = ''              | ''                 | 'CS25496F200'           |'R1206'| '(SMR1206AW)'                  | '5.49K'   | '1%'    | '1/4W'   | 'DISCRETE' | '5.49Kohm 1206'                                    | 'CHIP1206'     | ''          | ''            | ''        
 '5.49K'      | '1%'      | '1/4W'   | '1206LF'  | 'EMPTY'  | 'TMP_QCS25496F200'(!)   = ''              | ''                 | 'CS25496F200'           |'R1206'| '(SMR1206AW)'                  | '5.49K'   | '1%'    | '1/4W'   | 'IO'       | '5.49Kohm 1206'                                    | 'CHIP1206'     | ''          | ''            | ''        
 '6.04K'      | '1%'      | '1/4W'   | '1206LF'  | 'CHIP'   | 'TMP_QCS26046F200'(!)   = ''              | ''                 | 'CS26046F200'           |'R1206'| '(SMR1206AW)'                  | '6.04K'   | '1%'    | '1/4W'   | 'DISCRETE' | '6.04Kohm 1206'                                    | 'CHIP1206'     | ''          | ''            | ''        
 '6.04K'      | '1%'      | '1/4W'   | '1206LF'  | 'EMPTY'  | 'TMP_QCS26046F200'(!)   = ''              | ''                 | 'CS26046F200'           |'R1206'| '(SMR1206AW)'                  | '6.04K'   | '1%'    | '1/4W'   | 'IO'       | '6.04Kohm 1206'                                    | 'CHIP1206'     | ''          | ''            | ''        
 '9.53K'      | '1%'      | '1/4W'   | '1206LF'  | 'CHIP'   | 'TMP_QCS29536F200'(!)   = ''              | ''                 | 'CS29536F200'           |'R1206'| '(SMR1206AW)'                  | '9.53K'   | '1%'    | '1/4W'   | 'DISCRETE' | '9.53Kohm 1206'                                    | 'CHIP1206'     | ''          | ''            | ''        
 '9.53K'      | '1%'      | '1/4W'   | '1206LF'  | 'EMPTY'  | 'TMP_QCS29536F200'(!)   = ''              | ''                 | 'CS29536F200'           |'R1206'| '(SMR1206AW)'                  | '9.53K'   | '1%'    | '1/4W'   | 'IO'       | '9.53Kohm 1206'                                    | 'CHIP1206'     | ''          | ''            | ''        
 '63.4K'      | '1%'      | '1/4W'   | '1206LF'  | 'CHIP'   | 'TMP_QCS36346F200'(!)   = ''              | ''                 | 'CS36346F200'           |'R1206'| '(SMR1206AW)'                  | '63.4K'   | '1%'    | '1/4W'   | 'DISCRETE' | '63.4Kohm 1206'                                    | 'CHIP1206'     | ''          | ''            | ''        
 '63.4K'      | '1%'      | '1/4W'   | '1206LF'  | 'EMPTY'  | 'TMP_QCS36346F200'(!)   = ''              | ''                 | 'CS36346F200'           |'R1206'| '(SMR1206AW)'                  | '63.4K'   | '1%'    | '1/4W'   | 'IO'       | '63.4Kohm 1206'                                    | 'CHIP1206'     | ''          | ''            | ''        
 '0.015'      | '1%'      | '1/4W'   | '1206LF'  | 'CHIP'   | 'TMP_QCS+0156F200'(!)   = ''              | ''                 | 'CS+0156F200'           |'R1206'| '(SMR1206AW)'                  | '0.015'   | '1%'    | '1/4W'   | 'DISCRETE' | '0.015ohm 1206'                                    | 'CHIP1206'     | ''          | ''            | ''        
 '0.015'      | '1%'      | '1/4W'   | '1206LF'  | 'EMPTY'  | 'TMP_QCS+0156F200'(!)   = ''              | ''                 | 'CS+0156F200'           |'R1206'| '(SMR1206AW)'                  | '0.015'   | '1%'    | '1/4W'   | 'IO'       | '0.015ohm 1206'                                    | 'CHIP1206'     | ''          | ''            | ''        
 '0.025'      | '1%'      | '1/4W'   | '1206LF'  | 'CHIP'   | 'TMP_QCS+0256F200'(!)   = ''              | ''                 | 'CS+0256F200'           |'R1206'| '(SMR1206AW)'                  | '0.025'   | '1%'    | '1/4W'   | 'DISCRETE' | '0.025ohm 1206'                                    | 'CHIP1206'     | ''          | ''            | ''        
 '0.025'      | '1%'      | '1/4W'   | '1206LF'  | 'EMPTY'  | 'TMP_QCS+0256F200'(!)   = ''              | ''                 | 'CS+0256F200'           |'R1206'| '(SMR1206AW)'                  | '0.025'   | '1%'    | '1/4W'   | 'IO'       | '0.025ohm 1206'                                    | 'CHIP1206'     | ''          | ''            | ''        
 '5.11'       | '1%'      | '1/4W'   | '1206LF'  | 'CHIP'   | 'TMP_QCS-5116F208'(!)   = ''              | ''                 | 'CS-5116F208'           |'R1206'| '(SMR1206AW)'                  | '5.11'    | '1%'    | '1/4W'   | 'DISCRETE' | '5.11ohm 1206'                                     | 'CHIP1206'     | ''          | ''            | ''        
 '5.11'       | '1%'      | '1/4W'   | '1206LF'  | 'EMPTY'  | 'TMP_QCS-5116F208'(!)   = ''              | ''                 | 'CS-5116F208'           |'R1206'| '(SMR1206AW)'                  | '5.11'    | '1%'    | '1/4W'   | 'IO'       | '5.115ohm 1206'                                    | 'CHIP1206'     | ''          | ''            | ''        
 '22'         | '5%'      | '1/4W'   | '1206LF'  | 'CHIP'   | 'TMP_QCS02206J216'(!)   = 'End of Design' | 'Comp-Release Qty' | 'CS02206J216'           |'R1206'| '(SMR1206AW)'                  | '22'      | '5%'    | '1/4W'   | 'DISCRETE' | '22ohm 1206'                                       | 'CHIP1206'     | ''          | ''            | ''        
 '22'         | '5%'      | '1/4W'   | '1206LF'  | 'EMPTY'  | 'TMP_QCS02206J216'(!)   = 'End of Design' | 'Comp-Release Qty' | 'CS02206J216'           |'R1206'| '(SMR1206AW)'                  | '22'      | '5%'    | '1/4W'   | 'IO'       | '22ohm 1206'                                       | 'CHIP1206'     | ''          | ''            | ''        
 '53.6'       | '1%'      | '1/8W'   | '1206LF'  | 'CHIP'   | 'TMP_QCS05364FA07'(!)   = ''              | ''                 | 'CS05364FA07'           |'R1206'| '(SMR1206AW)'                  | '53.6'    | '1%'    | '1/8W'   | 'DISCRETE' | '53.6ohm 1206'                                     | 'CHIP1206'     | ''          | ''            | ''        
 '53.6'       | '1%'      | '1/8W'   | '1206LF'  | 'EMPTY'  | 'TMP_QCS05364FA07'(!)   = ''              | ''                 | 'CS05364FA07'           |'R1206'| '(SMR1206AW)'                  | '53.6'    | '1%'    | '1/8W'   | 'IO'       | '53.6ohm 1206'                                     | 'CHIP1206'     | ''          | ''            | ''        
 '2.49K'      | '1%'      | '1/8W'   | '0805LF'  | 'CHIP'   | 'TMP_QCS22494FA00'(!)   = ''              | ''                 | 'CS22494FA00'           |'R0805'| '(SMR0805AW)'                  | '2.49K'   | '1%'    | '1/8W'   | 'DISCRETE' | '2.49Kohm 0805'                                    | 'CHIP0805'     | ''          | ''            | ''        
 '2.49K'      | '1%'      | '1/8W'   | '0805LF'  | 'EMPTY'  | 'TMP_QCS22494FA00'(!)   = ''              | ''                 | 'CS22494FA00'           |'R0805'| '(SMR0805AW)'                  | '2.49K'   | '1%'    | '1/8W'   | 'IO'       | '2.49Kohm 0805'                                    | 'CHIP0805'     | ''          | ''            | ''        
 '174'        | '1%'      | '1/4W'   | '1206LF'  | 'CHIP'   | 'TMP_QCS11746F200'(!)   = ''              | ''                 | 'CS11746F200'           |'R1206'| '(SMR1206AW)'                  | '174'     | '1%'    | '1/4W'   | 'DISCRETE' | '174ohm 1206'                                      | 'CHIP1206'     | ''          | ''            | ''        
 '174'        | '1%'      | '1/4W'   | '1206LF'  | 'EMPTY'  | 'TMP_QCS11746F200'(!)   = ''              | ''                 | 'CS11746F200'           |'R1206'| '(SMR1206AW)'                  | '174'     | '1%'    | '1/4W'   | 'IO'       | '174ohm 1206'                                      | 'CHIP1206'     | ''          | ''            | ''        
 '3.16K'      | '1%'      | '1/4W'   | '1206LF'  | 'CHIP'   | 'TMP_QCS23166F200'(!)   = ''              | ''                 | 'CS23166F200'           |'R1206'| '(SMR1206AW)'                  | '3.16K'   | '1%'    | '1/4W'   | 'DISCRETE' | '3.16Kohm 1206'                                    | 'CHIP1206'     | ''          | ''            | ''        
 '3.16K'      | '1%'      | '1/4W'   | '1206LF'  | 'EMPTY'  | 'TMP_QCS23166F200'(!)   = ''              | ''                 | 'CS23166F200'           |'R1206'| '(SMR1206AW)'                  | '3.16K'   | '1%'    | '1/4W'   | 'IO'       | '3.16Kohm 1206'                                    | 'CHIP1206'     | ''          | ''            | ''        
 '3.83K'      | '1%'      | '1/4W'   | '1206LF'  | 'CHIP'   | 'TMP_QCS23836F200'(!)   = ''              | ''                 | 'CS23836F200'           |'R1206'| '(SMR1206AW)'                  | '3.83K'   | '1%'    | '1/4W'   | 'DISCRETE' | '3.83Kohm 1206'                                    | 'CHIP1206'     | ''          | ''            | ''        
 '3.83K'      | '1%'      | '1/4W'   | '1206LF'  | 'EMPTY'  | 'TMP_QCS23836F200'(!)   = ''              | ''                 | 'CS23836F200'           |'R1206'| '(SMR1206AW)'                  | '3.83K'   | '1%'    | '1/4W'   | 'IO'       | '3.83Kohm 1206'                                    | 'CHIP1206'     | ''          | ''            | ''        
 '15.4K'      | '1%'      | '1/4W'   | '1206LF'  | 'CHIP'   | 'TMP_QCS31546F200'(!)   = ''              | ''                 | 'CS31546F200'           |'R1206'| '(SMR1206AW)'                  | '15.4K'   | '1%'    | '1/4W'   | 'DISCRETE' | '15.4Kohm 1206'                                    | 'CHIP1206'     | ''          | ''            | ''        
 '15.4K'      | '1%'      | '1/4W'   | '1206LF'  | 'EMPTY'  | 'TMP_QCS31546F200'(!)   = ''              | ''                 | 'CS31546F200'           |'R1206'| '(SMR1206AW)'                  | '15.4K'   | '1%'    | '1/4W'   | 'IO'       | '15.4Kohm 1206'                                    | 'CHIP1206'     | ''          | ''            | ''        
 '20K'        | '1%'      | '1/4W'   | '1206LF'  | 'CHIP'   | 'TMP_QCS32006F200'(!)   = ''              | ''                 | 'CS32006F200'           |'R1206'| '(SMR1206AW)'                  | '20K'     | '1%'    | '1/4W'   | 'DISCRETE' | '20Kohm 1206'                                      | 'CHIP1206'     | ''          | ''            | ''        
 '20K'        | '1%'      | '1/4W'   | '1206LF'  | 'EMPTY'  | 'TMP_QCS32006F200'(!)   = ''              | ''                 | 'CS32006F200'           |'R1206'| '(SMR1206AW)'                  | '20K'     | '1%'    | '1/4W'   | 'IO'       | '20Kohm 1206'                                      | 'CHIP1206'     | ''          | ''            | ''        
 '22.1K'      | '1%'      | '1/4W'   | '1206LF'  | 'CHIP'   | 'TMP_QCS32216F200'(!)   = ''              | ''                 | 'CS32216F200'           |'R1206'| '(SMR1206AW)'                  | '22.1K'   | '1%'    | '1/4W'   | 'DISCRETE' | '22.1Kohm 1206'                                    | 'CHIP1206'     | ''          | ''            | ''        
 '22.1K'      | '1%'      | '1/4W'   | '1206LF'  | 'EMPTY'  | 'TMP_QCS32216F200'(!)   = ''              | ''                 | 'CS32216F200'           |'R1206'| '(SMR1206AW)'                  | '22.1K'   | '1%'    | '1/4W'   | 'IO'       | '22.1Kohm 1206'                                    | 'CHIP1206'     | ''          | ''            | ''        
 '1.5M'       | '1%'      | '1/4W'   | '1206LF'  | 'CHIP'   | 'TMP_QCS51506F200'(!)   = ''              | ''                 | 'CS51506F200'           |'R1206'| '(SMR1206AW)'                  | '1.5M'    | '1%'    | '1/4W'   | 'DISCRETE' | '1.5Mohm 1206'                                     | 'CHIP1206'     | ''          | ''            | ''        
 '1.5M'       | '1%'      | '1/4W'   | '1206LF'  | 'EMPTY'  | 'TMP_QCS51506F200'(!)   = ''              | ''                 | 'CS51506F200'           |'R1206'| '(SMR1206AW)'                  | '1.5M'    | '1%'    | '1/4W'   | 'IO'       | '1.5Mohm 1206'                                     | 'CHIP1206'     | ''          | ''            | ''        
 '60.4'       | '1%'      | '1/4W'   | '1206LF'  | 'CHIP'   | 'TMP_QCS06046F200'(!)   = ''              | ''                 | 'CS06046F200'           |'R1206'| '(SMR1206AW)'                  | '60.4'    | '1%'    | '1/4W'   | 'DISCRETE' | '60.4ohm 1206'                                     | 'CHIP1206'     | ''          | ''            | ''        
 '60.4'       | '1%'      | '1/4W'   | '1206LF'  | 'EMPTY'  | 'TMP_QCS06046F200'(!)   = ''              | ''                 | 'CS06046F200'           |'R1206'| '(SMR1206AW)'                  | '60.4'    | '1%'    | '1/4W'   | 'IO'       | '60.4ohm 1206'                                     | 'CHIP1206'     | ''          | ''            | ''        
 '787'        | '1%'      | '1/4W'   | '1206LF'  | 'CHIP'   | 'TMP_QCS17876F200'(!)   = ''              | ''                 | 'CS17876F200'           |'R1206'| '(SMR1206AW)'                  | '787'     | '1%'    | '1/4W'   | 'DISCRETE' | '787ohm 1206'                                      | 'CHIP1206'     | ''          | ''            | ''        
 '787'        | '1%'      | '1/4W'   | '1206LF'  | 'EMPTY'  | 'TMP_QCS17876F200'(!)   = ''              | ''                 | 'CS17876F200'           |'R1206'| '(SMR1206AW)'                  | '787'     | '1%'    | '1/4W'   | 'IO'       | '787ohm 1206'                                      | 'CHIP1206'     | ''          | ''            | ''        
 '953'        | '1%'      | '1/4W'   | '1206LF'  | 'CHIP'   | 'TMP_QCS19536F200'(!)   = ''              | ''                 | 'CS19536F200'           |'R1206'| '(SMR1206AW)'                  | '953'     | '1%'    | '1/4W'   | 'DISCRETE' | '953ohm 1206'                                      | 'CHIP1206'     | ''          | ''            | ''        
 '953'        | '1%'      | '1/4W'   | '1206LF'  | 'EMPTY'  | 'TMP_QCS19536F200'(!)   = ''              | ''                 | 'CS19536F200'           |'R1206'| '(SMR1206AW)'                  | '953'     | '1%'    | '1/4W'   | 'IO'       | '953ohm 1206'                                      | 'CHIP1206'     | ''          | ''            | ''        
 '1.3K'       | '1%'      | '1/4W'   | '1206LF'  | 'CHIP'   | 'TMP_QCS21306F200'(!)   = ''              | ''                 | 'CS21306F200'           |'R1206'| '(SMR1206AW)'                  | '1.3K'    | '1%'    | '1/4W'   | 'DISCRETE' | '1.3Kohm 1206'                                     | 'CHIP1206'     | ''          | ''            | ''        
 '1.3K'       | '1%'      | '1/4W'   | '1206LF'  | 'EMPTY'  | 'TMP_QCS21306F200'(!)   = ''              | ''                 | 'CS21306F200'           |'R1206'| '(SMR1206AW)'                  | '1.3K'    | '1%'    | '1/4W'   | 'IO'       | '1.3Kohm 1206'                                     | 'CHIP1206'     | ''          | ''            | ''        
 '1.82K'      | '1%'      | '1/4W'   | '1206LF'  | 'CHIP'   | 'TMP_QCS21826F200'(!)   = ''              | ''                 | 'CS21826F200'           |'R1206'| '(SMR1206AW)'                  | '1.82K'   | '1%'    | '1/4W'   | 'DISCRETE' | '1.82Kohm 1206'                                    | 'CHIP1206'     | ''          | ''            | ''        
 '1.82K'      | '1%'      | '1/4W'   | '1206LF'  | 'EMPTY'  | 'TMP_QCS21826F200'(!)   = ''              | ''                 | 'CS21826F200'           |'R1206'| '(SMR1206AW)'                  | '1.82K'   | '1%'    | '1/4W'   | 'IO'       | '1.82Kohm 1206'                                    | 'CHIP1206'     | ''          | ''            | ''        
 '4.7K'       | '1%'      | '1/4W'   | '1206LF'  | 'CHIP'   | 'TMP_QCS24706F200'(!)   = 'End of Design' | 'Comp-Approve'     | 'CS24706F200'           |'R1206'| '(SMR1206AW)'                  | '4.7K'    | '1%'    | '1/4W'   | 'DISCRETE' | '4.7Kohm 1206'                                     | 'CHIP1206'     | ''          | ''            | ''        
 '4.7K'       | '1%'      | '1/4W'   | '1206LF'  | 'EMPTY'  | 'TMP_QCS24706F200'(!)   = 'End of Design' | 'Comp-Approve'     | 'CS24706F200'           |'R1206'| '(SMR1206AW)'                  | '4.7K'    | '1%'    | '1/4W'   | 'IO'       | '4.7Kohm 1206'                                     | 'CHIP1206'     | ''          | ''            | ''        
 '17.4K'      | '1%'      | '1/4W'   | '1206LF'  | 'CHIP'   | 'TMP_QCS31746F200'(!)   = 'End of Design' | 'Comp-Approve'     | 'CS24706F200'           |'R1206'| '(SMR1206AW)'                  | '17.4K'   | '1%'    | '1/4W'   | 'DISCRETE' | '17.4Kohm 1206'                                    | 'CHIP1206'     | ''          | ''            | ''        
 '17.4K'      | '1%'      | '1/4W'   | '1206LF'  | 'EMPTY'  | 'TMP_QCS31746F200'(!)   = 'End of Design' | 'Comp-Approve'     | 'CS24706F200'           |'R1206'| '(SMR1206AW)'                  | '17.4K'   | '1%'    | '1/4W'   | 'IO'       | '17.4Kohm 1206'                                    | 'CHIP1206'     | ''          | ''            | ''        
 '130K'       | '1%'      | '1/10W'  | '0603LF'  | 'CHIP'   | 'TMP_QCS41303F917'(!)   = ''              | ''                 | 'CS41303F917'           |'R0603'| '(SMR0603AW)'                  | '130K'    | '1%'    | '1/10W'  | 'DISCRETE' | '130Kohm 0603'                                     | 'CHIP0603'     | ''          | ''            | ''        
 '130K'       | '1%'      | '1/10W'  | '0603LF'  | 'EMPTY'  | 'TMP_QCS41303F917'(!)   = ''              | ''                 | 'CS41303F917'           |'R0603'| '(SMR0603AW)'                  | '130K'    | '1%'    | '1/10W'  | 'IO'       | '130Kohm 0603'                                     | 'CHIP0603'     | ''          | ''            | ''        
 '12K'        | '1%'      | '1/16W'  | '0402LF'  | 'CHIP'   | 'TMP_QCS31202FB15'(!)   = 'End of Design' | 'Comp-Approve'     | 'CS31202FB15'           |'R0402'| '(R0402-0201)'                 | '12K'     | '1%'    | '1/16W'  | 'DISCRETE' | '12Kohm 0402'                                      | 'CHIP0402'     | ''          | ''            | ''        
 '12K'        | '1%'      | '1/16W'  | '0402LF'  | 'EMPTY'  | 'TMP_QCS31202FB15'(!)   = 'End of Design' | 'Comp-Approve'     | 'CS31202FB15'           |'R0402'| '(R0402-0201)'                 | '12K'     | '1%'    | '1/16W'  | 'IO'       | '12Kohm 0402'                                      | 'CHIP0402'     | ''          | ''            | ''        
 '68.1K'      | '1%'      | '1/4W'   | '1206LF'  | 'CHIP'   | 'TMP_QCS36816F200'(!)   = ''              | ''                 | 'CS36816F200'           |'R1206'| '(SMR1206AW)'                  | '68.1K'   | '1%'    | '1/4W'   | 'DISCRETE' | '68.1Kohm 1206'                                    | 'CHIP1206'     | ''          | ''            | ''        
 '68.1K'      | '1%'      | '1/4W'   | '1206LF'  | 'EMPTY'  | 'TMP_QCS36816F200'(!)   = ''              | ''                 | 'CS36816F200'           |'R1206'| '(SMR1206AW)'                  | '68.1K'   | '1%'    | '1/4W'   | 'IO'       | '68.1Kohm 1206'                                    | 'CHIP1206'     | ''          | ''            | ''        
 '1'          | '5%'      | '1/10W'  | '0603LF'  | 'CHIP'   | 'TMP_QCS-1003J913'(!)   = ''              | ''                 | 'CS-1003J913'           |'R0603'| '(SMR0603AW)'                  | '1'       | '5%'    | '1/10W'  | 'DISCRETE' | '1ohm 0603'                                        | 'CHIP0603'     | ''          | ''            | ''        
 '1'          | '5%'      | '1/10W'  | '0603LF'  | 'EMPTY'  | 'TMP_QCS-1003J913'(!)   = ''              | ''                 | 'CS-1003J913'           |'R0603'| '(SMR0603AW)'                  | '1'       | '5%'    | '1/10W'  | 'IO'       | '1ohm 0603'                                        | 'CHIP0603'     | ''          | ''            | ''        
 '10K'        | '1%'      | '1/4W'   | '1206LF'  | 'CHIP'   | 'TMP_QCS31006F200'(!)   = ''              | ''                 | 'CS31006F200'           |'R1206'| '(SMR1206AW)'                  | '10K'     | '1%'    | '1/4W'   | 'DISCRETE' | '10Kohm 1206'                                      | 'CHIP1206'     | ''          | ''            | ''        
 '10K'        | '1%'      | '1/4W'   | '1206LF'  | 'EMPTY'  | 'TMP_QCS31006F200'(!)   = ''              | ''                 | 'CS31006F200'           |'R1206'| '(SMR1206AW)'                  | '10K'     | '1%'    | '1/4W'   | 'IO'       | '10Kohm 1206'                                      | 'CHIP1206'     | ''          | ''            | ''        
 '8.66K'      | '1%'      | '1/4W'   | '1206LF'  | 'CHIP'   | 'TMP_QCS28666F200'(!)   = ''              | ''                 | 'CS28666F200'           |'R1206'| '(SMR1206AW)'                  | '8.66K'   | '1%'    | '1/4W'   | 'DISCRETE' | '8.66Kohm 1206'                                    | 'CHIP1206'     | ''          | ''            | ''        
 '8.66K'      | '1%'      | '1/4W'   | '1206LF'  | 'EMPTY'  | 'TMP_QCS28666F200'(!)   = ''              | ''                 | 'CS28666F200'           |'R1206'| '(SMR1206AW)'                  | '8.66K'   | '1%'    | '1/4W'   | 'IO'       | '8.66Kohm 1206'                                    | 'CHIP1206'     | ''          | ''            | ''        
 '7.15K'      | '1%'      | '1/4W'   | '1206LF'  | 'CHIP'   | 'TMP_QCS27156F200'(!)   = ''              | ''                 | 'CS27156F200'           |'R1206'| '(SMR1206AW)'                  | '7.15K'   | '1%'    | '1/4W'   | 'DISCRETE' | '7.15Kohm 1206'                                    | 'CHIP1206'     | ''          | ''            | ''        
 '7.15K'      | '1%'      | '1/4W'   | '1206LF'  | 'EMPTY'  | 'TMP_QCS27156F200'(!)   = ''              | ''                 | 'CS27156F200'           |'R1206'| '(SMR1206AW)'                  | '7.15K'   | '1%'    | '1/4W'   | 'IO'       | '7.15Kohm 1206'                                    | 'CHIP1206'     | ''          | ''            | ''        
 '2.15K'      | '1%'      | '1/4W'   | '1206LF'  | 'CHIP'   | 'TMP_QCS22156F200'(!)   = ''              | ''                 | 'CS22156F200'           |'R1206'| '(SMR1206AW)'                  | '2.15K'   | '1%'    | '1/4W'   | 'DISCRETE' | '2.15Kohm 1206'                                    | 'CHIP1206'     | ''          | ''            | ''        
 '2.15K'      | '1%'      | '1/4W'   | '1206LF'  | 'EMPTY'  | 'TMP_QCS22156F200'(!)   = ''              | ''                 | 'CS22156F200'           |'R1206'| '(SMR1206AW)'                  | '2.15K'   | '1%'    | '1/4W'   | 'IO'       | '2.15Kohm 1206'                                    | 'CHIP1206'     | ''          | ''            | ''        
 '4.32K'      | '1%'      | '1/4W'   | '1206LF'  | 'CHIP'   | 'TMP_QCS24326F200'(!)   = ''              | ''                 | 'CS24326F200'           |'R1206'| '(SMR1206AW)'                  | '4.32K'   | '1%'    | '1/4W'   | 'DISCRETE' | '4.32Kohm 1206'                                    | 'CHIP1206'     | ''          | ''            | ''        
 '4.32K'      | '1%'      | '1/4W'   | '1206LF'  | 'EMPTY'  | 'TMP_QCS24326F200'(!)   = ''              | ''                 | 'CS24326F200'           |'R1206'| '(SMR1206AW)'                  | '4.32K'   | '1%'    | '1/4W'   | 'IO'       | '4.32Kohm 1206'                                    | 'CHIP1206'     | ''          | ''            | ''        
 '5.9K'       | '1%'      | '1/4W'   | '1206LF'  | 'CHIP'   | 'TMP_QCS25906F200'(!)   = ''              | ''                 | 'CS25906F200'           |'R1206'| '(SMR1206AW)'                  | '5.9K'    | '1%'    | '1/4W'   | 'DISCRETE' | '5.9Kohm 1206'                                     | 'CHIP1206'     | ''          | ''            | ''        
 '5.9K'       | '1%'      | '1/4W'   | '1206LF'  | 'EMPTY'  | 'TMP_QCS25906F200'(!)   = ''              | ''                 | 'CS25906F200'           |'R1206'| '(SMR1206AW)'                  | '5.9K'    | '1%'    | '1/4W'   | 'IO'       | '5.9Kohm 1206'                                     | 'CHIP1206'     | ''          | ''            | ''        
 '243'        | '1%'      | '1/4W'   | '1206LF'  | 'CHIP'   | 'TMP_QCS12436F200'(!)   = ''              | ''                 | 'CS12436F200'           |'R1206'| '(SMR1206AW)'                  | '243'     | '1%'    | '1/4W'   | 'DISCRETE' | '243ohm 1206'                                      | 'CHIP1206'     | ''          | ''            | ''        
 '243'        | '1%'      | '1/4W'   | '1206LF'  | 'EMPTY'  | 'TMP_QCS12436F200'(!)   = ''              | ''                 | 'CS12436F200'           |'R1206'| '(SMR1206AW)'                  | '243'     | '1%'    | '1/4W'   | 'IO'       | '243ohm 1206'                                      | 'CHIP1206'     | ''          | ''            | ''        
 '0.020'      | '1%'      | '2W'     | '2512LF'  | 'CHIP'   | 'TMP_QCS+020AFR00'(!)   = ''              | ''                 | 'CS+020AFR00'           |'R2512'| '(SMR2512AW)'                  | '0.020'   | '1%'    | '2W'     | 'DISCRETE' | '0.020ohm 2512'                                    | 'CHIP2512'     | ''          | ''            | ''        
 '0.020'      | '1%'      | '2W'     | '2512LF'  | 'EMPTY'  | 'TMP_QCS+020AFR00'(!)   = ''              | ''                 | 'CS+020AFR00'           |'R2512'| '(SMR2512AW)'                  | '0.020'   | '1%'    | '2W'     | 'IO'       | '0.020ohm 2512'                                    | 'CHIP2512'     | ''          | ''            | ''        
 '8.2K'       | '1%'      | '1/4W'   | '1206LF'  | 'CHIP'   | 'TMP-C_T2I_0912_ALEX_2'(!) = ''              | ''                 | 'TMP-C_T2I_0912_ALEX_2' |'R1206'| '(SMR1206AW)'                  | '8.2K'    | '1%'    | '1/4W'   | 'DISCRETE' | '8.2Kohm 1206'                                     | 'CHIP1206'     | ''          | ''            | ''        
 '8.2K'       | '1%'      | '1/4W'   | '1206LF'  | 'EMPTY'  | 'TMP-C_T2I_0912_ALEX_2'(!) = ''              | ''                 | 'TMP-C_T2I_0912_ALEX_2' |'R1206'| '(SMR1206AW)'                  | '8.2K'    | '1%'    | '1/4W'   | 'IO'       | '8.2Kohm 1206'                                     | 'CHIP1206'     | ''          | ''            | ''        
 '48.7k'      | '1%'      | '1/4W'   | '1206LF'  | 'CHIP'   | 'TMP-C_T2I_0912_ALEX_3'(!) = ''              | ''                 | 'TMP-C_T2I_0912_ALEX_3' |'R1206'| '(SMR1206AW)'                  | '48.7k'   | '1%'    | '1/4W'   | 'DISCRETE' | '48.7kohm 1206'                                    | 'CHIP1206'     | ''          | ''            | ''        
 '48.7k'      | '1%'      | '1/4W'   | '1206LF'  | 'EMPTY'  | 'TMP-C_T2I_0912_ALEX_3'(!) = ''              | ''                 | 'TMP-C_T2I_0912_ALEX_3' |'R1206'| '(SMR1206AW)'                  | '48.7k'   | '1%'    | '1/4W'   | 'IO'       | '48.7kohm 1206'                                    | 'CHIP1206'     | ''          | ''            | ''        
 '3.4K'       | '1%'      | '1/4W'   | '1206LF'  | 'CHIP'   | 'TMP-C_T2I_0912_ALEX_4'(!) = ''              | ''                 | 'TMP-C_T2I_0912_ALEX_4' |'R1206'| '(SMR1206AW)'                  | '3.4K'    | '1%'    | '1/4W'   | 'DISCRETE' | '3.4Kohm 1206'                                     | 'CHIP1206'     | ''          | ''            | ''        
 '3.4K'       | '1%'      | '1/4W'   | '1206LF'  | 'EMPTY'  | 'TMP-C_T2I_0912_ALEX_4'(!) = ''              | ''                 | 'TMP-C_T2I_0912_ALEX_4' |'R1206'| '(SMR1206AW)'                  | '3.4K'    | '1%'    | '1/4W'   | 'IO'       | '3.4Kohm 1206'                                     | 'CHIP1206'     | ''          | ''            | ''        
 '3.3K'       | '1%'      | '1/4W'   | '1206LF'  | 'CHIP'   | 'TMP-C_T2I_0912_ALEX_5'(!) = ''              | ''                 | 'TMP-C_T2I_0912_ALEX_5' |'R1206'| '(SMR1206AW)'                  | '3.3K'    | '1%'    | '1/4W'   | 'DISCRETE' | '3.3Kohm 1206'                                     | 'CHIP1206'     | ''          | ''            | ''        
 '3.3K'       | '1%'      | '1/4W'   | '1206LF'  | 'EMPTY'  | 'TMP-C_T2I_0912_ALEX_5'(!) = ''              | ''                 | 'TMP-C_T2I_0912_ALEX_5' |'R1206'| '(SMR1206AW)'                  | '3.3K'    | '1%'    | '1/4W'   | 'IO'       | '3.3Kohm 1206'                                     | 'CHIP1206'     | ''          | ''            | ''        
 '6.65K'      | '1%'      | '1/4W'   | '1206LF'  | 'CHIP'   | 'TMP-C_T2I_0912_ALEX_6'(!) = ''              | ''                 | 'TMP-C_T2I_0912_ALEX_6' |'R1206'| '(SMR1206AW)'                  | '6.65K'   | '1%'    | '1/4W'   | 'DISCRETE' | '6.65Kohm 1206'                                    | 'CHIP1206'     | ''          | ''            | ''        
 '6.65K'      | '1%'      | '1/4W'   | '1206LF'  | 'EMPTY'  | 'TMP-C_T2I_0912_ALEX_6'(!) = ''              | ''                 | 'TMP-C_T2I_0912_ALEX_6' |'R1206'| '(SMR1206AW)'                  | '6.65K'   | '1%'    | '1/4W'   | 'IO'       | '6.65Kohm 1206'                                    | 'CHIP1206'     | ''          | ''            | ''        
 '2K'         | '1%'      | '1/4W'   | '1206LF'  | 'CHIP'   | 'TMP_QCS22006F200'(!)   = ''              | ''                 | 'CS22006F200'           |'R1206'| '(SMR1206AW)'                  | '2K'      | '1%'    | '1/4W'   | 'DISCRETE' | '2Kohm 1206'                                       | 'CHIP1206'     | ''          | ''            | ''        
 '2K'         | '1%'      | '1/4W'   | '1206LF'  | 'EMPTY'  | 'TMP_QCS22006F200'(!)   = ''              | ''                 | 'CS22006F200'           |'R1206'| '(SMR1206AW)'                  | '2K'      | '1%'    | '1/4W'   | 'IO'       | '2Kohm 1206'                                       | 'CHIP1206'     | ''          | ''            | ''        
 '27'         | '1%'      | '1/4W'   | '1206LF'  | 'CHIP'   | 'TMP_QCS02706F200'(!)   = 'End of Design' | 'Comp-Approve'     | 'CS02706F200'           |'R1206'| '(SMR1206AW)'                  | '27'      | '1%'    | '1/4W'   | 'DISCRETE' | '27ohm 1206'                                       | 'CHIP1206'     | ''          | ''            | ''        
 '27'         | '1%'      | '1/4W'   | '1206LF'  | 'EMPTY'  | 'TMP_QCS02706F200'(!)   = 'End of Design' | 'Comp-Approve'     | 'CS02706F200'           |'R1206'| '(SMR1206AW)'                  | '27'      | '1%'    | '1/4W'   | 'IO'       | '27ohm 1206'                                       | 'CHIP1206'     | ''          | ''            | ''        
 '4.99K'      | '1%'      | '1/4W'   | '1206LF'  | 'CHIP'   | 'TMP_QCS24996F210'(!)   = ''              | ''                 | 'CS24996F210'           |'R1206'| '(SMR1206AW)'                  | '4.99K'   | '1%'    | '1/4W'   | 'DISCRETE' | '4.99Kohm 1206'                                    | 'CHIP1206'     | ''          | ''            | ''        
 '4.99K'      | '1%'      | '1/4W'   | '1206LF'  | 'EMPTY'  | 'TMP_QCS24996F210'(!)   = ''              | ''                 | 'CS24996F210'           |'R1206'| '(SMR1206AW)'                  | '4.99K'   | '1%'    | '1/4W'   | 'IO'       | '4.99Kohm 1206'                                    | 'CHIP1206'     | ''          | ''            | ''        
 '3.24K'      | '1%'      | '1/4W'   | '1206LF'  | 'CHIP'   | 'TMP_QCS23246F200'(!)   = ''              | ''                 | 'CS23246F200'           |'R1206'| '(SMR1206AW)'                  | '3.24K'   | '1%'    | '1/4W'   | 'DISCRETE' | '3.24Kohm 1206'                                    | 'CHIP1206'     | ''          | ''            | ''        
 '3.24K'      | '1%'      | '1/4W'   | '1206LF'  | 'EMPTY'  | 'TMP_QCS23246F200'(!)   = ''              | ''                 | 'CS23246F200'           |'R1206'| '(SMR1206AW)'                  | '3.24K'   | '1%'    | '1/4W'   | 'IO'       | '3.24Kohm 1206'                                    | 'CHIP1206'     | ''          | ''            | ''        
 '301K'       | '1%'      | '1/4W'   | '1206LF'  | 'CHIP'   | 'TMP_QCS43016F200'(!)   = ''              | ''                 | 'CS43016F200'           |'R1206'| '(SMR1206AW)'                  | '301K'    | '1%'    | '1/4W'   | 'DISCRETE' | '301Kohm 1206'                                     | 'CHIP1206'     | ''          | ''            | ''        
 '301K'       | '1%'      | '1/4W'   | '1206LF'  | 'EMPTY'  | 'TMP_QCS43016F200'(!)   = ''              | ''                 | 'CS43016F200'           |'R1206'| '(SMR1206AW)'                  | '301K'    | '1%'    | '1/4W'   | 'IO'       | '301Kohm 1206'                                     | 'CHIP1206'     | ''          | ''            | ''        
 '1K'         | '0.1%'    | '1/8W'   | '1206LF'  | 'CHIP'   | 'TMP_QCS21004B200'(!)   = ''              | ''                 | 'CS21004B200'           |'R1206'| '(SMR1206AW)'                  | '1K'      | '0.1%'  | '1/8W'   | 'DISCRETE' | '1Kohm 1206'                                       | 'CHIP1206'     | ''          | ''            | ''        
 '1K'         | '0.1%'    | '1/8W'   | '1206LF'  | 'EMPTY'  | 'TMP_QCS21004B200'(!)   = ''              | ''                 | 'CS21004B200'           |'R1206'| '(SMR1206AW)'                  | '1K'      | '0.1%'  | '1/8W'   | 'IO'       | '1Kohm 1206'                                       | 'CHIP1206'     | ''          | ''            | ''        
 '2K'         | '0.1%'    | '1/8W'   | '1206LF'  | 'CHIP'   | 'TMP_QCS22004B200'(!)   = ''              | ''                 | 'CS22004B200'           |'R1206'| '(SMR1206AW)'                  | '2K'      | '0.1%'  | '1/8W'   | 'DISCRETE' | '2Kohm 1206'                                       | 'CHIP1206'     | ''          | ''            | ''        
 '2K'         | '0.1%'    | '1/8W'   | '1206LF'  | 'EMPTY'  | 'TMP_QCS22004B200'(!)   = ''              | ''                 | 'CS22004B200'           |'R1206'| '(SMR1206AW)'                  | '2K'      | '0.1%'  | '1/8W'   | 'IO'       | '2Kohm 1206'                                       | 'CHIP1206'     | ''          | ''            | ''        
 '49.9K'      | '1%'      | '1/4W'   | '1206LF'  | 'CHIP'   | 'TMP_QCS34996F200'(!)   = ''              | ''                 | 'CS34996F200'           |'R1206'| '(SMR1206AW)'                  | '49.9K'   | '1%'    | '1/4W'   | 'DISCRETE' | '49.9Kohm 1206'                                    | 'CHIP1206'     | ''          | ''            | ''        
 '49.9K'      | '1%'      | '1/4W'   | '1206LF'  | 'EMPTY'  | 'TMP_QCS34996F200'(!)   = ''              | ''                 | 'CS34996F200'           |'R1206'| '(SMR1206AW)'                  | '49.9K'   | '1%'    | '1/4W'   | 'IO'       | '49.9Kohm 1206'                                    | 'CHIP1206'     | ''          | ''            | ''        
 '100K'       | '1%'      | '1/4W'   | '1206LF'  | 'CHIP'   | 'TMP_QCS41006F200'(!)   = ''              | ''                 | 'CS41006F200'           |'R1206'| '(SMR1206AW)'                  | '100K'    | '1%'    | '1/4W'   | 'DISCRETE' | '100Kohm 1206'                                     | 'CHIP1206'     | ''          | ''            | ''        
 '100K'       | '1%'      | '1/4W'   | '1206LF'  | 'EMPTY'  | 'TMP_QCS41006F200'(!)   = ''              | ''                 | 'CS41006F200'           |'R1206'| '(SMR1206AW)'                  | '100K'    | '1%'    | '1/4W'   | 'IO'       | '100Kohm 1206'                                     | 'CHIP1206'     | ''          | ''            | ''        
 '1.2M'       | '1%'      | '1/4W'   | '1206LF'  | 'CHIP'   | 'TMP_QCS51206F200'(!)   = ''              | ''                 | 'CS51206F200'           |'R1206'| '(SMR1206AW)'                  | '1.2M'    | '1%'    | '1/4W'   | 'DISCRETE' | '1.2Mohm 1206'                                     | 'CHIP1206'     | ''          | ''            | ''        
 '1.2M'       | '1%'      | '1/4W'   | '1206LF'  | 'EMPTY'  | 'TMP_QCS51206F200'(!)   = ''              | ''                 | 'CS51206F200'           |'R1206'| '(SMR1206AW)'                  | '1.2M'    | '1%'    | '1/4W'   | 'IO'       | '1.2Mohm 1206'                                     | 'CHIP1206'     | ''          | ''            | ''        
 '1.54K'      | '0.1%'    | '1/8W'   | '1206LF'  | 'CHIP'   | 'TMP_QCS21544B200'(!)   = ''              | ''                 | 'CS21544B200'           |'R1206'| '(SMR1206AW)'                  | '1.54K'   | '0.1%'  | '1/8W'   | 'DISCRETE' | '1.54Kohm 1206'                                    | 'CHIP1206'     | ''          | ''            | ''        
 '1.54K'      | '0.1%'    | '1/8W'   | '1206LF'  | 'EMPTY'  | 'TMP_QCS21544B200'(!)   = ''              | ''                 | 'CS21544B200'           |'R1206'| '(SMR1206AW)'                  | '1.54K'   | '0.1%'  | '1/8W'   | 'IO'       | '1.54Kohm 1206'                                    | 'CHIP1206'     | ''          | ''            | ''        
 '3.16K'      | '0.1%'    | '1/8W'   | '1206LF'  | 'CHIP'   | 'TMP_QCS23164B200'(!)   = ''              | ''                 | 'CS23164B200'           |'R1206'| '(SMR1206AW)'                  | '3.16K'   | '0.1%'  | '1/8W'   | 'DISCRETE' | '3.16Kohm 1206'                                    | 'CHIP1206'     | ''          | ''            | ''        
 '3.16K'      | '0.1%'    | '1/8W'   | '1206LF'  | 'EMPTY'  | 'TMP_QCS23164B200'(!)   = ''              | ''                 | 'CS23164B200'           |'R1206'| '(SMR1206AW)'                  | '3.16K'   | '0.1%'  | '1/8W'   | 'IO'       | '3.16Kohm 1206'                                    | 'CHIP1206'     | ''          | ''            | ''        
 '10K'        | '0.1%'    | '1/8W'   | '1206LF'  | 'CHIP'   | 'TMP_QCS31004B200'(!)   = ''              | ''                 | 'CS31004B200'           |'R1206'| '(SMR1206AW)'                  | '10K'     | '0.1%'  | '1/8W'   | 'DISCRETE' | '10Kohm 1206'                                      | 'CHIP1206'     | ''          | ''            | ''        
 '10K'        | '0.1%'    | '1/8W'   | '1206LF'  | 'EMPTY'  | 'TMP_QCS31004B200'(!)   = ''              | ''                 | 'CS31004B200'           |'R1206'| '(SMR1206AW)'                  | '10K'     | '0.1%'  | '1/8W'   | 'IO'       | '10Kohm 1206'                                      | 'CHIP1206'     | ''          | ''            | ''        
 '0.5'        | '1%'      | '1W'     | '2512LF'  | 'CHIP'   | 'TMP_QCS+5008FR00'(!)   = ''              | ''                 | 'CS+5008FR00'           |'R2512'| '(SMR2512AW)'                  | '0.5'     | '1%'    | '1W'     | 'DISCRETE' | '0.5ohm 2512'                                      | 'CHIP2512'     | ''          | ''            | ''        
 '0.5'        | '1%'      | '1W'     | '2512LF'  | 'EMPTY'  | 'TMP_QCS+5008FR00'(!)   = ''              | ''                 | 'CS+5008FR00'           |'R2512'| '(SMR2512AW)'                  | '0.5'     | '1%'    | '1W'     | 'IO'       | '0.5ohm 2512'                                      | 'CHIP2512'     | ''          | ''            | ''        
 '255'        | '1%'      | '1/4W'   | '1206LF'  | 'CHIP'   | 'TMP_QCS12556F200'(!)   = ''              | ''                 | 'CS12556F200'           |'R1206'| '(SMR1206AW)'                  | '255'     | '1%'    | '1/4W'   | 'DISCRETE' | '255ohm 1206'                                      | 'CHIP1206'     | ''          | ''            | ''        
 '255'        | '1%'      | '1/4W'   | '1206LF'  | 'EMPTY'  | 'TMP_QCS12556F200'(!)   = ''              | ''                 | 'CS12556F200'           |'R1206'| '(SMR1206AW)'                  | '255'     | '1%'    | '1/4W'   | 'IO'       | '255ohm 1206'                                      | 'CHIP1206'     | ''          | ''            | ''        
 '4.53K'      | '1%'      | '1/4W'   | '1206LF'  | 'CHIP'   | 'TMP_QCS24536F200'(!)   = ''              | ''                 | 'CS24536F200'           |'R1206'| '(SMR1206AW)'                  | '4.53K'   | '1%'    | '1/4W'   | 'DISCRETE' | '4.53Kohm 1206'                                    | 'CHIP1206'     | ''          | ''            | ''        
 '4.53K'      | '1%'      | '1/4W'   | '1206LF'  | 'EMPTY'  | 'TMP_QCS24536F200'(!)   = ''              | ''                 | 'CS24536F200'           |'R1206'| '(SMR1206AW)'                  | '4.53K'   | '1%'    | '1/4W'   | 'IO'       | '4.53Kohm 1206'                                    | 'CHIP1206'     | ''          | ''            | ''        
 '130'        | '1%'      | '1/4W'   | '1206LF'  | 'CHIP'   | 'TMP_QCS11306F200'(!)   = ''              | ''                 | 'CS11306F200'           |'R1206'| '(SMR1206AW)'                  | '130'     | '1%'    | '1/4W'   | 'DISCRETE' | '130ohm 1206'                                      | 'CHIP1206'     | ''          | ''            | ''        
 '130'        | '1%'      | '1/4W'   | '1206LF'  | 'EMPTY'  | 'TMP_QCS11306F200'(!)   = ''              | ''                 | 'CS11306F200'           |'R1206'| '(SMR1206AW)'                  | '130'     | '1%'    | '1/4W'   | 'IO'       | '130ohm 1206'                                      | 'CHIP1206'     | ''          | ''            | ''        
 '261'        | '1%'      | '1/4W'   | '1206LF'  | 'CHIP'   | 'TMP_QCS12616F200'(!)   = ''              | ''                 | 'CS12616F200'           |'R1206'| '(SMR1206AW)'                  | '261'     | '1%'    | '1/4W'   | 'DISCRETE' | '261ohm 1206'                                      | 'CHIP1206'     | ''          | ''            | ''        
 '261'        | '1%'      | '1/4W'   | '1206LF'  | 'EMPTY'  | 'TMP_QCS12616F200'(!)   = ''              | ''                 | 'CS12616F200'           |'R1206'| '(SMR1206AW)'                  | '261'     | '1%'    | '1/4W'   | 'IO'       | '261ohm 1206'                                      | 'CHIP1206'     | ''          | ''            | ''        
 '1K'         | '1%'      | '1/4W'   | '1206LF'  | 'CHIP'   | 'TMP_QCS21006F200'(!)   = ''              | ''                 | 'CS21006F200'           |'R1206'| '(SMR1206AW)'                  | '1K'      | '1%'    | '1/4W'   | 'DISCRETE' | '1Kohm 1206'                                       | 'CHIP1206'     | ''          | ''            | ''        
 '1K'         | '1%'      | '1/4W'   | '1206LF'  | 'EMPTY'  | 'TMP_QCS21006F200'(!)   = ''              | ''                 | 'CS21006F200'           |'R1206'| '(SMR1206AW)'                  | '1K'      | '1%'    | '1/4W'   | 'IO'       | '1Kohm 1206'                                       | 'CHIP1206'     | ''          | ''            | ''        
 '2.2'        | '1%'      | '1/4W'   | '1206LF'  | 'CHIP'   | 'TMP_QCS-2206F200'(!)   = ''              | ''                 | 'CS-2206F200'           |'R1206'| '(SMR1206AW)'                  | '2.2'     | '1%'    | '1/4W'   | 'DISCRETE' | '2.2ohm 1206'                                      | 'CHIP1206'     | ''          | ''            | ''        
 '2.2'        | '1%'      | '1/4W'   | '1206LF'  | 'EMPTY'  | 'TMP_QCS-2206F200'(!)   = ''              | ''                 | 'CS-2206F200'           |'R1206'| '(SMR1206AW)'                  | '2.2'     | '1%'    | '1/4W'   | 'IO'       | '2.2ohm 1206'                                      | 'CHIP1206'     | ''          | ''            | ''        
 '732'        | '1%'      | '1/4W'   | '1206LF'  | 'CHIP'   | 'TMP_QCS17326F200'(!)   = ''              | ''                 | 'CS17326F200'           |'R1206'| '(SMR1206AW)'                  | '732'     | '1%'    | '1/4W'   | 'DISCRETE' | '732ohm 1206'                                      | 'CHIP1206'     | ''          | ''            | ''        
 '732'        | '1%'      | '1/4W'   | '1206LF'  | 'EMPTY'  | 'TMP_QCS17326F200'(!)   = ''              | ''                 | 'CS17326F200'           |'R1206'| '(SMR1206AW)'                  | '732'     | '1%'    | '1/4W'   | 'IO'       | '732ohm 1206'                                      | 'CHIP1206'     | ''          | ''            | ''        
 '143K'       | '1%'      | '1/16W'  | '0402LF'  | 'CHIP'   | 'TMP_QCS41432FB18'(!)   = 'End of Design' | 'Comp-Approve'     | 'CS41432FB18'           |'R0402'| '(R0402-0201)'                 | '143K'    | '1%'    | '1/16W'  | 'DISCRETE' | '143Kohm 0402'                                     | 'CHIP0402'     | ''          | ''            | ''        
 '143K'       | '1%'      | '1/16W'  | '0402LF'  | 'EMPTY'  | 'TMP_QCS41432FB18'(!)   = 'End of Design' | 'Comp-Approve'     | 'CS41432FB18'           |'R0402'| '(R0402-0201)'                 | '143K'    | '1%'    | '1/16W'  | 'IO'       | '143Kohm 0402'                                     | 'CHIP0402'     | ''          | ''            | ''        
 '255'        | '1%'      | '1/2W'   | '1206LF'  | 'CHIP'   | 'TMP_QCS12557F200'(!)   = ''              | ''                 | 'CS12557F200'           |'R1206'| '(SMR1206AW)'                  | '255'     | '1%'    | '1/2W'   | 'DISCRETE' | '255ohm 1206'                                      | 'CHIP1206'     | ''          | ''            | ''        
 '255'        | '1%'      | '1/2W'   | '1206LF'  | 'EMPTY'  | 'TMP_QCS12557F200'(!)   = ''              | ''                 | 'CS12557F200'           |'R1206'| '(SMR1206AW)'                  | '255'     | '1%'    | '1/2W'   | 'IO'       | '255ohm 1206'                                      | 'CHIP1206'     | ''          | ''            | ''        
 '100'        | '1%'      | '1/2W'   | '1206LF'  | 'CHIP'   | 'TMP_QCS11007F200'(!)   = ''              | ''                 | 'CS11007F200'           |'R1206XI'| '(SMR1206AW)'                  | '100'     | '1%'    | '1/2W'   | 'DISCRETE' | 'RES CHIP 100 1/2W +-1%(1206)'                     | 'CHIP1206'     | ''          | ''            | '20221027'
 '100'        | '1%'      | '1/2W'   | '1206LF'  | 'EMPTY'  | 'TMP_QCS11007F200'(!)   = ''              | ''                 | 'CS11007F200'           |'R1206XI'| '(SMR1206AW)'                  | '100'     | '1%'    | '1/2W'   | 'IO'       | 'RES CHIP 100 1/2W +-1%(1206)'                     | 'CHIP1206'     | ''          | ''            | '20221027'
 '18'         | '1%'      | '1/4W'   | '0805LF'  | 'CHIP'   | 'TMP_QCS01806FA00'(!)   = ''              | ''                 | 'CS01806FA00'           |'R0805'| '(SMR0805AW)'                  | '18'      | '1%'    | '1/4W'   | 'DISCRETE' | '18ohm 0805'                                       | 'CHIP0805'     | ''          | ''            | ''        
 '18'         | '1%'      | '1/4W'   | '0805LF'  | 'EMPTY'  | 'TMP_QCS01806FA00'(!)   = ''              | ''                 | 'CS01806FA00'           |'R0805'| '(SMR0805AW)'                  | '18'      | '1%'    | '1/4W'   | 'IO'       | '18ohm 0805'                                       | 'CHIP0805'     | ''          | ''            | ''        
 '820'        | '1%'      | '1/4W'   | '0805LF'  | 'CHIP'   | 'TMP_QCS18206FA00'(!)   = ''              | ''                 | 'CS18206FA00'           |'R0805'| '(SMR0805AW)'                  | '820'     | '1%'    | '1/4W'   | 'DISCRETE' | '820ohm 0805'                                      | 'CHIP0805'     | ''          | ''            | ''        
 '820'        | '1%'      | '1/4W'   | '0805LF'  | 'EMPTY'  | 'TMP_QCS18206FA00'(!)   = ''              | ''                 | 'CS18206FA00'           |'R0805'| '(SMR0805AW)'                  | '820'     | '1%'    | '1/4W'   | 'IO'       | '820ohm 0805'                                      | 'CHIP0805'     | ''          | ''            | ''        
 '10K'        | '5%'      | '1/10W'  | '0603'    | 'CHIP'   | 'TMP_QCS31003J941'(!)   = ''              | ''                 | 'CS31003J941'           |'R0603'| '(SMR0603AW)'                  | '10K'     | '5%'    | '1/10W'  | 'DISCRETE' | '10Kohm 0603'                                      | 'CHIP0603'     | ''          | ''            | ''        
 '10K'        | '5%'      | '1/10W'  | '0603'    | 'EMPTY'  | 'TMP_QCS31003J941'(!)   = ''              | ''                 | 'CS31003J941'           |'R0603'| '(SMR0603AW)'                  | '10K'     | '5%'    | '1/10W'  | 'IO'       | '10Kohm 0603'                                      | 'CHIP0603'     | ''          | ''            | ''        
 '243'        | '1%'      | '1/10W'  | '0603'    | 'CHIP'   | 'TMP_QCS12433F900'(!)   = ''              | ''                 | 'CS12433F900'           |'R0603'| '(SMR0603AW)'                  | '243'     | '1%'    | '1/10W'  | 'DISCRETE' | '243ohm 0603'                                      | 'CHIP0603'     | ''          | ''            | ''        
 '243'        | '1%'      | '1/10W'  | '0603'    | 'EMPTY'  | 'TMP_QCS12433F900'(!)   = ''              | ''                 | 'CS12433F900'           |'R0603'| '(SMR0603AW)'                  | '243'     | '1%'    | '1/10W'  | 'IO'       | '243ohm 0603'                                      | 'CHIP0603'     | ''          | ''            | ''        
 '69.8'       | '1%'      | '1/10W'  | '0603'    | 'CHIP'   | 'TMP_QCS06983F911'(!)   = ''              | ''                 | 'CS06983F911'           |'R0603'| '(SMR0603AW)'                  | '69.8'    | '1%'    | '1/10W'  | 'DISCRETE' | '69.8ohm 0603'                                     | 'CHIP0603'     | ''          | ''            | ''        
 '69.8'       | '1%'      | '1/10W'  | '0603'    | 'EMPTY'  | 'TMP_QCS06983F911'(!)   = ''              | ''                 | 'CS06983F911'           |'R0603'| '(SMR0603AW)'                  | '69.8'    | '1%'    | '1/10W'  | 'IO'       | '69.8ohm 0603'                                     | 'CHIP0603'     | ''          | ''            | ''        
 '10'         | '1%'      | '1/4W'   | '1206LF'  | 'CHIP'   | 'TMP_QCS01006F214'(!)   = ''              | ''                 | 'CS01006F214'           |'R1206'| '(SMR1206AW)'                  | '10'      | '1%'    | '1/4W'   | 'DISCRETE' | '10ohm 1206'                                       | 'CHIP1206'     | ''          | ''            | ''        
 '10'         | '1%'      | '1/4W'   | '1206LF'  | 'EMPTY'  | 'TMP_QCS01006F214'(!)   = ''              | ''                 | 'CS01006F214'           |'R1206'| '(SMR1206AW)'                  | '10'      | '1%'    | '1/4W'   | 'IO'       | '10ohm 1206'                                       | 'CHIP1206'     | ''          | ''            | ''        
 '0.05'       | '1%'      | '1W'     | '2512LF'  | 'CHIP'   | 'TMP_QCS+0508FR00'(!)   = ''              | ''                 | 'CS+0508FR00'           |'R2512'| '(SMR2512AW)'                  | '0.05'    | '1%'    | '1W'     | 'DISCRETE' | '0.05ohm 2512'                                     | 'CHIP2512'     | ''          | ''            | ''        
 '0.05'       | '1%'      | '1W'     | '2512LF'  | 'EMPTY'  | 'TMP_QCS+0508FR00'(!)   = ''              | ''                 | 'CS+0508FR00'           |'R2512'| '(SMR2512AW)'                  | '0.05'    | '1%'    | '1W'     | 'IO'       | '0.05ohm 2512'                                     | 'CHIP2512'     | ''          | ''            | ''        
 '0.3'        | '1%'      | '1W'     | '2512LF'  | 'CHIP'   | 'TMP_QCS+3008FR00'(!)   = ''              | ''                 | 'CS+3008FR00'           |'R2512'| '(SMR2512AW)'                  | '0.3'     | '1%'    | '1W'     | 'DISCRETE' | '0.3ohm 2512'                                      | 'CHIP2512'     | ''          | ''            | ''        
 '0.3'        | '1%'      | '1W'     | '2512LF'  | 'EMPTY'  | 'TMP_QCS+3008FR00'(!)   = ''              | ''                 | 'CS+3008FR00'           |'R2512'| '(SMR2512AW)'                  | '0.3'     | '1%'    | '1W'     | 'IO'       | '0.3ohm 2512'                                      | 'CHIP2512'     | ''          | ''            | ''        
 '110'        | '1%'      | '1/16W'  | '0402LF'  | 'CHIP'   | 'TMP_QCS11102FB18'(!)   = 'End of Design' | 'Comp-Approve'     | 'CS11102FB18'           |'R0402'| '(R0402-0201)'                 | '110'     | '1%'    | '1/16W'  | 'DISCRETE' | '110ohm 0402'                                      | 'CHIP0402'     | ''          | ''            | ''        
 '110'        | '1%'      | '1/16W'  | '0402LF'  | 'EMPTY'  | 'TMP_QCS11102FB18'(!)   = 'End of Design' | 'Comp-Approve'     | 'CS11102FB18'           |'R0402'| '(R0402-0201)'                 | '110'     | '1%'    | '1/16W'  | 'IO'       | '110ohm 0402'                                      | 'CHIP0402'     | ''          | ''            | ''        
 '4.02K'      | '1%'      | '1/16W'  | '0402LF'  | 'CHIP'   | 'TMP_QCS24022FB13'(!)   = 'End of Design' | 'Comp-Approve'     | 'CS24022FB13'           |'R0402'| '(R0402-0201)'                 | '4.02K'   | '1%'    | '1/16W'  | 'DISCRETE' | '4.02Kohm 0402'                                    | 'CHIP0402'     | ''          | ''            | ''        
 '4.02K'      | '1%'      | '1/16W'  | '0402LF'  | 'EMPTY'  | 'TMP_QCS24022FB13'(!)   = 'End of Design' | 'Comp-Approve'     | 'CS24022FB13'           |'R0402'| '(R0402-0201)'                 | '4.02K'   | '1%'    | '1/16W'  | 'IO'       | '4.02Kohm 0402'                                    | 'CHIP0402'     | ''          | ''            | ''        
 '8.06K'      | '1%'      | '1/16W'  | '0402LF'  | 'CHIP'   | 'TMP_QCS28062FB21'(!)   = 'End of Design' | 'Comp-Approve'     | 'CS28062FB21'           |'R0402'| '(R0402-0201)'                 | '8.06K'   | '1%'    | '1/16W'  | 'DISCRETE' | '8.06Kohm 0402'                                    | 'CHIP0402'     | ''          | ''            | ''        
 '8.06K'      | '1%'      | '1/16W'  | '0402LF'  | 'EMPTY'  | 'TMP_QCS28062FB21'(!)   = 'End of Design' | 'Comp-Approve'     | 'CS28062FB21'           |'R0402'| '(R0402-0201)'                 | '8.06K'   | '1%'    | '1/16W'  | 'IO'       | '8.06Kohm 0402'                                    | 'CHIP0402'     | ''          | ''            | ''        
 '2.49K'      | '1%'      | '1/16W'  | '0402LF'  | 'CHIP'   | 'TMP_QCS22492FB22'(!)   = 'End of Design' | 'Comp-Approve'     | 'CS22492FB22'           |'R0402'| '(R0402-0201)'                 | '2.49K'   | '1%'    | '1/16W'  | 'DISCRETE' | '2.49Kohm 0402'                                    | 'CHIP0402'     | ''          | ''            | ''        
 '2.49K'      | '1%'      | '1/16W'  | '0402LF'  | 'EMPTY'  | 'TMP_QCS22492FB22'(!)   = 'End of Design' | 'Comp-Approve'     | 'CS22492FB22'           |'R0402'| '(R0402-0201)'                 | '2.49K'   | '1%'    | '1/16W'  | 'IO'       | '2.49Kohm 0402'                                    | 'CHIP0402'     | ''          | ''            | ''        
 '11K'        | '1%'      | '1/16W'  | '0402LF'  | 'CHIP'   | 'TMP_QCS31102FB11'(!)   = 'End of Design' | 'Comp-Approve'     | 'CS31102FB11'           |'R0402'| '(R0402-0201)'                 | '11K'     | '1%'    | '1/16W'  | 'DISCRETE' | '11Kohm 0402'                                      | 'CHIP0402'     | ''          | ''            | ''        
 '11K'        | '1%'      | '1/16W'  | '0402LF'  | 'EMPTY'  | 'TMP_QCS31102FB11'(!)   = 'End of Design' | 'Comp-Approve'     | 'CS31102FB11'           |'R0402'| '(R0402-0201)'                 | '11K'     | '1%'    | '1/16W'  | 'IO'       | '11Kohm 0402'                                      | 'CHIP0402'     | ''          | ''            | ''        
 '10.7K'      | '0.1%'    | '1/4W'   | '1206LF'  | 'CHIP'   | 'TMP_QCS31076B200'(!)   = ''              | ''                 | 'CS31076B200'           |'R1206'| '(SMR1206AW)'                  | '10.7K'   | '0.1%'  | '1/4W'   | 'DISCRETE' | '10.7Kohm 1206'                                    | 'CHIP1206'     | ''          | ''            | ''        
 '10.7K'      | '0.1%'    | '1/4W'   | '1206LF'  | 'EMPTY'  | 'TMP_QCS31076B200'(!)   = ''              | ''                 | 'CS31076B200'           |'R1206'| '(SMR1206AW)'                  | '10.7K'   | '0.1%'  | '1/4W'   | 'IO'       | '10.7Kohm 1206'                                    | 'CHIP1206'     | ''          | ''            | ''        
 '56.2K'      | '0.1%'    | '1/4W'   | '1206LF'  | 'CHIP'   | 'TMP_QCS35626B200'(!)   = ''              | ''                 | 'CS35626B200'           |'R1206'| '(SMR1206AW)'                  | '56.2K'   | '0.1%'  | '1/4W'   | 'DISCRETE' | '56.2Kohm 1206'                                    | 'CHIP1206'     | ''          | ''            | ''        
 '56.2K'      | '0.1%'    | '1/4W'   | '1206LF'  | 'EMPTY'  | 'TMP_QCS35626B200'(!)   = ''              | ''                 | 'CS35626B200'           |'R1206'| '(SMR1206AW)'                  | '56.2K'   | '0.1%'  | '1/4W'   | 'IO'       | '56.2Kohm 1206'                                    | 'CHIP1206'     | ''          | ''            | ''        
 '80.6K'      | '0.1%'    | '1/4W'   | '1206LF'  | 'CHIP'   | 'TMP_QCS38066B200'(!)   = ''              | ''                 | 'CS38066B200'           |'R1206'| '(SMR1206AW)'                  | '80.6K'   | '0.1%'  | '1/4W'   | 'DISCRETE' | '80.6Kohm 1206'                                    | 'CHIP1206'     | ''          | ''            | ''        
 '80.6K'      | '0.1%'    | '1/4W'   | '1206LF'  | 'EMPTY'  | 'TMP_QCS38066B200'(!)   = ''              | ''                 | 'CS38066B200'           |'R1206'| '(SMR1206AW)'                  | '80.6K'   | '0.1%'  | '1/4W'   | 'IO'       | '80.6Kohm 1206'                                    | 'CHIP1206'     | ''          | ''            | ''        
 '0.001'      | '0.1%'    | '1W'     | '2512LF'  | 'CHIP'   | 'TMP_QCS+0018BR00'(!)   = 'End of Design' | 'Comp-Release Qty' | 'CS+0018BR00'           |'R2512'| '(SMR2512AW)'                  | '0.001'   | '0.1%'  | '1W'     | 'DISCRETE' | '0.001ohm 2512'                                    | 'CHIP2512'     | ''          | ''            | ''        
 '0.001'      | '0.1%'    | '1W'     | '2512LF'  | 'EMPTY'  | 'TMP_QCS+0018BR00'(!)   = 'End of Design' | 'Comp-Release Qty' | 'CS+0018BR00'           |'R2512'| '(SMR2512AW)'                  | '0.001'   | '0.1%'  | '1W'     | 'IO'       | '0.001ohm 2512'                                    | 'CHIP2512'     | ''          | ''            | ''        
 '0.2'        | '0.1%'    | '1W'     | '2512LF'  | 'CHIP'   | 'TMP_QCS+2008BR00'(!)   = ''              | ''                 | 'CS+2008BR00'           |'R2512'| '(SMR2512AW)'                  | '0.2'     | '0.1%'  | '1W'     | 'DISCRETE' | '0.2ohm 2512'                                      | 'CHIP2512'     | ''          | ''            | ''        
 '0.2'        | '0.1%'    | '1W'     | '2512LF'  | 'EMPTY'  | 'TMP_QCS+2008BR00'(!)   = ''              | ''                 | 'CS+2008BR00'           |'R2512'| '(SMR2512AW)'                  | '0.2'     | '0.1%'  | '1W'     | 'IO'       | '0.2ohm 2512'                                      | 'CHIP2512'     | ''          | ''            | ''        
 '0.03'       | '0.1%'    | '1W'     | '2512LF'  | 'CHIP'   | 'TMP_QCS+0308BR00'(!)   = ''              | ''                 | 'CS+0308BR00'           |'R2512'| '(SMR2512AW)'                  | '0.03'    | '0.1%'  | '1W'     | 'DISCRETE' | '0.03ohm 2512'                                     | 'CHIP2512'     | ''          | ''            | ''        
 '0.03'       | '0.1%'    | '1W'     | '2512LF'  | 'EMPTY'  | 'TMP_QCS+0308BR00'(!)   = ''              | ''                 | 'CS+0308BR00'           |'R2512'| '(SMR2512AW)'                  | '0.03'    | '0.1%'  | '1W'     | 'IO'       | '0.03ohm 2512'                                     | 'CHIP2512'     | ''          | ''            | ''        
 '2.67K'      | '1%'      | '1/10W'  | '0603'    | 'CHIP'   | 'TMP_QCS22673F927'(!)   = 'End of Design' | 'Comp-Approve'     | 'CS22673F927'           |'R0603'| '(SMR0603AW)'                  | '2.67K'   | '1%'    | '1/10W'  | 'DISCRETE' | '2.67Kohm 0603'                                    | 'CHIP0603'     | ''          | ''            | ''        
 '2.67K'      | '1%'      | '1/10W'  | '0603'    | 'EMPTY'  | 'TMP_QCS22673F927'(!)   = 'End of Design' | 'Comp-Approve'     | 'CS22673F927'           |'R0603'| '(SMR0603AW)'                  | '2.67K'   | '1%'    | '1/10W'  | 'IO'       | '2.67Kohm 0603'                                    | 'CHIP0603'     | ''          | ''            | ''        
 '23.2K'      | '1%'      | '1/16W'  | '0402LF'  | 'CHIP'   | 'TMP_QCS32322FB11'(!)   = 'End of Design' | 'Comp-Approve'     | 'CS32322FB11'           |'R0402'| '(R0402-0201)'                 | '23.2K'   | '1%'    | '1/16W'  | 'DISCRETE' | '23.2Kohm 0402'                                    | 'CHIP0402'     | ''          | ''            | ''        
 '23.2K'      | '1%'      | '1/16W'  | '0402LF'  | 'EMPTY'  | 'TMP_QCS32322FB11'(!)   = 'End of Design' | 'Comp-Approve'     | 'CS32322FB11'           |'R0402'| '(R0402-0201)'                 | '23.2K'   | '1%'    | '1/16W'  | 'IO'       | '23.2Kohm 0402'                                    | 'CHIP0402'     | ''          | ''            | ''        
 '174'        | '1%'      | '1/10W'  | '0603'    | 'CHIP'   | 'TMP_QCS11743F900'(!)   = ''              | ''                 | 'CS11743F900'           |'R0603'| '(SMR0603AW)'                  | '174'     | '1%'    | '1/10W'  | 'DISCRETE' | '174ohm 0603'                                      | 'CHIP0603'     | ''          | ''            | ''        
 '174'        | '1%'      | '1/10W'  | '0603'    | 'EMPTY'  | 'TMP_QCS11743F900'(!)   = ''              | ''                 | 'CS11743F900'           |'R0603'| '(SMR0603AW)'                  | '174'     | '1%'    | '1/10W'  | 'IO'       | '174ohm 0603'                                      | 'CHIP0603'     | ''          | ''            | ''        
 '7.32K'      | '1%'      | '1/10W'  | '0603'    | 'CHIP'   | 'TMP_QCS27323F919'(!)   = ''              | ''                 | 'CS27323F919'           |'R0603'| '(SMR0603AW)'                  | '7.32K'   | '1%'    | '1/10W'  | 'DISCRETE' | '7.32Kohm 0603'                                    | 'CHIP0603'     | ''          | ''            | ''        
 '7.32K'      | '1%'      | '1/10W'  | '0603'    | 'EMPTY'  | 'TMP_QCS27323F919'(!)   = ''              | ''                 | 'CS27323F919'           |'R0603'| '(SMR0603AW)'                  | '7.32K'   | '1%'    | '1/10W'  | 'IO'       | '7.32Kohm 0603'                                    | 'CHIP0603'     | ''          | ''            | ''        
 '255'        | '0.1%'    | '1/10W'  | '0603'    | 'CHIP'   | 'TMP_QCS12553B900'(!)   = ''              | ''                 | 'CS12553B900'           |'R0603'| '(SMR0603AW)'                  | '255'     | '0.1%'  | '1/10W'  | 'DISCRETE' | '255ohm 0603'                                      | 'CHIP0603'     | ''          | ''            | ''        
 '255'        | '0.1%'    | '1/10W'  | '0603'    | 'EMPTY'  | 'TMP_QCS12553B900'(!)   = ''              | ''                 | 'CS12553B900'           |'R0603'| '(SMR0603AW)'                  | '255'     | '0.1%'  | '1/10W'  | 'IO'       | '255ohm 0603'                                      | 'CHIP0603'     | ''          | ''            | ''        
 '22'         | '1%'      | '1/10W'  | '0603'    | 'CHIP'   | 'TMP_QCS02203F919'(!)   = 'End of Design' | 'Comp-Approve'     | 'CS02203F919'           |'R0603'| '(SMR0603AW)'                  | '22'      | '1%'    | '1/10W'  | 'DISCRETE' | '22ohm 0603'                                       | 'CHIP0603'     | ''          | ''            | ''        
 '22'         | '1%'      | '1/10W'  | '0603'    | 'EMPTY'  | 'TMP_QCS02203F919'(!)   = 'End of Design' | 'Comp-Approve'     | 'CS02203F919'           |'R0603'| '(SMR0603AW)'                  | '22'      | '1%'    | '1/10W'  | 'IO'       | '22ohm 0603'                                       | 'CHIP0603'     | ''          | ''            | ''        
 '4.99K'      | '1%'      | '1/10W'  | '0603'    | 'CHIP'   | 'TMP_QCS24993F949'(!)   = 'End of Design' | 'Comp-Approve'     | 'CS24993F949'           |'R0603'| '(SMR0603AW)'                  | '4.99K'   | '1%'    | '1/10W'  | 'DISCRETE' | '4.99Kohm 0603'                                    | 'CHIP0603'     | ''          | ''            | ''        
 '4.99K'      | '1%'      | '1/10W'  | '0603'    | 'EMPTY'  | 'TMP_QCS24993F949'(!)   = 'End of Design' | 'Comp-Approve'     | 'CS24993F949'           |'R0603'| '(SMR0603AW)'                  | '4.99K'   | '1%'    | '1/10W'  | 'IO'       | '4.99Kohm 0603'                                    | 'CHIP0603'     | ''          | ''            | ''        
 '0.5'        | '1%'      | '1/4W'   | '1206'    | 'CHIP'   | 'TMP_QCS+5006F200'(!)   = ''              | ''                 | 'CS+5006F200'           |'R1206'| '(SMR1206AW)'                  | '0.5'     | '1%'    | '1/4W'   | 'DISCRETE' | '0.5ohm 1206'                                      | 'CHIP1206'     | ''          | ''            | ''        
 '0.5'        | '1%'      | '1/4W'   | '1206'    | 'EMPTY'  | 'TMP_QCS+5006F200'(!)   = ''              | ''                 | 'CS+5006F200'           |'R1206'| '(SMR1206AW)'                  | '0.5'     | '1%'    | '1/4W'   | 'IO'       | '0.5ohm 1206'                                      | 'CHIP1206'     | ''          | ''            | ''        
 '0.51'       | '5%'      | '1/4W'   | '1206'    | 'CHIP'   | 'TMP_QCS+5106J203'(!)   = ''              | ''                 | 'CS+5106J203'           |'R1206'| '(SMR1206AW)'                  | '0.51'    | '5%'    | '1/4W'   | 'DISCRETE' | '0.51ohm 1206'                                     | 'CHIP1206'     | ''          | ''            | ''        
 '0.51'       | '5%'      | '1/4W'   | '1206'    | 'EMPTY'  | 'TMP_QCS+5106J203'(!)   = ''              | ''                 | 'CS+5106J203'           |'R1206'| '(SMR1206AW)'                  | '0.51'    | '5%'    | '1/4W'   | 'IO'       | '0.51ohm 1206'                                     | 'CHIP1206'     | ''          | ''            | ''        
 '1.5K'       | '5%'      | '1/16W'  | '0402LF'  | 'CHIP'   | 'TMP_QCS21502JB16'(!)   = 'End of Design' | 'Comp-Approve'     | 'CS21502JB16'           |'R0402'| '(R0402-0201)'                 | '1.5K'    | '5%'    | '1/16W'  | 'DISCRETE' | '1.5Kohm 0402'                                     | 'CHIP0402'     | ''          | ''            | ''        
 '1.5K'       | '5%'      | '1/16W'  | '0402LF'  | 'EMPTY'  | 'TMP_QCS21502JB16'(!)   = 'End of Design' | 'Comp-Approve'     | 'CS21502JB16'           |'R0402'| '(R0402-0201)'                 | '1.5K'    | '5%'    | '1/16W'  | 'IO'       | '1.5Kohm 0402'                                     | 'CHIP0402'     | ''          | ''            | ''        
 '3.3K'       | '5%'      | '1/16W'  | '0402LF'  | 'CHIP'   | 'TMP_QCS23302JB22'(!)   = 'End of Design' | 'Comp-Approve'     | 'CS23302JB22'           |'R0402'| '(R0402-0201)'                 | '3.3K'    | '5%'    | '1/16W'  | 'DISCRETE' | '3.3Kohm 0402'                                     | 'CHIP0402'     | ''          | ''            | ''        
 '3.3K'       | '5%'      | '1/16W'  | '0402LF'  | 'EMPTY'  | 'TMP_QCS23302JB22'(!)   = 'End of Design' | 'Comp-Approve'     | 'CS23302JB22'           |'R0402'| '(R0402-0201)'                 | '3.3K'    | '5%'    | '1/16W'  | 'IO'       | '3.3Kohm 0402'                                     | 'CHIP0402'     | ''          | ''            | ''        
 '4.7K'       | '5%'      | '1/16W'  | '0402LF'  | 'CHIP'   | 'TMP_QCS24702JB38'(!)   = 'End of Design' | 'Comp-Approve'     | 'CS24702JB38'           |'R0402'| '(R0402-0201)'                 | '4.7K'    | '5%'    | '1/16W'  | 'DISCRETE' | '4.7Kohm 0402'                                     | 'CHIP0402'     | ''          | ''            | ''        
 '4.7K'       | '5%'      | '1/16W'  | '0402LF'  | 'EMPTY'  | 'TMP_QCS24702JB38'(!)   = 'End of Design' | 'Comp-Approve'     | 'CS24702JB38'           |'R0402'| '(R0402-0201)'                 | '4.7K'    | '5%'    | '1/16W'  | 'IO'       | '4.7Kohm 0402'                                     | 'CHIP0402'     | ''          | ''            | ''        
 '470K'       | '1%'      | '1/16W'  | '0402LF'  | 'CHIP'   | 'TMP_QCS44702FB13'(!)   = 'End of Design' | 'Comp-Approve'     | 'CS44702FB13'           |'R0402'| '(R0402-0201)'                 | '470K'    | '1%'    | '1/16W'  | 'DISCRETE' | '470Kohm 0402'                                     | 'CHIP0402'     | ''          | ''            | ''        
 '470K'       | '1%'      | '1/16W'  | '0402LF'  | 'EMPTY'  | 'TMP_QCS44702FB13'(!)   = 'End of Design' | 'Comp-Approve'     | 'CS44702FB13'           |'R0402'| '(R0402-0201)'                 | '470K'    | '1%'    | '1/16W'  | 'IO'       | '470Kohm 0402'                                     | 'CHIP0402'     | ''          | ''            | ''        
 '15K'        | '5%'      | '1/16W'  | '0402LF'  | 'CHIP'   | 'TMP_QCS31502JB26'(!)   = 'End of Design' | 'Comp-Approve'     | 'CS31502JB26'           |'R0402'| '(R0402-0201)'                 | '15K'     | '5%'    | '1/16W'  | 'DISCRETE' | '15Kohm 0402'                                      | 'CHIP0402'     | ''          | ''            | ''        
 '15K'        | '5%'      | '1/16W'  | '0402LF'  | 'EMPTY'  | 'TMP_QCS31502JB26'(!)   = 'End of Design' | 'Comp-Approve'     | 'CS31502JB26'           |'R0402'| '(R0402-0201)'                 | '15K'     | '5%'    | '1/16W'  | 'IO'       | '15Kohm 0402'                                      | 'CHIP0402'     | ''          | ''            | ''        
 '47K'        | '5%'      | '1/16W'  | '0402LF'  | 'CHIP'   | 'TMP_QCS34702JB21'(!)   = 'End of Design' | 'Comp-Approve'     | 'CS34702JB21'           |'R0402'| '(R0402-0201)'                 | '47K'     | '5%'    | '1/16W'  | 'DISCRETE' | '47Kohm 0402'                                      | 'CHIP0402'     | ''          | ''            | ''        
 '47K'        | '5%'      | '1/16W'  | '0402LF'  | 'EMPTY'  | 'TMP_QCS34702JB21'(!)   = 'End of Design' | 'Comp-Approve'     | 'CS34702JB21'           |'R0402'| '(R0402-0201)'                 | '47K'     | '5%'    | '1/16W'  | 'IO'       | '47Kohm 0402'                                      | 'CHIP0402'     | ''          | ''            | ''        
 '100'        | '0.1%'    | '1/10W'  | '0603'    | 'CHIP'   | 'TMP_QCS11003B900'(!)   = 'End of Design' | 'Comp-Approve'     | 'CS11003B900'           |'R0603'| '(SMR0603AW)'                  | '100'     | '0.1%'  | '1/10W'  | 'DISCRETE' | '100ohm 0603'                                      | 'CHIP0603'     | ''          | ''            | ''        
 '100'        | '0.1%'    | '1/10W'  | '0603'    | 'EMPTY'  | 'TMP_QCS11003B900'(!)   = 'End of Design' | 'Comp-Approve'     | 'CS11003B900'           |'R0603'| '(SMR0603AW)'                  | '100'     | '0.1%'  | '1/10W'  | 'IO'       | '100ohm 0603'                                      | 'CHIP0603'     | ''          | ''            | ''        
 '10.7K'      | '0.1%'    | '1/10W'  | '0603'    | 'CHIP'   | 'TMP_QCS31073B900'(!)   = ''              | ''                 | 'CS31073B900'           |'R0603'| '(SMR0603AW)'                  | '10.7K'   | '0.1%'  | '1/10W'  | 'DISCRETE' | '10.7Kohm 0603'                                    | 'CHIP0603'     | ''          | ''            | ''        
 '10.7K'      | '0.1%'    | '1/10W'  | '0603'    | 'EMPTY'  | 'TMP_QCS31073B900'(!)   = ''              | ''                 | 'CS31073B900'           |'R0603'| '(SMR0603AW)'                  | '10.7K'   | '0.1%'  | '1/10W'  | 'IO'       | '10.7Kohm 0603'                                    | 'CHIP0603'     | ''          | ''            | ''        
 '80.6K'      | '0.1%'    | '1/10W'  | '0603'    | 'CHIP'   | 'TMP_QCS38063B900'(!)   = ''              | ''                 | 'CS38063B900'           |'R0603'| '(SMR0603AW)'                  | '80.6K'   | '0.1%'  | '1/10W'  | 'DISCRETE' | '80.6Kohm 0603'                                    | 'CHIP0603'     | ''          | ''            | ''        
 '80.6K'      | '0.1%'    | '1/10W'  | '0603'    | 'EMPTY'  | 'TMP_QCS38063B900'(!)   = ''              | ''                 | 'CS38063B900'           |'R0603'| '(SMR0603AW)'                  | '80.6K'   | '0.1%'  | '1/10W'  | 'IO'       | '80.6Kohm 0603'                                    | 'CHIP0603'     | ''          | ''            | ''        
 '56.2K'      | '0.1%'    | '1/10W'  | '0603'    | 'CHIP'   | 'TMP_QCS35623B900'(!)   = ''              | ''                 | 'CS35623B900'           |'R0603'| '(SMR0603AW)'                  | '56.2K'   | '0.1%'  | '1/10W'  | 'DISCRETE' | '56.2Kohm 0603'                                    | 'CHIP0603'     | ''          | ''            | ''        
 '56.2K'      | '0.1%'    | '1/10W'  | '0603'    | 'EMPTY'  | 'TMP_QCCS35623B90'(!)   = ''              | ''                 | 'CS35623B900'           |'R0603'| '(SMR0603AW)'                  | '56.2K'   | '0.1%'  | '1/10W'  | 'IO'       | '56.2Kohm 0603'                                    | 'CHIP0603'     | ''          | ''            | ''        
 '215K'       | '0.1%'    | '1/10W'  | '0603'    | 'CHIP'   | 'TMP_QCS42153B900'(!)   = ''              | ''                 | 'CS42153B900'           |'R0603'| '(SMR0603AW)'                  | '215K'    | '0.1%'  | '1/10W'  | 'DISCRETE' | '215Kohm 0603'                                     | 'CHIP0603'     | ''          | ''            | ''        
 '215K'       | '0.1%'    | '1/10W'  | '0603'    | 'EMPTY'  | 'TMP_QCS42153B900'(!)   = ''              | ''                 | 'CS42153B900'           |'R0603'| '(SMR0603AW)'                  | '215K'    | '0.1%'  | '1/10W'  | 'IO'       | '215Kohm 0603'                                     | 'CHIP0603'     | ''          | ''            | ''        
 '1.65K'      | '1%'      | '1/16W'  | '0402LF'  | 'CHIP'   | 'TMP_QCS21652FB29'(!)   = 'End of Design' | 'Comp-Approve'     | 'CS21652FB29'           |'R0402'| '(R0402-0201)'                 | '1.65K'   | '1%'    | '1/16W'  | 'DISCRETE' | '1.65Kohm 0402'                                    | 'CHIP0402'     | ''          | ''            | ''        
 '1.65K'      | '1%'      | '1/16W'  | '0402LF'  | 'EMPTY'  | 'TMP_QCS21652FB29'(!)   = 'End of Design' | 'Comp-Approve'     | 'CS21652FB29'           |'R0402'| '(R0402-0201)'                 | '1.65K'   | '1%'    | '1/16W'  | 'IO'       | '1.65Kohm 0402'                                    | 'CHIP0402'     | ''          | ''            | ''        
 '41.2K'      | '1%'      | '1/16W'  | '0402LF'  | 'CHIP'   | 'TMP_QCS34122FB19'(!)   = ''              | ''                 | 'CS34122FB19'           |'R0402'| '(R0402-0201)'                 | '41.2K'   | '1%'    | '1/16W'  | 'DISCRETE' | '41.2Kohm 0402'                                    | 'CHIP0402'     | ''          | ''            | ''        
 '41.2K'      | '1%'      | '1/16W'  | '0402LF'  | 'EMPTY'  | 'TMP_QCS34122FB19'(!)   = ''              | ''                 | 'CS34122FB19'           |'R0402'| '(R0402-0201)'                 | '41.2K'   | '1%'    | '1/16W'  | 'IO'       | '41.2Kohm 0402'                                    | 'CHIP0402'     | ''          | ''            | ''        
 '1.62K'      | '1%'      | '1/16W'  | '0402LF'  | 'CHIP'   | 'TMP_QCS21622FB17'(!)   = 'End of Design' | 'Comp-Approve'     | 'CS21622FB17'           |'R0402'| '(R0402-0201)'                 | '1.62K'   | '1%'    | '1/16W'  | 'DISCRETE' | '1.62Kohm 0402'                                    | 'CHIP0402'     | ''          | ''            | ''        
 '1.62K'      | '1%'      | '1/16W'  | '0402LF'  | 'EMPTY'  | 'TMP_QCS21622FB17'(!)   = 'End of Design' | 'Comp-Approve'     | 'CS21622FB17'           |'R0402'| '(R0402-0201)'                 | '1.62K'   | '1%'    | '1/16W'  | 'IO'       | '1.62Kohm 0402'                                    | 'CHIP0402'     | ''          | ''            | ''        
 '86.6K'      | '1%'      | '1/16W'  | '0402LF'  | 'CHIP'   | 'TMP_QCS38662FB16'(!)   = 'End of Design' | 'Comp-Approve'     | 'CS38662FB16'           |'R0402'| '(R0402-0201)'                 | '86.6K'   | '1%'    | '1/16W'  | 'DISCRETE' | '86.6Kohm 0402'                                    | 'CHIP0402'     | ''          | ''            | ''        
 '86.6K'      | '1%'      | '1/16W'  | '0402LF'  | 'EMPTY'  | 'TMP_QCS38662FB16'(!)   = 'End of Design' | 'Comp-Approve'     | 'CS38662FB16'           |'R0402'| '(R0402-0201)'                 | '86.6K'   | '1%'    | '1/16W'  | 'IO'       | '86.6Kohm 0402'                                    | 'CHIP0402'     | ''          | ''            | ''        
 '40.2K'      | '1%'      | '1/16W'  | '0402LF'  | 'CHIP'   | 'TMP_QCS34022FB15'(!)   = 'End of Design' | 'Comp-Approve'     | 'CS34022FB15'           |'R0402'| '(R0402-0201)'                 | '40.2K'   | '1%'    | '1/16W'  | 'DISCRETE' | '40.2Kohm 0402'                                    | 'CHIP0402'     | ''          | ''            | ''        
 '40.2K'      | '1%'      | '1/16W'  | '0402LF'  | 'EMPTY'  | 'TMP_QCS34022FB15'(!)   = 'End of Design' | 'Comp-Approve'     | 'CS34022FB15'           |'R0402'| '(R0402-0201)'                 | '40.2K'   | '1%'    | '1/16W'  | 'IO'       | '40.2Kohm 0402'                                    | 'CHIP0402'     | ''          | ''            | ''        
 '27K'        | '1%'      | '1/16W'  | '0402LF'  | 'CHIP'   | 'TMP_QCS32702FB16'(!)   = 'End of Design' | 'Comp-Approve'     | 'CS32702FB16'           |'R0402'| '(R0402-0201)'                 | '27K'     | '1%'    | '1/16W'  | 'DISCRETE' | '27Kohm 0402'                                      | 'CHIP0402'     | ''          | ''            | ''        
 '27K'        | '1%'      | '1/16W'  | '0402LF'  | 'EMPTY'  | 'TMP_QCS32702FB16'(!)   = 'End of Design' | 'Comp-Approve'     | 'CS32702FB16'           |'R0402'| '(R0402-0201)'                 | '27K'     | '1%'    | '1/16W'  | 'IO'       | '27Kohm 0402'                                      | 'CHIP0402'     | ''          | ''            | ''        
 '47'         | '1%'      | '1/16W'  | '0402LF'  | 'CHIP'   | 'TMP_QCS04702FB16'(!)   = 'End of Design' | 'Comp-Approve'     | 'CS04702FB16'           |'R0402'| '(R0402-0201)'                 | '47'      | '1%'    | '1/16W'  | 'DISCRETE' | '47ohm 0402'                                       | 'CHIP0402'     | ''          | ''            | ''        
 '47'         | '1%'      | '1/16W'  | '0402LF'  | 'EMPTY'  | 'TMP_QCS04702FB16'(!)   = 'End of Design' | 'Comp-Approve'     | 'CS04702FB16'           |'R0402'| '(R0402-0201)'                 | '47'      | '1%'    | '1/16W'  | 'IO'       | '47ohm 0402'                                       | 'CHIP0402'     | ''          | ''            | ''        
 '16.2K'      | '1%'      | '1/16W'  | '0402LF'  | 'CHIP'   | 'TMP_QCS31622FB27'(!)   = 'End of Design' | 'Comp-Approve'     | 'CS31622FB27'           |'R0402'| '(R0402-0201)'                 | '16.2K'   | '1%'    | '1/16W'  | 'DISCRETE' | '16.2Kohm 0402'                                    | 'CHIP0402'     | ''          | ''            | ''        
 '16.2K'      | '1%'      | '1/16W'  | '0402LF'  | 'EMPTY'  | 'TMP_QCS31622FB27'(!)   = 'End of Design' | 'Comp-Approve'     | 'CS31622FB27'           |'R0402'| '(R0402-0201)'                 | '16.2K'   | '1%'    | '1/16W'  | 'IO'       | '16.2Kohm 0402'                                    | 'CHIP0402'     | ''          | ''            | ''        
 '69.8K'      | '1%'      | '1/16W'  | '0402LF'  | 'CHIP'   | 'TMP_QCS36982FB11'(!)   = 'End of Design' | 'Comp-Approve'     | 'CS36982FB11'           |'R0402'| '(R0402-0201)'                 | '69.8K'   | '1%'    | '1/16W'  | 'DISCRETE' | '69.8Kohm 0402'                                    | 'CHIP0402'     | ''          | ''            | ''        
 '69.8K'      | '1%'      | '1/16W'  | '0402LF'  | 'EMPTY'  | 'TMP_QCS36982FB11'(!)   = 'End of Design' | 'Comp-Approve'     | 'CS36982FB11'           |'R0402'| '(R0402-0201)'                 | '69.8K'   | '1%'    | '1/16W'  | 'IO'       | '69.8Kohm 0402'                                    | 'CHIP0402'     | ''          | ''            | ''        
 '7.32K'      | '1%'      | '1/16W'  | '0402LF'  | 'CHIP'   | 'TMP_QCS27322FB12'(!)   = 'End of Design' | 'Comp-Approve'     | 'CS27322FB12'           |'R0402'| '(R0402-0201)'                 | '7.32K'   | '1%'    | '1/16W'  | 'DISCRETE' | '7.32Kohm 0402'                                    | 'CHIP0402'     | ''          | ''            | ''        
 '7.32K'      | '1%'      | '1/16W'  | '0402LF'  | 'EMPTY'  | 'TMP_QCS27322FB12'(!)   = 'End of Design' | 'Comp-Approve'     | 'CS27322FB12'           |'R0402'| '(R0402-0201)'                 | '7.32K'   | '1%'    | '1/16W'  | 'IO'       | '7.32Kohm 0402'                                    | 'CHIP0402'     | ''          | ''            | ''        
 '57.6K'      | '1%'      | '1/16W'  | '0402LF'  | 'CHIP'   | 'TMP_QCS35762FB11'(!)   = 'End of Design' | 'Comp-Approve'     | 'CS35762FB11'           |'R0402'| '(R0402-0201)'                 | '57.6K'   | '1%'    | '1/16W'  | 'DISCRETE' | '57.6Kohm 0402'                                    | 'CHIP0402'     | ''          | ''            | ''        
 '57.6K'      | '1%'      | '1/16W'  | '0402LF'  | 'EMPTY'  | 'TMP_QCS35762FB11'(!)   = 'End of Design' | 'Comp-Approve'     | 'CS35762FB11'           |'R0402'| '(R0402-0201)'                 | '57.6K'   | '1%'    | '1/16W'  | 'IO'       | '57.6Kohm 0402'                                    | 'CHIP0402'     | ''          | ''            | ''        
 '4.99K'      | '1%'      | '1/16W'  | '0402LF'  | 'CHIP'   | 'TMP_QCS24992FB26'(!)   = 'End of Design' | 'Comp-Approve'     | 'CS24992FB26'           |'R0402'| '(R0402-0201)'                 | '4.99K'   | '1%'    | '1/16W'  | 'DISCRETE' | '4.99Kohm 0402'                                    | 'CHIP0402'     | ''          | ''            | ''        
 '4.99K'      | '1%'      | '1/16W'  | '0402LF'  | 'EMPTY'  | 'TMP_QCS24992FB26'(!)   = 'End of Design' | 'Comp-Approve'     | 'CS24992FB26'           |'R0402'| '(R0402-0201)'                 | '4.99K'   | '1%'    | '1/16W'  | 'IO'       | '4.99Kohm 0402'                                    | 'CHIP0402'     | ''          | ''            | ''        
 '82K'        | '1%'      | '1/16W'  | '0402LF'  | 'CHIP'   | 'TMP_QCS38202FB14'(!)   = 'End of Design' | 'Comp-Approve'     | 'CS38202FB14'           |'R0402'| '(R0402-0201)'                 | '82K'     | '1%'    | '1/16W'  | 'DISCRETE' | '82Kohm 0402'                                      | 'CHIP0402'     | ''          | ''            | ''        
 '82K'        | '1%'      | '1/16W'  | '0402LF'  | 'EMPTY'  | 'TMP_QCS38202FB14'(!)   = 'End of Design' | 'Comp-Approve'     | 'CS38202FB14'           |'R0402'| '(R0402-0201)'                 | '82K'     | '1%'    | '1/16W'  | 'IO'       | '82Kohm 0402'                                      | 'CHIP0402'     | ''          | ''            | ''        
 '11.8K'      | '1%'      | '1/16W'  | '0402LF'  | 'CHIP'   | 'TMP_QCS31182FB18'(!)   = 'End of Design' | 'Comp-Approve'     | 'CS31182FB18'           |'R0402'| '(R0402-0201)'                 | '11.8K'   | '1%'    | '1/16W'  | 'DISCRETE' | '11.8Kohm 0402'                                    | 'CHIP0402'     | ''          | ''            | ''        
 '11.8K'      | '1%'      | '1/16W'  | '0402LF'  | 'EMPTY'  | 'TMP_QCS31182FB18'(!)   = 'End of Design' | 'Comp-Approve'     | 'CS31182FB18'           |'R0402'| '(R0402-0201)'                 | '11.8K'   | '1%'    | '1/16W'  | 'IO'       | '11.8Kohm 0402'                                    | 'CHIP0402'     | ''          | ''            | ''        
 '45.3K'      | '1%'      | '1/16W'  | '0402LF'  | 'CHIP'   | 'TMP_QCS34532FB18'(!)   = 'End of Design' | 'Comp-Approve'     | 'CS34532FB18'           |'R0402'| '(R0402-0201)'                 | '45.3K'   | '1%'    | '1/16W'  | 'DISCRETE' | '45.3Kohm 0402'                                    | 'CHIP0402'     | ''          | ''            | ''        
 '45.3K'      | '1%'      | '1/16W'  | '0402LF'  | 'EMPTY'  | 'TMP_QCS34532FB18'(!)   = 'End of Design' | 'Comp-Approve'     | 'CS34532FB18'           |'R0402'| '(R0402-0201)'                 | '45.3K'   | '1%'    | '1/16W'  | 'IO'       | '45.3Kohm 0402'                                    | 'CHIP0402'     | ''          | ''            | ''        
 '16K'        | '1%'      | '1/16W'  | '0402LF'  | 'CHIP'   | 'TMP_QCS31602FB00'(!)   = 'End of Design' | 'Comp-Approve'     | 'CS31602FB00'           |'R0402'| '(R0402-0201)'                 | '16K'     | '1%'    | '1/16W'  | 'DISCRETE' | '16Kohm 0402'                                      | 'CHIP0402'     | ''          | ''            | ''        
 '16K'        | '1%'      | '1/16W'  | '0402LF'  | 'EMPTY'  | 'TMP_QCS31602FB00'(!)   = 'End of Design' | 'Comp-Approve'     | 'CS31602FB00'           |'R0402'| '(R0402-0201)'                 | '16K'     | '1%'    | '1/16W'  | 'IO'       | '16Kohm 0402'                                      | 'CHIP0402'     | ''          | ''            | ''        
 '150'        | '1%'      | '1/16W'  | '0402LF'  | 'CHIP'   | 'TMP_QCS11502FB21'(!)   = 'End of Design' | 'Comp-Approve'     | 'CS11502FB21'           |'R0402'| '(R0402-0201)'                 | '150'     | '1%'    | '1/16W'  | 'DISCRETE' | '150ohm 0402'                                      | 'CHIP0402'     | ''          | ''            | ''        
 '150'        | '1%'      | '1/16W'  | '0402LF'  | 'EMPTY'  | 'TMP_QCS11502FB21'(!)   = 'End of Design' | 'Comp-Approve'     | 'CS11502FB21'           |'R0402'| '(R0402-0201)'                 | '150'     | '1%'    | '1/16W'  | 'IO'       | '150ohm 0402'                                      | 'CHIP0402'     | ''          | ''            | ''        
 '2.37K'      | '1%'      | '1/16W'  | '0402LF'  | 'CHIP'   | 'TMP_QCS22372FB11'(!)   = 'End of Design' | 'Comp-Approve'     | 'CS22372FB11'           |'R0402'| '(R0402-0201)'                 | '2.37K'   | '1%'    | '1/16W'  | 'DISCRETE' | '2.37Kohm 0402'                                    | 'CHIP0402'     | ''          | ''            | ''        
 '2.37K'      | '1%'      | '1/16W'  | '0402LF'  | 'EMPTY'  | 'TMP_QCS22372FB11'(!)   = 'End of Design' | 'Comp-Approve'     | 'CS22372FB11'           |'R0402'| '(R0402-0201)'                 | '2.37K'   | '1%'    | '1/16W'  | 'IO'       | '2.37Kohm 0402'                                    | 'CHIP0402'     | ''          | ''            | ''        
 '3.16K'      | '1%'      | '1/16W'  | '0402LF'  | 'CHIP'   | 'TMP_QCS23162FB04'(!)   = 'End of Design' | 'Comp-Approve'     | 'CS23162FB04'           |'R0402'| '(R0402-0201)'                 | '3.16K'   | '1%'    | '1/16W'  | 'DISCRETE' | '3.16Kohm 0402'                                    | 'CHIP0402'     | ''          | ''            | ''        
 '3.16K'      | '1%'      | '1/16W'  | '0402LF'  | 'EMPTY'  | 'TMP_QCS23162FB04'(!)   = 'End of Design' | 'Comp-Approve'     | 'CS23162FB04'           |'R0402'| '(R0402-0201)'                 | '3.16K'   | '1%'    | '1/16W'  | 'IO'       | '3.16Kohm 0402'                                    | 'CHIP0402'     | ''          | ''            | ''        
 '42.2K'      | '1%'      | '1/16W'  | '0402LF'  | 'CHIP'   | 'TMP_QCS34222FB00'(!)   = 'End of Design' | 'Comp-Approve'     | 'CS34222FB00'           |'R0402'| '(R0402-0201)'                 | '42.2K'   | '1%'    | '1/16W'  | 'DISCRETE' | '42.2Kohm 0402'                                    | 'CHIP0402'     | ''          | ''            | ''        
 '42.2K'      | '1%'      | '1/16W'  | '0402LF'  | 'EMPTY'  | 'TMP_QCS34222FB00'(!)   = 'End of Design' | 'Comp-Approve'     | 'CS34222FB00'           |'R0402'| '(R0402-0201)'                 | '42.2K'   | '1%'    | '1/16W'  | 'IO'       | '42.2Kohm 0402'                                    | 'CHIP0402'     | ''          | ''            | ''        
 '56K'        | '1%'      | '1/16W'  | '0402LF'  | 'CHIP'   | 'TMP_QCS35602FB11'(!)   = 'End of Design' | 'Comp-Approve'     | 'CS35602FB11'           |'R0402'| '(R0402-0201)'                 | '56K'     | '1%'    | '1/16W'  | 'DISCRETE' | '56Kohm 0402'                                      | 'CHIP0402'     | ''          | ''            | ''        
 '56K'        | '1%'      | '1/16W'  | '0402LF'  | 'EMPTY'  | 'TMP_QCS35602FB11'(!)   = 'End of Design' | 'Comp-Approve'     | 'CS35602FB11'           |'R0402'| '(R0402-0201)'                 | '56K'     | '1%'    | '1/16W'  | 'IO'       | '56Kohm 0402'                                      | 'CHIP0402'     | ''          | ''            | ''        
 '80.6K'      | '1%'      | '1/16W ' | '0402LF ' | 'CHIP'   | 'TMP_QCS38062FB14'(!)   = 'End of Design' | 'Comp-Approve'     | 'CS38062FB14'           |'R0402'| '(R0402-0201)'                 | '80.6K'   | '1%'    | '1/16W ' | 'DISCRETE' | 'RES CHIP 80.6K 1/16W +-1% (0402)'                 | 'CHIP0402 '    | ''          | ''            | ''        
 '80.6K'      | '1%'      | '1/16W ' | '0402LF ' | 'EMPTY'  | 'TMP_QCS38062FB14'(!)   = 'End of Design' | 'Comp-Approve'     | 'CS38062FB14'           |'R0402'| '(R0402-0201)'                 | '80.6K'   | '1%'    | '1/16W ' | 'IO'       | 'RES CHIP 80.6K 1/16W +-1% (0402)'                 | 'CHIP0402 '    | ''          | ''            | ''        
 '22K'        | '1%'      | '1/16W'  | '0402LF'  | 'CHIP'   | 'TMP_QCS32202FB18'(!)   = 'End of Design' | 'Comp-Approve'     | 'CS32202FB18'           |'R0402'| '(R0402-0201)'                 | '22K'     | '1%'    | '1/16W'  | 'DISCRETE' | 'RES CHIP 22K 1/16W+-1%(0402)'                     | 'CHIP0402'     | ''          | ''            | ''        
 '22K'        | '1%'      | '1/16W'  | '0402LF'  | 'EMPTY'  | 'TMP_QCS32202FB18'(!)   = 'End of Design' | 'Comp-Approve'     | 'CS32202FB18'           |'R0402'| '(R0402-0201)'                 | '22K'     | '1%'    | '1/16W'  | 'IO'       | 'RES CHIP 22K 1/16W+-1%(0402)'                     | 'CHIP0402'     | ''          | ''            | ''        
 '12.1K'      | '1%'      | '1/16W'  | '0402LF'  | 'CHIP'   | 'TMP_QCS31212FB28'(!)   = 'End of Design' | 'Comp-Approve'     | 'CS31212FB28'           |'R0402'| '(R0402-0201)'                 | '12.1K'   | '1%'    | '1/16W'  | 'DISCRETE' | 'RES CHIP 12.1K 1/16W +-1%(0402)'                  | 'CHIP0402'     | ''          | ''            | ''        
 '12.1K'      | '1%'      | '1/16W'  | '0402LF'  | 'EMPTY'  | 'TMP_QCS31212FB28'(!)   = 'End of Design' | 'Comp-Approve'     | 'CS31212FB28'           |'R0402'| '(R0402-0201)'                 | '12.1K'   | '1%'    | '1/16W'  | 'IO'       | 'RES CHIP 12.1K 1/16W +-1%(0402)'                  | 'CHIP0402'     | ''          | ''            | ''        
 '37.4K'      | '1%'      | '1/16W'  | '0402LF'  | 'CHIP'   | 'TMP_QCS33742FB17'(!)   = 'End of Design' | 'Comp-Approve'     | 'CS33742FB17'           |'R0402'| '(R0402-0201)'                 | '37.4K'   | '1%'    | '1/16W ' | 'DISCRETE' | 'RES CHIP 37.4K 1/16W +-1% (0402)'                 | 'CHIP0402'     | ''          | ''            | ''        
 '37.4K'      | '1%'      | '1/16W'  | '0402LF'  | 'EMPTY'  | 'TMP_QCS33742FB17'(!)   = 'End of Design' | 'Comp-Approve'     | 'CS33742FB17'           |'R0402'| '(R0402-0201)'                 | '37.4K'   | '1%'    | '1/16W ' | 'IO'       | 'RES CHIP 37.4K 1/16W +-1% (0402)'                 | 'CHIP0402'     | ''          | ''            | ''        
 '680'        | '5%'      | '1/16W ' | '0402LF ' | 'CHIP'   | 'TMP_QCS16802JB27'(!)   = 'End of Design' | 'Comp-Approve'     | 'CS16802JB27'           |'R0402'| '(R0402-0201)'                 | '680'     | '5%'    | '1/16W ' | 'DISCRETE' | 'RES CHIP 680 1/16W +-5%(0402)'                    | 'CHIP0402 '    | ''          | ''            | ''        
 '680'        | '5%'      | '1/16W ' | '0402LF ' | 'EMPTY'  | 'TMP_QCS16802JB27'(!)   = 'End of Design' | 'Comp-Approve'     | 'CS16802JB27'           |'R0402'| '(R0402-0201)'                 | '680'     | '5%'    | '1/16W ' | 'IO'       | 'RES CHIP 680 1/16W +-5%(0402)'                    | 'CHIP0402 '    | ''          | ''            | ''        
 '5.1'        | '1%'      | '1/10W'  | '0603LF'  | 'CHIP'   | 'TMP_QCS-5103F916'(!)   = ''              | ''                 | 'CS-5103F916'           |'R0603'| '(SMR0603AW)'                  | '5.1'     | '1%'    | '1/10W'  | 'DISCRETE' | 'RES CHIP 5.1 1/10W +-1%(0603)'                    | 'CHIP0603'     | ''          | ''            | ''        
 '5.1'        | '1%'      | '1/10W'  | '0603LF'  | 'EMPTY'  | 'TMP_QCS-5103F916'(!)   = ''              | ''                 | 'CS-5103F916'           |'R0603'| '(SMR0603AW)'                  | '5.1'     | '1%'    | '1/10W'  | 'IO'       | 'RES CHIP 5.1 1/10W +-1%(0603)'                    | 'CHIP0603'     | ''          | ''            | ''        
 '2M'         | '1%'      | '1/16W'  | '0402LF'  | 'CHIP'   | 'TMP_QCS52002FB06'(!)   = 'End of Design' | 'Comp-Approve'     | 'CS52002FB06'           |'R0402'| '(R0402-0201)'                 | '2M'      | '1%'    | '1/16W ' | 'DISCRETE' | 'RES CHIP 2M 1/16W +-1%(0402)'                     | 'CHIP0402 '    | ''          | ''            | ''        
 '2M'         | '1%'      | '1/16W'  | '0402LF'  | 'EMPTY'  | 'TMP_QCS52002FB06'(!)   = 'End of Design' | 'Comp-Approve'     | 'CS52002FB06'           |'R0402'| '(R0402-0201)'                 | '2M'      | '1%'    | '1/16W ' | 'IO'       | 'RES CHIP 2M 1/16W +-1%(0402)'                     | 'CHIP0402 '    | ''          | ''            | ''        
 '165'        | '1%'      | '1/16W'  | '0402LF'  | 'CHIP'   | 'TMP_QCS11652FB19'(!)   = 'End of Design' | 'Comp-Approve'     | 'CS11652FB19'           |'R0402'| '(R0402-0201)'                 | '165'     | '1%'    | '1/16W ' | 'DISCRETE' | 'RES CHIP 165 1/16W +-1%(0402)'                    | 'CHIP0402 '    | ''          | ''            | ''        
 '165'        | '1%'      | '1/16W'  | '0402LF'  | 'EMPTY'  | 'TMP_QCS11652FB19'(!)   = 'End of Design' | 'Comp-Approve'     | 'CS11652FB19'           |'R0402'| '(R0402-0201)'                 | '165'     | '1%'    | '1/16W ' | 'IO'       | 'RES CHIP 165 1/16W +-1%(0402)'                    | 'CHIP0402 '    | ''          | ''            | ''        
 '49.9K'      | '1%'      | '1/16W ' | '0402LF ' | 'CHIP'   | 'TMP_QCS34992FB10'(!)   = 'End of Design' | 'Comp-Approve'     | 'CS34992FB10'           |'R0402'| '(R0402-0201)'                 | '49.9K'   | '1%'    | '1/16W ' | 'DISCRETE' | 'RES CHIP 49.9K 1/16W +-1%(0402)'                  | 'CHIP0402 '    | ''          | ''            | ''        
 '49.9K'      | '1%'      | '1/16W ' | '0402LF ' | 'EMPTY'  | 'TMP_QCS34992FB10'(!)   = 'End of Design' | 'Comp-Approve'     | 'CS34992FB10'           |'R0402'| '(R0402-0201)'                 | '49.9K'   | '1%'    | '1/16W ' | 'IO'       | 'RES CHIP 49.9K 1/16W +-1%(0402)'                  | 'CHIP0402 '    | ''          | ''            | ''        
 '15K'        | '1%'      | '1/16W'  | '0402LF'  | 'CHIP'   | 'TMP_QCS31502FB24'(!)   = 'End of Design' | 'Comp-Approve'     | 'CS31502FB24'           |'R0402'| '(R0402-0201)'                 | '15K'     | '1%'    | '1/16W ' | 'DISCRETE' | 'RES CHIP 15K 1/16W +-1% (0402)'                   | 'CHIP0402'     | ''          | ''            | ''        
 '15K'        | '1%'      | '1/16W'  | '0402LF'  | 'EMPTY'  | 'TMP_QCS31502FB24'(!)   = 'End of Design' | 'Comp-Approve'     | 'CS31502FB24'           |'R0402'| '(R0402-0201)'                 | '15K'     | '1%'    | '1/16W ' | 'IO'       | 'RES CHIP 15K 1/16W +-1% (0402)'                   | 'CHIP0402'     | ''          | ''            | ''        
 '10K'        | '1%'      | '1/16W'  | '0402LF'  | 'CHIP'   | 'TMP_QCS31002FB26'(!)   = 'End of Design' | 'Comp-Approve'     | 'CS31002FB26'           |'R0402'| '(R0402-0201)'                 | '10K'     | '1%'    | '1/16W'  | 'DISCRETE' | 'RES CHIP 10K 1/16W +-1% (0402)'                   | 'CHIP0402'     | ''          | ''            | ''        
 '10K'        | '1%'      | '1/16W'  | '0402LF'  | 'EMPTY'  | 'TMP_QCS31002FB26'(!)   = 'End of Design' | 'Comp-Approve'     | 'CS31002FB26'           |'R0402'| '(R0402-0201)'                 | '10K'     | '1%'    | '1/16W'  | 'IO'       | 'RES CHIP 10K 1/16W +-1% (0402)'                   | 'CHIP0402'     | ''          | ''            | ''        
 '2.7K'       | '1%'      | '1/16W'  | '0402LF'  | 'CHIP'   | 'TMP_QCS22702FB14'(!)   = 'End of Design' | 'Comp-Approve'     | 'CS22702FB14'           |'R0402'| '(R0402-0201)'                 | '2.7K'    | '1%'    | '1/16W ' | 'DISCRETE' | 'RES CHIP 2.7K 1/16W +-1%(0402)'                   | 'CHIP0402 '    | ''          | ''            | ''        
 '2.7K'       | '1%'      | '1/16W'  | '0402LF'  | 'EMPTY'  | 'TMP_QCS22702FB14'(!)   = 'End of Design' | 'Comp-Approve'     | 'CS22702FB14'           |'R0402'| '(R0402-0201)'                 | '2.7K'    | '1%'    | '1/16W ' | 'IO'       | 'RES CHIP 2.7K 1/16W +-1%(0402)'                   | 'CHIP0402 '    | ''          | ''            | ''        
 '402K'       | '1%'      | '1/16W'  | '0402LF'  | 'CHIP'   | 'TMP_QCS44022FB25'(!)   = 'End of Design' | 'Comp-Approve'     | 'CS44022FB25'           |'R0402'| '(R0402-0201)'                 | '402K'    | '1%'    | '1/16W ' | 'DISCRETE' | 'RES CHIP 402K 1/16W +-1% (0402)'                  | 'CHIP0402 '    | ''          | ''            | ''        
 '402K'       | '1%'      | '1/16W'  | '0402LF'  | 'EMPTY'  | 'TMP_QCS44022FB25'(!)   = 'End of Design' | 'Comp-Approve'     | 'CS44022FB25'           |'R0402'| '(R0402-0201)'                 | '402K'    | '1%'    | '1/16W ' | 'IO'       | 'RES CHIP 402K 1/16W +-1% (0402)'                  | 'CHIP0402 '    | ''          | ''            | ''        
 '511K'       | '1%'      | '1/10W'  | '0603LF ' | 'CHIP'   | 'TMP_QCS45113F900'(!)   = 'End of Design' | 'Comp-Approve'     | 'CS45113F900'           |'R0603'| '(SMR0603AW)'                  | '511K'    | '1%'    | '1/10W ' | 'DISCRETE' | 'RES CHIP 511K 1/10W +-1%(0603)'                   | 'CHIP0603 '    | ''          | ''            | ''        
 '511K'       | '1%'      | '1/10W'  | '0603LF ' | 'EMPTY'  | 'TMP_QCS45113F900'(!)   = 'End of Design' | 'Comp-Approve'     | 'CS45113F900'           |'R0603'| '(SMR0603AW)'                  | '511K'    | '1%'    | '1/10W ' | 'IO'       | 'RES CHIP 511K 1/10W +-1%(0603)'                   | 'CHIP0603 '    | ''          | ''            | ''        
 '220'        | '5%'      | '1/2W'   | '1210LF ' | 'CHIP'   | 'TMP_QCS12207J300'(!)   = ''              | ''                 | 'CS12207J300'           |'R1210'| '(SMR1210AW)'                  | '220'     | '5%'    | '1/2W'   | 'DISCRETE' | 'RES CHIP 220 1/2W +-5%(1210)'                     | 'CHIP1210 '    | ''          | ''            | ''        
 '220'        | '5%'      | '1/2W'   | '1210LF ' | 'EMPTY'  | 'TMP_QCS12207J300'(!)   = ''              | ''                 | 'CS12207J300'           |'R1210'| '(SMR1210AW)'                  | '220'     | '5%'    | '1/2W'   | 'IO'       | 'RES CHIP 220 1/2W +-5%(1210)'                     | 'CHIP1210 '    | ''          | ''            | ''        
 '56'         | '5%'      | '1/10W'  | '0603LF ' | 'CHIP'   | 'TMP_QCS05603J930'(!)   = ''              | ''                 | 'CS05603J930'           |'R0603'| '(SMR0603AW)'                  | '56'      | '5%'    | '1/10W ' | 'DISCRETE' | 'RESISTOR CHIP 56 1/10W,+-5%(1608)'                | 'CHIP0603 '    | ''          | ''            | ''        
 '56'         | '5%'      | '1/10W'  | '0603LF ' | 'EMPTY'  | 'TMP_QCS05603J930'(!)   = ''              | ''                 | 'CS05603J930'           |'R0603'| '(SMR0603AW)'                  | '56'      | '5%'    | '1/10W ' | 'IO'       | 'RESISTOR CHIP 56 1/10W,+-5%(1608)'                | 'CHIP0603 '    | ''          | ''            | ''        
 '2.55K'      | '1%'      | '1/16W ' | '0402LF ' | 'CHIP'   | 'TMP_QCS22552FB01'(!)   = 'End of Design' | 'Comp-Approve'     | 'CS22552FB01'           |'R0402'| '(R0402-0201)'                 | '2.55K'   | '1%'    | '1/16W ' | 'DISCRETE' | 'RES CHIP 2.55K 1/16W +-1%(0402)'                  | 'CHIP0402 '    | ''          | ''            | ''        
 '2.55K'      | '1%'      | '1/16W ' | '0402LF ' | 'EMPTY'  | 'TMP_QCS22552FB01'(!)   = 'End of Design' | 'Comp-Approve'     | 'CS22552FB01'           |'R0402'| '(R0402-0201)'                 | '2.55K'   | '1%'    | '1/16W ' | 'IO'       | 'RES CHIP 2.55K 1/16W +-1%(0402)'                  | 'CHIP0402 '    | ''          | ''            | ''        
 '9.53K'      | '1%'      | '1/16W ' | '0402LF ' | 'CHIP'   | 'TMP_QCS29532FB10'(!)   = 'End of Design' | 'Comp-Approve'     | 'CS29532FB10'           |'R0402'| '(R0402-0201)'                 | '9.53K'   | '1%'    | '1/16W ' | 'DISCRETE' | 'RES CHIP 9.53K 1/16W +-1%(0402)'                  | 'CHIP0402 '    | ''          | ''            | ''        
 '9.53K'      | '1%'      | '1/16W ' | '0402LF ' | 'EMPTY'  | 'TMP_QCS29532FB10'(!)   = 'End of Design' | 'Comp-Approve'     | 'CS29532FB10'           |'R0402'| '(R0402-0201)'                 | '9.53K'   | '1%'    | '1/16W ' | 'IO'       | 'RES CHIP 9.53K 1/16W +-1%(0402)'                  | 'CHIP0402 '    | ''          | ''            | ''        
 '909'        | '1%'      | '1/16W'  | '0402LF'  | 'CHIP'   | 'TMP_QCS19092FB17'(!)   = 'End of Design' | 'Comp-Approve'     | 'CS19092FB17'           |'R0402'| '(R0402-0201)'                 | '909'     | '1%'    | '1/16W'  | 'DISCRETE' | 'RES CHIP 909(1/16W,1%,0402)'                      | 'CHIP0402'     | ''          | ''            | ''        
 '909'        | '1%'      | '1/16W'  | '0402LF'  | 'EMPTY'  | 'TMP_QCS19092FB17'(!)   = 'End of Design' | 'Comp-Approve'     | 'CS19092FB17'           |'R0402'| '(R0402-0201)'                 | '909'     | '1%'    | '1/16W'  | 'IO'       | 'RES CHIP 909(1/16W,1%,0402)'                      | 'CHIP0402'     | ''          | ''            | ''        
 '51'         | '1%'      | '1/16W ' | '0402LF ' | 'CHIP'   | 'TMP_QCS05102FB09'(!)   = 'End of Design' | 'Comp-Approve'     | 'CS05102FB09'           |'R0402'| '(R0402-0201)'                 | '51'      | '1%'    | '1/16W ' | 'DISCRETE' | 'RES CHIP 51 1/16W +-1% (0402)'                    | 'CHIP0402 '    | ''          | ''            | ''        
 '51'         | '1%'      | '1/16W ' | '0402LF ' | 'EMPTY'  | 'TMP_QCS05102FB09'(!)   = 'End of Design' | 'Comp-Approve'     | 'CS05102FB09'           |'R0402'| '(R0402-0201)'                 | '51'      | '1%'    | '1/16W ' | 'IO'       | 'RES CHIP 51 1/16W +-1% (0402)'                    | 'CHIP0402 '    | ''          | ''            | ''        
 '59K'        | '1%'      | '1/16W ' | '0402LF ' | 'CHIP'   | 'TMP_QCS35902FB03'(!)   = ''              | ''                 | 'CS35902FB03'           |'R0402'| '(R0402-0201)'                 | '59K'     | '1%'    | '1/16W ' | 'DISCRETE' | 'RESISTOR CHIP 59K 1/16W +-1%(0402)'               | 'CHIP0402 '    | ''          | ''            | ''        
 '59K'        | '1%'      | '1/16W ' | '0402LF ' | 'EMPTY'  | 'TMP_QCS35902FB03'(!)   = ''              | ''                 | 'CS35902FB03'           |'R0402'| '(R0402-0201)'                 | '59K'     | '1%'    | '1/16W ' | 'IO'       | 'RESISTOR CHIP 59K 1/16W +-1%(0402)'               | 'CHIP0402 '    | ''          | ''            | ''        
 '0.39'       | '1%'      | '1/10W'  | '0603LF ' | 'CHIP'   | 'TMP_QCS+3903F900'(!)   = ''              | ''                 | 'CS+3903F900'           |'R0603'| '(SMR0603AW)'                  | '0.39'    | '1%'    | '1/10W ' | 'DISCRETE' | 'RES CHIP 0.39 1/10W +-1%(0603)'                   | 'CHIP0603'     | ''          | ''            | ''        
 '0.39'       | '1%'      | '1/10W'  | '0603LF ' | 'EMPTY'  | 'TMP_QCS+3903F900'(!)   = ''              | ''                 | 'CS+3903F900'           |'R0603'| '(SMR0603AW)'                  | '0.39'    | '1%'    | '1/10W ' | 'IO'       | 'RES CHIP 0.39 1/10W +-1%(0603)'                   | 'CHIP0603'     | ''          | ''            | ''        
 '2.61K'      | '1%'      | '1/16W ' | '0402LF ' | 'CHIP'   | 'TMP_QCS22612FB15'(!)   = 'End of Design' | 'Comp-Approve'     | 'CS22612FB15'           |'R0402'| '(R0402-0201)'                 | '2.61K'   | '1%'    | '1/16W ' | 'DISCRETE' | 'RES CHIP 2.61K 1/16W +-1%(0402)'                  | 'CHIP0402 '    | ''          | ''            | ''        
 '2.61K'      | '1%'      | '1/16W ' | '0402LF ' | 'EMPTY'  | 'TMP_QCS22612FB15'(!)   = 'End of Design' | 'Comp-Approve'     | 'CS22612FB15'           |'R0402'| '(R0402-0201)'                 | '2.61K'   | '1%'    | '1/16W ' | 'IO'       | 'RES CHIP 2.61K 1/16W +-1%(0402)'                  | 'CHIP0402 '    | ''          | ''            | ''        
 '52.3K'      | '1%'      | '1/10W'  | '0603LF ' | 'CHIP'   | 'TMP_QCS35233F916'(!)   = ''              | ''                 | 'CS35233F916'           |'R0603'| '(SMR0603AW)'                  | '52.3K'   | '1%'    | '1/10W ' | 'DISCRETE' | 'RES CHIP 52.3K 1/10W +-1% (0603)'                 | 'CHIP0603'     | ''          | ''            | ''        
 '52.3K'      | '1%'      | '1/10W'  | '0603LF ' | 'EMPTY'  | 'TMP_QCS35233F916'(!)   = ''              | ''                 | 'CS35233F916'           |'R0603'| '(SMR0603AW)'                  | '52.3K'   | '1%'    | '1/10W ' | 'IO'       | 'RES CHIP 52.3K 1/10W +-1% (0603)'                 | 'CHIP0603'     | ''          | ''            | ''        
 '6.49K'      | '1%'      | '1/16W ' | '0402LF ' | 'CHIP'   | 'TMP_QCS26492FB23'(!)   = 'End of Design' | 'Comp-Approve'     | 'CS26492FB23'           |'R0402'| '(R0402-0201)'                 | '6.49K'   | '1%'    | '1/16W ' | 'DISCRETE' | 'RES CHIP 6.49K 1/16W +-1%(0402)'                  | 'CHIP0402 '    | ''          | ''            | ''        
 '6.49K'      | '1%'      | '1/16W ' | '0402LF ' | 'EMPTY'  | 'TMP_QCS26492FB23'(!)   = 'End of Design' | 'Comp-Approve'     | 'CS26492FB23'           |'R0402'| '(R0402-0201)'                 | '6.49K'   | '1%'    | '1/16W ' | 'IO'       | 'RES CHIP 6.49K 1/16W +-1%(0402)'                  | 'CHIP0402 '    | ''          | ''            | ''        
 '1.47K'      | '1%'      | '1/16W ' | '0402LF ' | 'CHIP'   | 'TMP_QCS21472FB21'(!)   = 'End of Design' | 'Comp-Approve'     | 'CS21472FB21'           |'R0402'| '(R0402-0201)'                 | '1.47K'   | '1%'    | '1/16W ' | 'DISCRETE' | 'RES CHIP 1.47K 1/16W +-1% (0402)'                 | 'CHIP0402 '    | ''          | ''            | ''        
 '1.47K'      | '1%'      | '1/16W ' | '0402LF ' | 'EMPTY'  | 'TMP_QCS21472FB21'(!)   = 'End of Design' | 'Comp-Approve'     | 'CS21472FB21'           |'R0402'| '(R0402-0201)'                 | '1.47K'   | '1%'    | '1/16W ' | 'IO'       | 'RES CHIP 1.47K 1/16W +-1% (0402)'                 | 'CHIP0402 '    | ''          | ''            | ''        
 '9.1K'       | '0.5%'    | '1/10W'  | '0603LF ' | 'CHIP'   | 'TMP_QCS29103D915'(!)   = ''              | ''                 | 'CS29103D915'           |'R0603'| '(SMR0603AW)'                  | '9.1K'    | '0.5%'  | '1/10W ' | 'DISCRETE' | 'RES CHIP 9.1K 1/10W +-0.5%(0603)'                 | 'CHIP0603'     | ''          | ''            | ''        
 '9.1K'       | '0.5%'    | '1/10W'  | '0603LF ' | 'EMPTY'  | 'TMP_QCS29103D915'(!)   = ''              | ''                 | 'CS29103D915'           |'R0603'| '(SMR0603AW)'                  | '9.1K'    | '0.5%'  | '1/10W ' | 'IO'       | 'RES CHIP 9.1K 1/10W +-0.5%(0603)'                 | 'CHIP0603'     | ''          | ''            | ''        
 '4.32K'      | '1%'      | '1/16W'  | '0402LF'  | 'CHIP'   | 'TMP_QCS24322FB14'(!)   = 'End of Design' | 'Comp-Approve'     | 'CS24322FB14'           |'R0402'| '(R0402-0201)'                 | '4.32K'   | '1%'    | '1/16W'  | 'DISCRETE' | 'RES CHIP 4.32K 1/16W +-1%(0402)'                  | 'CHIP0402'     | ''          | ''            | ''        
 '4.32K'      | '1%'      | '1/16W'  | '0402LF'  | 'EMPTY'  | 'TMP_QCS24322FB14'(!)   = 'End of Design' | 'Comp-Approve'     | 'CS24322FB14'           |'R0402'| '(R0402-0201)'                 | '4.32K'   | '1%'    | '1/16W'  | 'IO'       | 'RES CHIP 4.32K 1/16W +-1%(0402)'                  | 'CHIP0402'     | ''          | ''            | ''        
 '7.5K'       | '1%'      | '1/16W'  | '0402LF'  | 'CHIP'   | 'TMP_QCS27502FB11'(!)   = 'End of Design' | 'Comp-Approve'     | 'CS27502FB11'           |'R0402'| '(R0402-0201)'                 | '7.5K'    | '1%'    | '1/16W'  | 'DISCRETE' | 'RES CHIP 7.5K 1/16W +-1% (0402)'                  | 'CHIP0402'     | ''          | ''            | ''        
 '7.5K'       | '1%'      | '1/16W'  | '0402LF'  | 'EMPTY'  | 'TMP_QCS27502FB11'(!)   = 'End of Design' | 'Comp-Approve'     | 'CS27502FB11'           |'R0402'| '(R0402-0201)'                 | '7.5K'    | '1%'    | '1/16W'  | 'IO'       | 'RES CHIP 7.5K 1/16W +-1% (0402)'                  | 'CHIP0402'     | ''          | ''            | ''        
 '300'        | '1%'      | '1/16W ' | '0402LF ' | 'CHIP'   | 'TMP_QCS13002FB00'(!)   = 'End of Design' | 'Comp-Approve'     | 'CS13002FB00'           |'R0402'| '(R0402-0201)'                 | '300'     | '1%'    | '1/16W ' | 'DISCRETE' | 'RES CHIP 300 1/16W +-1%(0402)'                    | 'CHIP0402 '    | ''          | ''            | ''        
 '300'        | '1%'      | '1/16W ' | '0402LF ' | 'EMPTY'  | 'TMP_QCS13002FB00'(!)   = 'End of Design' | 'Comp-Approve'     | 'CS13002FB00'           |'R0402'| '(R0402-0201)'                 | '300'     | '1%'    | '1/16W ' | 'IO'       | 'RES CHIP 300 1/16W +-1%(0402)'                    | 'CHIP0402 '    | ''          | ''            | ''        
 '120'        | '5%'      | '1/10W'  | '0603LF ' | 'CHIP'   | 'TMP_QCS11203J936'(!)   = ''              | ''                 | 'CS11203J936'           |'R0603'| '(SMR0603AW)'                  | '120'     | '5%'    | '1/10W ' | 'DISCRETE' | 'RES CHIP 120 1/10W +-5%(0603)'                    | 'CHIP0603'     | ''          | ''            | ''        
 '120'        | '5%'      | '1/10W'  | '0603LF ' | 'EMPTY'  | 'TMP_QCS11203J936'(!)   = ''              | ''                 | 'CS11203J936'           |'R0603'| '(SMR0603AW)'                  | '120'     | '5%'    | '1/10W ' | 'IO'       | 'RES CHIP 120 1/10W +-5%(0603)'                    | 'CHIP0603'     | ''          | ''            | ''        
 '150'        | '5%'      | '1/10W'  | '0603LF ' | 'CHIP'   | 'TMP_QCS11503J937'(!)   = ''              | ''                 | 'CS11503J937'           |'R0603'| '(SMR0603AW)'                  | '150'     | '5%'    | '1/10W ' | 'DISCRETE' | 'RES CHIP 150 1/10W +-5%(0603)'                    | 'CHIP0603'     | ''          | ''            | ''        
 '150'        | '5%'      | '1/10W'  | '0603LF ' | 'EMPTY'  | 'TMP_QCS11503J937'(!)   = ''              | ''                 | 'CS11503J937'           |'R0603'| '(SMR0603AW)'                  | '150'     | '5%'    | '1/10W ' | 'IO'       | 'RES CHIP 150 1/10W +-5%(0603)'                    | 'CHIP0603'     | ''          | ''            | ''        
 '93.1K'      | '1%'      | '1/16W ' | '0402LF ' | 'CHIP'   | 'TMP_QCS39312FB15'(!)   = 'End of Design' | 'Comp-Approve'     | 'CS39312FB15'           |'R0402'| '(R0402-0201)'                 | '93.1K'   | '1%'    | '1/16W ' | 'DISCRETE' | 'RES CHIP 93.1K 1/16W +-1%(0402)'                  | 'CHIP0402 '    | ''          | ''            | ''        
 '93.1K'      | '1%'      | '1/16W ' | '0402LF ' | 'EMPTY'  | 'TMP_QCS39312FB15'(!)   = 'End of Design' | 'Comp-Approve'     | 'CS39312FB15'           |'R0402'| '(R0402-0201)'                 | '93.1K'   | '1%'    | '1/16W ' | 'IO'       | 'RES CHIP 93.1K 1/16W +-1%(0402)'                  | 'CHIP0402 '    | ''          | ''            | ''        
 '10.2K'      | '1%'      | '1/16W ' | '0402LF ' | 'CHIP'   | 'TMP_QCS31022FB17'(!)   = 'End of Design' | 'Comp-Approve'     | 'CS31022FB17'           |'R0402'| '(R0402-0201)'                 | '10.2K'   | '1%'    | '1/16W ' | 'DISCRETE' | 'RES CHIP 10.2K 1/16W +-1%(0402)'                  | 'CHIP0402 '    | ''          | ''            | ''        
 '10.2K'      | '1%'      | '1/16W ' | '0402LF ' | 'EMPTY'  | 'TMP_QCS31022FB17'(!)   = 'End of Design' | 'Comp-Approve'     | 'CS31022FB17'           |'R0402'| '(R0402-0201)'                 | '10.2K'   | '1%'    | '1/16W ' | 'IO'       | 'RES CHIP 10.2K 1/16W +-1%(0402)'                  | 'CHIP0402 '    | ''          | ''            | ''        
 '1.37K'      | '1%'      | '1/16W ' | '0402LF ' | 'CHIP'   | 'TMP_QCS21372FB19'(!)   = 'End of Design' | 'Comp-Approve'     | 'CS21372FB19'           |'R0402'| '(R0402-0201)'                 | '1.37K'   | '1%'    | '1/16W ' | 'DISCRETE' | 'RES CHIP 1.37K 1/16W +-1%(0402)'                  | 'CHIP0402 '    | ''          | ''            | ''        
 '1.37K'      | '1%'      | '1/16W ' | '0402LF ' | 'EMPTY'  | 'TMP_QCS21372FB19'(!)   = 'End of Design' | 'Comp-Approve'     | 'CS21372FB19'           |'R0402'| '(R0402-0201)'                 | '1.37K'   | '1%'    | '1/16W ' | 'IO'       | 'RES CHIP 1.37K 1/16W +-1%(0402)'                  | 'CHIP0402 '    | ''          | ''            | ''        
 '90.9K'      | '1%'      | '1/16W ' | '0402LF ' | 'CHIP'   | 'TMP_QCS39092FB11'(!)   = 'End of Design' | 'Comp-Approve'     | 'CS39092FB11'           |'R0402'| '(R0402-0201)'                 | '90.9K'   | '1%'    | '1/16W ' | 'DISCRETE' | 'RES CHIP 90.9K 1/16W +-1% (0402)'                 | 'CHIP0402 '    | ''          | ''            | ''        
 '90.9K'      | '1%'      | '1/16W ' | '0402LF ' | 'EMPTY'  | 'TMP_QCS39092FB11'(!)   = 'End of Design' | 'Comp-Approve'     | 'CS39092FB11'           |'R0402'| '(R0402-0201)'                 | '90.9K'   | '1%'    | '1/16W ' | 'IO'       | 'RES CHIP 90.9K 1/16W +-1% (0402)'                 | 'CHIP0402 '    | ''          | ''            | ''        
 '45.3K'      | '1%'      | '1/16W ' | '0402LF ' | 'CHIP'   | 'TMP_QCS34532FB18'(!)   = 'End of Design' | 'Comp-Approve'     | 'CS34532FB18'           |'R0402'| '(R0402-0201)'                 | '45.3K'   | '1%'    | '1/16W ' | 'DISCRETE' | 'RES CHIP 45.3K 1/16W +-1% (0402)'                 | 'CHIP0402 '    | ''          | ''            | ''        
 '45.3K'      | '1%'      | '1/16W ' | '0402LF ' | 'EMPTY'  | 'TMP_QCS34532FB18'(!)   = 'End of Design' | 'Comp-Approve'     | 'CS34532FB18'           |'R0402'| '(R0402-0201)'                 | '45.3K'   | '1%'    | '1/16W ' | 'IO'       | 'RES CHIP 45.3K 1/16W +-1% (0402)'                 | 'CHIP0402 '    | ''          | ''            | ''        
 '5.49K'      | '1%'      | '1/16W ' | '0402LF ' | 'CHIP'   | 'TMP_QCS25492FB12'(!)   = 'End of Design' | 'Comp-Approve'     | 'CS25492FB12'           |'R0402'| '(R0402-0201)'                 | '5.49K'   | '1%'    | '1/16W ' | 'DISCRETE' | 'RES CHIP 5.49K 1/16W +-1%(0402)'                  | 'CHIP0402 '    | ''          | ''            | ''        
 '5.49K'      | '1%'      | '1/16W ' | '0402LF ' | 'EMPTY'  | 'TMP_QCS25492FB12'(!)   = 'End of Design' | 'Comp-Approve'     | 'CS25492FB12'           |'R0402'| '(R0402-0201)'                 | '5.49K'   | '1%'    | '1/16W ' | 'IO'       | 'RES CHIP 5.49K 1/16W +-1%(0402)'                  | 'CHIP0402 '    | ''          | ''            | ''        
 '5.1K'       | '1%'      | '1/10W'  | '0603LF ' | 'CHIP'   | 'TMP_QCS25103F917'(!)   = 'End of Design' | 'Comp-Release Qty' | 'CS25103F917'           |'R0603'| '(SMR0603AW)'                  | '5.1K'    | '1%'    | '1/10W ' | 'DISCRETE' | 'RES CHIP 5.1K 1/10W +-1% (0603)'                  | 'CHIP0603'     | ''          | ''            | ''        
 '5.1K'       | '1%'      | '1/10W'  | '0603LF ' | 'EMPTY'  | 'TMP_QCS25103F917'(!)   = 'End of Design' | 'Comp-Release Qty' | 'CS25103F917'           |'R0603'| '(SMR0603AW)'                  | '5.1K'    | '1%'    | '1/10W ' | 'IO'       | 'RES CHIP 5.1K 1/10W +-1% (0603)'                  | 'CHIP0603'     | ''          | ''            | ''        
 '10'         | '1%'      | '1/16W'  | '0402LF'  | 'CHIP'   | 'TMP_QCS01002FB21'(!)   = 'End of Design' | 'Comp-Approve'     | 'CS01002FB21'           |'R0402'| '(R0402-0201)'                 | '10'      | '1%'    | '1/16W'  | 'DISCRETE' | 'RES CHIP 10 1/16W +-1%(0402)'                     | 'CHIP0402'     | ''          | ''            | ''        
 '10'         | '1%'      | '1/16W'  | '0402LF'  | 'EMPTY'  | 'TMP_QCS01002FB21'(!)   = 'End of Design' | 'Comp-Approve'     | 'CS01002FB21'           |'R0402'| '(R0402-0201)'                 | '10'      | '1%'    | '1/16W'  | 'IO'       | 'RES CHIP 10 1/16W +-1%(0402)'                     | 'CHIP0402'     | ''          | ''            | ''        
 '56'         | '1%'      | '1/16W'  | '0402LF'  | 'CHIP'   | 'TMP_QCS05602FB15'(!)   = 'End of Design' | 'Comp-Approve'     | 'CS05602FB15'           |'R0402'| '(R0402-0201)'                 | '56'      | '1%'    | '1/16W'  | 'DISCRETE' | 'RESISTOR CHIP 56 1/16W +-1% (0402)'               | 'CHIP0402'     | ''          | ''            | ''        
 '56'         | '1%'      | '1/16W'  | '0402LF'  | 'EMPTY'  | 'TMP_QCS05602FB15'(!)   = 'End of Design' | 'Comp-Approve'     | 'CS05602FB15'           |'R0402'| '(R0402-0201)'                 | '56'      | '1%'    | '1/16W'  | 'IO'       | 'RESISTOR CHIP 56 1/16W +-1% (0402)'               | 'CHIP0402'     | ''          | ''            | ''        
 '82.5'       | '1%'      | '1/16W'  | '0402LF'  | 'CHIP'   | 'TMP_QCS08252FB11'(!)   = 'End of Design' | 'Comp-Approve'     | 'CS08252FB11'           |'R0402'| '(R0402-0201)'                 | '82.5'    | '1%'    | '1/16W'  | 'DISCRETE' | 'RES CHIP 82.5 1/16W +-1%(0402)'                   | 'CHIP0402'     | ''          | ''            | ''        
 '82.5'       | '1%'      | '1/16W'  | '0402LF'  | 'EMPTY'  | 'TMP_QCS08252FB11'(!)   = 'End of Design' | 'Comp-Approve'     | 'CS08252FB11'           |'R0402'| '(R0402-0201)'                 | '82.5'    | '1%'    | '1/16W'  | 'IO'       | 'RES CHIP 82.5 1/16W +-1%(0402)'                   | 'CHIP0402'     | ''          | ''            | ''        
 '100'        | '1%'      | '1/16W'  | '0402LF'  | 'CHIP'   | 'TMP_QCS11002FB22'(!)   = 'End of Design' | 'Comp-Approve'     | 'CS11002FB22'           |'R0402'| '(R0402-0201)'                 | '100'     | '1%'    | '1/16W'  | 'DISCRETE' | 'RES CHIP 100 1/16W +-1%(0402)'                    | 'CHIP0402'     | ''          | ''            | ''        
 '100'        | '1%'      | '1/16W'  | '0402LF'  | 'EMPTY'  | 'TMP_QCS11002FB22'(!)   = 'End of Design' | 'Comp-Approve'     | 'CS11002FB22'           |'R0402'| '(R0402-0201)'                 | '100'     | '1%'    | '1/16W'  | 'IO'       | 'RES CHIP 100 1/16W +-1%(0402)'                    | 'CHIP0402'     | ''          | ''            | ''        
 '100'        | '5%'      | '1/16W'  | '0402LF'  | 'CHIP'   | 'TMP_QCS11002JB32'(!)   = 'End of Design' | 'Comp-Approve'     | 'CS11002JB32'           |'R0402'| '(R0402-0201)'                 | '100'     | '5%'    | '1/16W'  | 'DISCRETE' | 'RES CHIP 100 1/16W +-5% (0402)'                   | 'CHIP0402'     | ''          | ''            | ''        
 '100'        | '5%'      | '1/16W'  | '0402LF'  | 'EMPTY'  | 'TMP_QCS11002JB32'(!)   = 'End of Design' | 'Comp-Approve'     | 'CS11002JB32'           |'R0402'| '(R0402-0201)'                 | '100'     | '5%'    | '1/16W'  | 'IO'       | 'RES CHIP 100 1/16W +-5% (0402)'                   | 'CHIP0402'     | ''          | ''            | ''        
 '178'        | '1%'      | '1/10W'  | '0603LF'  | 'CHIP'   | 'TMP_QCS11783F912'(!)   = ''              | ''                 | 'CS11783F912'           |'R0603'| '(SMR0603AW)'                  | '178'     | '1%'    | '1/10W'  | 'DISCRETE' | 'RES CHIP 178 1/10W +-1%(0603)'                    | 'CHIP0603'     | ''          | ''            | ''        
 '178'        | '1%'      | '1/10W'  | '0603LF'  | 'EMPTY'  | 'TMP_QCS11783F912'(!)   = ''              | ''                 | 'CS11783F912'           |'R0603'| '(SMR0603AW)'                  | '178'     | '1%'    | '1/10W'  | 'IO'       | 'RES CHIP 178 1/10W +-1%(0603)'                    | 'CHIP0603'     | ''          | ''            | ''        
 '301'        | '1%'      | '1/16W'  | '0402LF'  | 'CHIP'   | 'TMP_QCS13012FB14'(!)   = 'End of Design' | 'Comp-Approve'     | 'CS13012FB14'           |'R0402'| '(R0402-0201)'                 | '301'     | '1%'    | '1/16W'  | 'DISCRETE' | 'RES CHIP 301 1/16W +-1%(0402)'                    | 'CHIP0402'     | ''          | ''            | ''        
 '301'        | '1%'      | '1/16W'  | '0402LF'  | 'EMPTY'  | 'TMP_QCS13012FB14'(!)   = 'End of Design' | 'Comp-Approve'     | 'CS13012FB14'           |'R0402'| '(R0402-0201)'                 | '301'     | '1%'    | '1/16W'  | 'IO'       | 'RES CHIP 301 1/16W +-1%(0402)'                    | 'CHIP0402'     | ''          | ''            | ''        
 '340'        | '1%'      | '1/10W'  | '0603LF'  | 'CHIP'   | 'TMP_QCS13403F902'(!)   = ''              | ''                 | 'CS13403F902'           |'R0603'| '(SMR0603AW)'                  | '340'     | '1%'    | '1/10W'  | 'DISCRETE' | 'RES CHIP 340 1/10W +-1%(0603)'                    | 'CHIP0402'     | ''          | ''            | ''        
 '340'        | '1%'      | '1/10W'  | '0603LF'  | 'EMPTY'  | 'TMP_QCS13403F902'(!)   = ''              | ''                 | 'CS13403F902'           |'R0603'| '(SMR0603AW)'                  | '340'     | '1%'    | '1/10W'  | 'IO'       | 'RES CHIP 340 1/10W +-1%(0603)'                    | 'CHIP0402'     | ''          | ''            | ''        
 '953'        | '1%'      | '1/16W'  | '0402LF'  | 'CHIP'   | 'TMP_QCS19532FB00'(!)   = 'End of Design' | 'Comp-Approve'     | 'CS19532FB00'           |'R0402'| '(R0402-0201)'                 | '953'     | '1%'    | '1/16W'  | 'DISCRETE' | 'RES CHIP 953 1/16W +-1% (0402)'                   | 'CHIP0402'     | ''          | ''            | ''        
 '953'        | '1%'      | '1/16W'  | '0402LF'  | 'EMPTY'  | 'TMP_QCS19532FB00'(!)   = 'End of Design' | 'Comp-Approve'     | 'CS19532FB00'           |'R0402'| '(R0402-0201)'                 | '953'     | '1%'    | '1/16W'  | 'IO'       | 'RES CHIP 953 1/16W +-1% (0402)'                   | 'CHIP0402'     | ''          | ''            | ''        
 '1K'         | '5%'      | '1/16W'  | '0402LF'  | 'CHIP'   | 'TMP_QCS21002JB34'(!)   = 'End of Design' | 'Comp-Approve'     | 'CS21002JB34'           |'R0402'| '(R0402-0201)'                 | '1K'      | '5%'    | '1/16W'  | 'DISCRETE' | 'RES CHIP 1K 1/16W 5%(0402)'                       | 'CHIP0402'     | ''          | ''            | ''        
 '1K'         | '5%'      | '1/16W'  | '0402LF'  | 'EMPTY'  | 'TMP_QCS21002JB34'(!)   = 'End of Design' | 'Comp-Approve'     | 'CS21002JB34'           |'R0402'| '(R0402-0201)'                 | '1K'      | '5%'    | '1/16W'  | 'IO'       | 'RES CHIP 1K 1/16W 5%(0402)'                       | 'CHIP0402'     | ''          | ''            | ''        
 '1.21K'      | '1%'      | '1/16W'  | '0402LF'  | 'CHIP'   | 'TMP_QCS21212FB18'(!)   = 'End of Design' | 'Comp-Approve'     | 'CS21212FB18'           |'R0402'| '(R0402-0201)'                 | '1.21K'   | '1%'    | '1/16W'  | 'DISCRETE' | 'RES CHIP 1.21K 1/16W +-1%(0402)'                  | 'CHIP0402'     | ''          | ''            | ''        
 '1.21K'      | '1%'      | '1/16W'  | '0402LF'  | 'EMPTY'  | 'TMP_QCS21212FB18'(!)   = 'End of Design' | 'Comp-Approve'     | 'CS21212FB18'           |'R0402'| '(R0402-0201)'                 | '1.21K'   | '1%'    | '1/16W'  | 'IO'       | 'RES CHIP 1.21K 1/16W +-1%(0402)'                  | 'CHIP0402'     | ''          | ''            | ''        
 '2K'         | '1%'      | '1/16W'  | '0402LF'  | 'CHIP'   | 'TMP_QCS22002FB19'(!)   = 'End of Design' | 'Comp-Approve'     | 'CS22002FB19'           |'R0402'| '(R0402-0201)'                 | '2K'      | '1%'    | '1/16W'  | 'DISCRETE' | 'RES CHIP 2K 1/16W +-1%(0402)'                     | 'CHIP0402'     | ''          | ''            | ''        
 '2K'         | '1%'      | '1/16W'  | '0402LF'  | 'EMPTY'  | 'TMP_QCS22002FB19'(!)   = 'End of Design' | 'Comp-Approve'     | 'CS22002FB19'           |'R0402'| '(R0402-0201)'                 | '2K'      | '1%'    | '1/16W'  | 'IO'       | 'RES CHIP 2K 1/16W +-1%(0402)'                     | 'CHIP0402'     | ''          | ''            | ''        
 '2.2'        | '5%'      | '1/16W'  | '0402LF'  | 'CHIP'   | 'TMP_QCS-2202JB25'(!)   = 'End of Design' | 'Comp-Approve'     | 'CS-2202JB25'           |'R0402'| '(R0402-0201)'                 | '2.2'     | '5%'    | '1/16W'  | 'DISCRETE' | 'RES CHIP 2.2 1/16W +-5%  (0402)'                  | 'CHIP0402'     | ''          | ''            | ''        
 '2.2'        | '5%'      | '1/16W'  | '0402LF'  | 'EMPTY'  | 'TMP_QCS-2202JB25'(!)   = 'End of Design' | 'Comp-Approve'     | 'CS-2202JB25'           |'R0402'| '(R0402-0201)'                 | '2.2'     | '5%'    | '1/16W'  | 'IO'       | 'RES CHIP 2.2 1/16W +-5%  (0402)'                  | 'CHIP0402'     | ''          | ''            | ''        
 '2.2K'       | '1%'      | '1/16W'  | '0402LF'  | 'CHIP'   | 'TMP_QCS22202FB08'(!)   = 'End of Design' | 'Comp-Approve'     | 'CS22202FB08'           |'R0402'| '(R0402-0201)'                 | '2.2K'    | '1%'    | '1/16W'  | 'DISCRETE' | 'RES CHIP 2.2K 1/16W +-1%(0402)'                   | 'CHIP0402'     | ''          | ''            | ''        
 '2.2K'       | '1%'      | '1/16W'  | '0402LF'  | 'EMPTY'  | 'TMP_QCS22202FB08'(!)   = 'End of Design' | 'Comp-Approve'     | 'CS22202FB08'           |'R0402'| '(R0402-0201)'                 | '2.2K'    | '1%'    | '1/16W'  | 'IO'       | 'RES CHIP 2.2K 1/16W +-1%(0402)'                   | 'CHIP0402'     | ''          | ''            | ''        
 '2.26K'      | '1%'      | '1/16W'  | '0402LF'  | 'CHIP'   | 'TMP_QCS22262FB05'(!)   = 'End of Design' | 'Comp-Approve'     | 'CS22262FB05'           |'R0402'| '(R0402-0201)'                 | '2.26K'   | '1%'    | '1/16W'  | 'DISCRETE' | 'RES CHIP 2.26K 1/16W +-1%(0402)'                  | 'CHIP0402'     | ''          | ''            | ''        
 '2.26K'      | '1%'      | '1/16W'  | '0402LF'  | 'EMPTY'  | 'TMP_QCS22262FB05'(!)   = 'End of Design' | 'Comp-Approve'     | 'CS22262FB05'           |'R0402'| '(R0402-0201)'                 | '2.26K'   | '1%'    | '1/16W'  | 'IO'       | 'RES CHIP 2.26K 1/16W +-1%(0402)'                  | 'CHIP0402'     | ''          | ''            | ''        
 '2.8K'       | '1%'      | '1/16W'  | '0402LF'  | 'CHIP'   | 'TMP_QCS22802FB00'(!)   = ''              | ''                 | 'CS22802FB00'           |'R0402'| '(R0402-0201)'                 | '2.8K'    | '1%'    | '1/16W'  | 'DISCRETE' | 'RES CHIP 2.8K 1/16W +-1%(0402)'                   | 'CHIP0402'     | ''          | ''            | ''        
 '2.8K'       | '1%'      | '1/16W'  | '0402LF'  | 'EMPTY'  | 'TMP_QCS22802FB00'(!)   = ''              | ''                 | 'CS22802FB00'           |'R0402'| '(R0402-0201)'                 | '2.8K'    | '1%'    | '1/16W'  | 'IO'       | 'RES CHIP 2.8K 1/16W +-1%(0402)'                   | 'CHIP0402'     | ''          | ''            | ''        
 '3.3K'       | '1%'      | '1/16W'  | '0402LF'  | 'CHIP'   | 'TMP_QCS23302FB12'(!)   = 'End of Design' | 'Comp-Approve'     | 'CS23302FB12'           |'R0402'| '(R0402-0201)'                 | '3.3K'    | '1%'    | '1/16W'  | 'DISCRETE' | 'RES CHIP 3.3K 1/16W +-1%(0402)'                   | 'CHIP0402'     | ''          | ''            | ''        
 '3.3K'       | '1%'      | '1/16W'  | '0402LF'  | 'EMPTY'  | 'TMP_QCS23302FB12'(!)   = 'End of Design' | 'Comp-Approve'     | 'CS23302FB12'           |'R0402'| '(R0402-0201)'                 | '3.3K'    | '1%'    | '1/16W'  | 'IO'       | 'RES CHIP 3.3K 1/16W +-1%(0402)'                   | 'CHIP0402'     | ''          | ''            | ''        
 '5.1K'       | '1%'      | '1/16W'  | '0402LF'  | 'CHIP'   | 'TMP_QCS25102FB02'(!)   = 'End of Design' | 'Comp-Approve'     | 'CS25102FB02'           |'R0402'| '(R0402-0201)'                 | '5.1K'    | '1%'    | '1/16W'  | 'DISCRETE' | 'RES CHIP 5.1K 1/16W +-1%(0402)'                   | 'CHIP0402'     | ''          | ''            | ''        
 '5.1K'       | '1%'      | '1/16W'  | '0402LF'  | 'EMPTY'  | 'TMP_QCS25102FB02'(!)   = 'End of Design' | 'Comp-Approve'     | 'CS25102FB02'           |'R0402'| '(R0402-0201)'                 | '5.1K'    | '1%'    | '1/16W'  | 'IO'       | 'RES CHIP 5.1K 1/16W +-1%(0402)'                   | 'CHIP0402'     | ''          | ''            | ''        
 '5.11K'      | '1%'      | '1/16W'  | '0402LF'  | 'CHIP'   | 'TMP_QCS25112FB15'(!)   = 'End of Design' | 'Comp-Approve'     | 'CS25112FB15'           |'R0402'| '(R0402-0201)'                 | '5.11K'   | '1%'    | '1/16W'  | 'DISCRETE' | 'RES CHIP 5.11K 1/16W +-1%(0402)'                  | 'CHIP0402'     | ''          | ''            | ''        
 '5.11K'      | '1%'      | '1/16W'  | '0402LF'  | 'EMPTY'  | 'TMP_QCS25112FB15'(!)   = 'End of Design' | 'Comp-Approve'     | 'CS25112FB15'           |'R0402'| '(R0402-0201)'                 | '5.11K'   | '1%'    | '1/16W'  | 'IO'       | 'RES CHIP 5.11K 1/16W +-1%(0402)'                  | 'CHIP0402'     | ''          | ''            | ''        
 '7.15K'      | '1%'      | '1/16W'  | '0402LF'  | 'CHIP'   | 'TMP_QCS27152FB19'(!)   = ''              | ''                 | 'CS27152FB19'           |'R0402'| '(R0402-0201)'                 | '7.15K'   | '1%'    | '1/16W'  | 'DISCRETE' | 'RES CHIP 7.15K 1/16W +-1% (0402)'                 | 'CHIP0402'     | ''          | ''            | ''        
 '7.15K'      | '1%'      | '1/16W'  | '0402LF'  | 'EMPTY'  | 'TMP_QCS27152FB19'(!)   = ''              | ''                 | 'CS27152FB19'           |'R0402'| '(R0402-0201)'                 | '7.15K'   | '1%'    | '1/16W'  | 'IO'       | 'RES CHIP 7.15K 1/16W +-1% (0402)'                 | 'CHIP0402'     | ''          | ''            | ''        
 '11.3K'      | '1%'      | '1/16W'  | '0402LF'  | 'CHIP'   | 'TMP_QCS31132FB07'(!)   = 'End of Design' | 'Comp-Approve'     | 'CS31132FB07'           |'R0402'| '(R0402-0201)'                 | '11.3K'   | '1%'    | '1/16W'  | 'DISCRETE' | 'RES CHIP 11.3K 1/16W +-1%(0402)'                  | 'CHIP0402'     | ''          | ''            | ''        
 '11.3K'      | '1%'      | '1/16W'  | '0402LF'  | 'EMPTY'  | 'TMP_QCS31132FB07'(!)   = 'End of Design' | 'Comp-Approve'     | 'CS31132FB07'           |'R0402'| '(R0402-0201)'                 | '11.3K'   | '1%'    | '1/16W'  | 'IO'       | 'RES CHIP 11.3K 1/16W +-1%(0402)'                  | 'CHIP0402'     | ''          | ''            | ''        
 '13K'        | '1%'      | '1/16W'  | '0402LF'  | 'CHIP'   | 'TMP_QCS31302FB19'(!)   = 'End of Design' | 'Comp-Approve'     | 'CS31302FB19'           |'R0402'| '(R0402-0201)'                 | '13K'     | '1%'    | '1/16W'  | 'DISCRETE' | 'RES CHIP 13K 1/16W +-1%( 0402)'                   | 'CHIP0402'     | ''          | ''            | ''        
 '13K'        | '1%'      | '1/16W'  | '0402LF'  | 'EMPTY'  | 'TMP_QCS31302FB19'(!)   = 'End of Design' | 'Comp-Approve'     | 'CS31302FB19'           |'R0402'| '(R0402-0201)'                 | '13K'     | '1%'    | '1/16W'  | 'IO'       | 'RES CHIP 13K 1/16W +-1%( 0402)'                   | 'CHIP0402'     | ''          | ''            | ''        
 '18.2K'      | '1%'      | '1/16W'  | '0402LF'  | 'CHIP'   | 'TMP_QCS31822FB16'(!)   = 'End of Design' | 'Comp-Approve'     | 'CS31822FB16'           |'R0402'| '(R0402-0201)'                 | '18.2K'   | '1%'    | '1/16W'  | 'DISCRETE' | 'RES CHIP 18.2K 1/16W +-1%( 0402)'                 | 'CHIP0402'     | ''          | ''            | ''        
 '18.2K'      | '1%'      | '1/16W'  | '0402LF'  | 'EMPTY'  | 'TMP_QCS31822FB16'(!)   = 'End of Design' | 'Comp-Approve'     | 'CS31822FB16'           |'R0402'| '(R0402-0201)'                 | '18.2K'   | '1%'    | '1/16W'  | 'IO'       | 'RES CHIP 18.2K 1/16W +-1%( 0402)'                 | 'CHIP0402'     | ''          | ''            | ''        
 '20K'        | '5%'      | '1/16W'  | '0402LF'  | 'CHIP'   | 'TMP_QCS32002JB12'(!)   = 'End of Design' | 'Comp-Approve'     | 'CS32002JB12'           |'R0402'| '(R0402-0201)'                 | '20K'     | '5%'    | '1/16W'  | 'DISCRETE' | 'RES CHIP 20K 1/16W +-5% (0402)'                   | 'CHIP0402'     | ''          | ''            | ''        
 '20K'        | '5%'      | '1/16W'  | '0402LF'  | 'EMPTY'  | 'TMP_QCS32002JB12'(!)   = 'End of Design' | 'Comp-Approve'     | 'CS32002JB12'           |'R0402'| '(R0402-0201)'                 | '20K'     | '5%'    | '1/16W'  | 'IO'       | 'RES CHIP 20K 1/16W +-5% (0402)'                   | 'CHIP0402'     | ''          | ''            | ''        
 '61.9K'      | '1%'      | '1/16W'  | '0402LF'  | 'CHIP'   | 'TMP_QCS36192FB16'(!)   = 'End of Design' | 'Comp-Approve'     | 'CS36192FB16'           |'R0402'| '(R0402-0201)'                 | '61.9K'   | '1%'    | '1/16W'  | 'DISCRETE' | 'RES CHIP 61.9K 1/16W +-1%(0402)'                  | 'CHIP0402'     | ''          | ''            | ''        
 '61.9K'      | '1%'      | '1/16W'  | '0402LF'  | 'EMPTY'  | 'TMP_QCS36192FB16'(!)   = 'End of Design' | 'Comp-Approve'     | 'CS36192FB16'           |'R0402'| '(R0402-0201)'                 | '61.9K'   | '1%'    | '1/16W'  | 'IO'       | 'RES CHIP 61.9K 1/16W +-1%(0402)'                  | 'CHIP0402'     | ''          | ''            | ''        
 '68.1K'      | '1%'      | '1/16W'  | '0402LF'  | 'CHIP'   | 'TMP_QCS36812FB15'(!)   = 'End of Design' | 'Comp-Approve'     | 'CS36812FB15'           |'R0402'| '(R0402-0201)'                 | '68.1K'   | '1%'    | '1/16W'  | 'DISCRETE' | 'RES CHIP 68.1K 1/16W +-1%(0402)'                  | 'CHIP0402'     | ''          | ''            | ''        
 '68.1K'      | '1%'      | '1/16W'  | '0402LF'  | 'EMPTY'  | 'TMP_QCS36812FB15'(!)   = 'End of Design' | 'Comp-Approve'     | 'CS36812FB15'           |'R0402'| '(R0402-0201)'                 | '68.1K'   | '1%'    | '1/16W'  | 'IO'       | 'RES CHIP 68.1K 1/16W +-1%(0402)'                  | 'CHIP0402'     | ''          | ''            | ''        
 '150K'       | '1%'      | '1/16W'  | '0402LF'  | 'CHIP'   | 'TMP_QCS41502FB18'(!)   = 'End of Design' | 'Comp-Approve'     | 'CS41502FB18'           |'R0402'| '(R0402-0201)'                 | '150K'    | '1%'    | '1/16W'  | 'DISCRETE' | 'RES CHIP 150K 1/16W +-1%(0402)'                   | 'CHIP0402'     | ''          | ''            | ''        
 '150K'       | '1%'      | '1/16W'  | '0402LF'  | 'EMPTY'  | 'TMP_QCS41502FB18'(!)   = 'End of Design' | 'Comp-Approve'     | 'CS41502FB18'           |'R0402'| '(R0402-0201)'                 | '150K'    | '1%'    | '1/16W'  | 'IO'       | 'RES CHIP 150K 1/16W +-1%(0402)'                   | 'CHIP0402'     | ''          | ''            | ''        
 '147K'       | '0.1%'    | '1/16W'  | '0402LF'  | 'CHIP'   | 'TMP_QCS41472BB00'(!)   = ''              | ''                 | 'CS41472BB00'           |'R0402'| '(R0402-0201)'                 | '147K'    | '0.1%'  | '1/16W'  | 'DISCRETE' | 'RES CHIP 147K 1/16W +-0.1% (0402)'                | 'CHIP0402'     | ''          | ''            | ''        
 '147K'       | '0.1%'    | '1/16W'  | '0402LF'  | 'EMPTY'  | 'TMP_QCS41472BB00'(!)   = ''              | ''                 | 'CS41472BB00'           |'R0402'| '(R0402-0201)'                 | '147K'    | '0.1%'  | '1/16W'  | 'IO'       | 'RES CHIP 147K 1/16W +-0.1% (0402)'                | 'CHIP0402'     | ''          | ''            | ''        
 '7.15K'      | '0.1%'    | '1/16W'  | '0402LF'  | 'CHIP'   | 'TMP_QCS27152BB00'(!)   = ''              | ''                 | 'CS27152BB00'           |'R0402'| '(R0402-0201)'                 | '7.15K'   | '0.1%'  | '1/16W'  | 'DISCRETE' | 'RES CHIP 7.15K 1/16W +-0.1% (0402)'               | 'CHIP0402'     | ''          | ''            | ''        
 '7.15K'      | '0.1%'    | '1/16W'  | '0402LF'  | 'EMPTY'  | 'TMP_QCS27152BB00'(!)   = ''              | ''                 | 'CS27152BB00'           |'R0402'| '(R0402-0201)'                 | '7.15K'   | '0.1%'  | '1/16W'  | 'IO'       | 'RES CHIP 7.15K 1/16W +-0.1% (0402)'               | 'CHIP0402'     | ''          | ''            | ''        
 '140K'       | '0.1%'    | '1/16W'  | '0402LF'  | 'CHIP'   | 'TMP_QCS41402BB00'(!)   = ''              | ''                 | 'CS41402BB00'           |'R0402'| '(R0402-0201)'                 | '140K'    | '0.1%'  | '1/16W'  | 'DISCRETE' | 'RES CHIP 140K 1/16W +-0.1% (0402)'                | 'CHIP0402'     | ''          | ''            | ''        
 '140K'       | '0.1%'    | '1/16W'  | '0402LF'  | 'EMPTY'  | 'TMP_QCS41402BB00'(!)   = ''              | ''                 | 'CS41402BB00'           |'R0402'| '(R0402-0201)'                 | '140K'    | '0.1%'  | '1/16W'  | 'IO'       | 'RES CHIP 140K 1/16W +-0.1% (0402)'                | 'CHIP0402'     | ''          | ''            | ''        
 '330'        | '1%'      | '1/16W'  | '0402LF'  | 'CHIP'   | 'TMP_QCS13302FB11'(!)   = 'End of Design' | 'Comp-Approve'     | 'CS13302FB11'           |'R0402'| '(R0402-0201)'                 | '330'     | '1%'    | '1/16W'  | 'DISCRETE' | 'RES CHIP 330 1/16W +-1%(0402)'                    | 'CHIP0402'     | ''          | ''            | ''        
 '330'        | '1%'      | '1/16W'  | '0402LF'  | 'EMPTY'  | 'TMP_QCS13302FB11'(!)   = 'End of Design' | 'Comp-Approve'     | 'CS13302FB11'           |'R0402'| '(R0402-0201)'                 | '330'     | '1%'    | '1/16W'  | 'IO'       | 'RES CHIP 330 1/16W +-1%(0402)'                    | 'CHIP0402'     | ''          | ''            | ''        
 '220'        | '1%'      | '1/16W'  | '0402LF'  | 'CHIP'   | 'TMP_QCS12202FB14'(!)   = 'End of Design' | 'Comp-Approve'     | 'CS12202FB14'           |'R0402'| '(R0402-0201)'                 | '220'     | '1%'    | '1/16W'  | 'DISCRETE' | 'RES CHIP 220 1/16W +-1%(0402)'                    | 'CHIP0402'     | ''          | ''            | ''        
 '220'        | '1%'      | '1/16W'  | '0402LF'  | 'EMPTY'  | 'TMP_QCS12202FB14'(!)   = 'End of Design' | 'Comp-Approve'     | 'CS12202FB14'           |'R0402'| '(R0402-0201)'                 | '220'     | '1%'    | '1/16W'  | 'IO'       | 'RES CHIP 220 1/16W +-1%(0402)'                    | 'CHIP0402'     | ''          | ''            | ''        
 '5.76K'      | '1%'      | '1/16W'  | '0402LF'  | 'CHIP'   | 'TMP_QCS25762FB01'(!)   = 'End of Design' | 'Comp-Approve'     | 'CS25762FB01'           |'R0402'| '(R0402-0201)'                 | '5.76K'   | '1%'    | '1/16W'  | 'DISCRETE' | 'RES CHIP 5.76K 1/16W +-1%(0402)'                  | 'CHIP0402'     | ''          | ''            | ''        
 '5.76K'      | '1%'      | '1/16W'  | '0402LF'  | 'EMPTY'  | 'TMP_QCS25762FB01'(!)   = 'End of Design' | 'Comp-Approve'     | 'CS25762FB01'           |'R0402'| '(R0402-0201)'                 | '5.76K'   | '1%'    | '1/16W'  | 'IO'       | 'RES CHIP 5.76K 1/16W +-1%(0402)'                  | 'CHIP0402'     | ''          | ''            | ''        
 '3.74K'      | '1%'      | '1/16W'  | '0402LF'  | 'CHIP'   | 'TMP_QCS23742FB00'(!)   = 'End of Design' | 'Comp-Approve'     | 'CS23742FB00'           |'R0402'| '(R0402-0201)'                 | '3.74K'   | '1%'    | '1/16W'  | 'DISCRETE' | 'RES CHIP 3.74K 1/16W +-1%(0402)'                  | 'CHIP0402'     | ''          | ''            | ''        
 '3.74K'      | '1%'      | '1/16W'  | '0402LF'  | 'EMPTY'  | 'TMP_QCS23742FB00'(!)   = 'End of Design' | 'Comp-Approve'     | 'CS23742FB00'           |'R0402'| '(R0402-0201)'                 | '3.74K'   | '1%'    | '1/16W'  | 'IO'       | 'RES CHIP 3.74K 1/16W +-1%(0402)'                  | 'CHIP0402'     | ''          | ''            | ''        
 '12.7K'      | '1%'      | '1/16W'  | '0402LF'  | 'CHIP'   | 'TMP_QCS31272FB17'(!)   = 'End of Design' | 'Comp-Approve'     | 'CS31272FB17'           |'R0402'| '(R0402-0201)'                 | '12.7K'   | '1%'    | '1/16W'  | 'DISCRETE' | 'RES CHIP 12.7K 1/16W +-1% (0402)'                 | 'CHIP0402'     | ''          | ''            | ''        
 '12.7K'      | '1%'      | '1/16W'  | '0402LF'  | 'EMPTY'  | 'TMP_QCS31272FB17'(!)   = 'End of Design' | 'Comp-Approve'     | 'CS31272FB17'           |'R0402'| '(R0402-0201)'                 | '12.7K'   | '1%'    | '1/16W'  | 'IO'       | 'RES CHIP 12.7K 1/16W +-1% (0402)'                 | 'CHIP0402'     | ''          | ''            | ''        
 '31.6K'      | '1%'      | '1/16W'  | '0402LF'  | 'CHIP'   | 'TMP_QCS33162FB14'(!)   = 'End of Design' | 'Comp-Approve'     | 'CS33162FB14'           |'R0402'| '(R0402-0201)'                 | '31.6K'   | '1%'    | '1/16W'  | 'DISCRETE' | 'RES CHIP 31.6K 1/16W +-1%(0402)'                  | 'CHIP0402'     | ''          | ''            | ''        
 '31.6K'      | '1%'      | '1/16W'  | '0402LF'  | 'EMPTY'  | 'TMP_QCS33162FB14'(!)   = 'End of Design' | 'Comp-Approve'     | 'CS33162FB14'           |'R0402'| '(R0402-0201)'                 | '31.6K'   | '1%'    | '1/16W'  | 'IO'       | 'RES CHIP 31.6K 1/16W +-1%(0402)'                  | 'CHIP0402'     | ''          | ''            | ''        
 '54.9K'      | '1%'      | '1/16W'  | '0402LF'  | 'CHIP'   | 'TMP_QCS35492FB14'(!)   = 'End of Design' | 'Comp-Approve'     | 'CS35492FB14'           |'R0402'| '(R0402-0201)'                 | '54.9K'   | '1%'    | '1/16W'  | 'DISCRETE' | 'RES CHIP 54.9K 1/16W +-1%(0402)'                  | 'CHIP0402'     | ''          | ''            | ''        
 '54.9K'      | '1%'      | '1/16W'  | '0402LF'  | 'EMPTY'  | 'TMP_QCS35492FB14'(!)   = 'End of Design' | 'Comp-Approve'     | 'CS35492FB14'           |'R0402'| '(R0402-0201)'                 | '54.9K'   | '1%'    | '1/16W'  | 'IO'       | 'RES CHIP 54.9K 1/16W +-1%(0402)'                  | 'CHIP0402'     | ''          | ''            | ''        
 '8.87K'      | '1%'      | '1/16W'  | '0402LF'  | 'CHIP'   | 'TMP_QCS28872FB08'(!)   = 'End of Design' | 'Comp-Approve'     | 'CS28872FB08'           |'R0402'| '(R0402-0201)'                 | '8.87K'   | '1%'    | '1/16W'  | 'DISCRETE' | 'RES CHIP 8.87K 1/16W +-1%(0402)'                  | 'CHIP0402'     | ''          | ''            | ''        
 '8.87K'      | '1%'      | '1/16W'  | '0402LF'  | 'EMPTY'  | 'TMP_QCS28872FB08'(!)   = 'End of Design' | 'Comp-Approve'     | 'CS28872FB08'           |'R0402'| '(R0402-0201)'                 | '8.87K'   | '1%'    | '1/16W'  | 'IO'       | 'RES CHIP 8.87K 1/16W +-1%(0402)'                  | 'CHIP0402'     | ''          | ''            | ''        
 '2.67K'      | '1%'      | '1/16W'  | '0402LF'  | 'CHIP'   | 'TMP_QCS22672FB12'(!)   = 'End of Design' | 'Comp-Approve'     | 'CS22672FB12'           |'R0402'| '(R0402-0201)'                 | '2.67K'   | '1%'    | '1/16W'  | 'DISCRETE' | 'RES CHIP 2.67K 1/16W +-1%(0402) '                 | 'CHIP0402'     | ''          | ''            | ''        
 '2.67K'      | '1%'      | '1/16W'  | '0402LF'  | 'EMPTY'  | 'TMP_QCS22672FB12'(!)   = 'End of Design' | 'Comp-Approve'     | 'CS22672FB12'           |'R0402'| '(R0402-0201)'                 | '2.67K'   | '1%'    | '1/16W'  | 'IO'       | 'RES CHIP 2.67K 1/16W +-1%(0402) '                 | 'CHIP0402'     | ''          | ''            | ''        
 '5.36K'      | '1%'      | '1/16W'  | '0402LF'  | 'CHIP'   | 'TMP_QCS25362FB15'(!)   = 'End of Design' | 'Comp-Approve'     | 'CS25362FB15'           |'R0402'| '(R0402-0201)'                 | '5.36K'   | '1%'    | '1/16W'  | 'DISCRETE' | 'RES CHIP 5.36K 1/16W +-1%(0402) '                 | 'CHIP0402'     | ''          | ''            | ''        
 '5.36K'      | '1%'      | '1/16W'  | '0402LF'  | 'EMPTY'  | 'TMP_QCS25362FB15'(!)   = 'End of Design' | 'Comp-Approve'     | 'CS25362FB15'           |'R0402'| '(R0402-0201)'                 | '5.36K'   | '1%'    | '1/16W'  | 'IO'       | 'RES CHIP 5.36K 1/16W +-1%(0402) '                 | 'CHIP0402'     | ''          | ''            | ''        
 '390K'       | '1%'      | '1/16W'  | '0402LF'  | 'CHIP'   | 'TMP_QCS43902FB00'(!)   = 'End of Design' | 'Comp-Approve'     | 'CS43902FB00'           |'R0402'| '(R0402-0201)'                 | '390K'    | '1%'    | '1/16W'  | 'DISCRETE' | 'RES CHIP 390K 1/16W +-1%(0402)'                   | 'CHIP0402'     | ''          | ''            | ''        
 '390K'       | '1%'      | '1/16W'  | '0402LF'  | 'EMPTY'  | 'TMP_QCS43902FB00'(!)   = 'End of Design' | 'Comp-Approve'     | 'CS43902FB00'           |'R0402'| '(R0402-0201)'                 | '390K'    | '1%'    | '1/16W'  | 'IO'       | 'RES CHIP 390K 1/16W +-1%(0402)'                   | 'CHIP0402'     | ''          | ''            | ''        
 '100K'       | '1%'      | '1/16W'  | '0402LF'  | 'CHIP'   | 'TMP_QCS41002FB28'(!)   = 'End of Design' | 'Comp-Approve'     | 'CS41002FB28'           |'R0402'| '(R0402-0201)'                 | '100K'    | '1%'    | '1/16W'  | 'DISCRETE' | 'RES CHIP 100K 1/16W +-1% (0402)'                  | 'CHIP0402'     | ''          | ''            | ''        
 '100K'       | '1%'      | '1/16W'  | '0402LF'  | 'EMPTY'  | 'TMP_QCS41002FB28'(!)   = 'End of Design' | 'Comp-Approve'     | 'CS41002FB28'           |'R0402'| '(R0402-0201)'                 | '100K'    | '1%'    | '1/16W'  | 'IO'       | 'RES CHIP 100K 1/16W +-1% (0402)'                  | 'CHIP0402'     | ''          | ''            | ''        
 '110K'       | '1%'      | '1/16W'  | '0402LF'  | 'CHIP'   | 'TMP_QCS41102FB13'(!)   = 'End of Design' | 'Comp-Approve'     | 'CS41102FB13'           |'R0402'| '(R0402-0201)'                 | '110K'    | '1%'    | '1/16W'  | 'DISCRETE' | 'RES CHIP 110K 1/16W +-1%(0402)'                   | 'CHIP0402'     | ''          | ''            | ''        
 '110K'       | '1%'      | '1/16W'  | '0402LF'  | 'EMPTY'  | 'TMP_QCS41102FB13'(!)   = 'End of Design' | 'Comp-Approve'     | 'CS41102FB13'           |'R0402'| '(R0402-0201)'                 | '110K'    | '1%'    | '1/16W'  | 'IO'       | 'RES CHIP 110K 1/16W +-1%(0402)'                   | 'CHIP0402'     | ''          | ''            | ''        
 '10'         | '5%'      | '1/16W'  | '0402LF'  | 'CHIP'   | 'TMP_QCS01002JB22'(!)   = 'End of Design' | 'Comp-Approve'     | 'CS01002JB22'           |'R0402'| '(R0402-0201)'                 | '10'      | '5%'    | '1/16W'  | 'DISCRETE' | 'RES CHIP 10 1/16W +-5%(0402)'                     | 'CHIP0402'     | ''          | ''            | ''        
 '10'         | '5%'      | '1/16W'  | '0402LF'  | 'EMPTY'  | 'TMP_QCS01002JB22'(!)   = 'End of Design' | 'Comp-Approve'     | 'CS01002JB22'           |'R0402'| '(R0402-0201)'                 | '10'      | '5%'    | '1/16W'  | 'IO'       | 'RES CHIP 10 1/16W +-5%(0402)'                     | 'CHIP0402'     | ''          | ''            | ''        
 '20K'        | '5%'      | '1/16W'  | '0402LF'  | 'CHIP'   | 'TMP_QCS32002JB04'(!)   = ''              | ''                 | 'CS32002JB04'           |'R0402'| '(R0402-0201)'                 | '20K'     | '5%'    | '1/16W'  | 'DISCRETE' | 'RES CHIP 20K 1/16W +-5% (0402)'                   | 'CHIP0402'     | ''          | ''            | ''        
 '20K'        | '5%'      | '1/16W'  | '0402LF'  | 'EMPTY'  | 'TMP_QCS32002JB04'(!)   = ''              | ''                 | 'CS32002JB04'           |'R0402'| '(R0402-0201)'                 | '20K'     | '5%'    | '1/16W'  | 'IO'       | 'RES CHIP 20K 1/16W +-5% (0402)'                   | 'CHIP0402'     | ''          | ''            | ''        
 '56'         | '5%'      | '1/16W'  | '0402LF'  | 'CHIP'   | 'TMP_QCS05602JB17'(!)   = 'End of Design' | 'Comp-Approve'     | 'CS05602JB17'           |'R0402'| '(R0402-0201)'                 | '56'      | '5%'    | '1/16W'  | 'DISCRETE' | 'RES CHIP 56 1/16W +-5% (0402)'                    | 'CHIP0402'     | ''          | ''            | '20100527'
 '56'         | '5%'      | '1/16W'  | '0402LF'  | 'EMPTY'  | 'TMP_QCS05602JB17'(!)   = 'End of Design' | 'Comp-Approve'     | 'CS05602JB17'           |'R0402'| '(R0402-0201)'                 | '56'      | '5%'    | '1/16W'  | 'IO'       | 'RES CHIP 56 1/16W +-5% (0402)'                    | 'CHIP0402'     | ''          | ''            | '20100527'
 '20'         | '1%'      | '1/16W'  | '0402LF'  | 'CHIP'   | 'TMP_QCS02002FB23'(!)   = 'End of Design' | 'Comp-Approve'     | 'CS02002FB23'           |'R0402'| '(R0402-0201)'                 | '20'      | '1%'    | '1/16W'  | 'DISCRETE' | 'RES CHIP 20 1/16W +-1% (0402)'                    | 'CHIP0402'     | ''          | ''            | '20100601'
 '20'         | '1%'      | '1/16W'  | '0402LF'  | 'EMPTY'  | 'TMP_QCS02002FB23'(!)   = 'End of Design' | 'Comp-Approve'     | 'CS02002FB23'           |'R0402'| '(R0402-0201)'                 | '20'      | '1%'    | '1/16W'  | 'IO'       | 'RES CHIP 20 1/16W +-1% (0402)'                    | 'CHIP0402'     | ''          | ''            | '20100601'
 '4.02K'      | '1%'      | '1/16W'  | '0402LF'  | 'CHIP'   | 'TMP_QCS24022FB05'(!)   = ''              | ''                 | 'CS24022FB05'           |'R0402'| '(R0402-0201)'                 | '4.02K'   | '1%'    | '1/16W'  | 'DISCRETE' | 'RES CHIP 4.02K 1/16W +-1%(0402)'                  | 'CHIP0402'     | ''          | ''            | '20100601'
 '4.02K'      | '1%'      | '1/16W'  | '0402LF'  | 'EMPTY'  | 'TMP_QCS24022FB05'(!)   = ''              | ''                 | 'CS24022FB05'           |'R0402'| '(R0402-0201)'                 | '4.02K'   | '1%'    | '1/16W'  | 'IO'       | 'RES CHIP 4.02K 1/16W +-1%(0402)'                  | 'CHIP0402'     | ''          | ''            | '20100601'
 '21.5K'      | '1%'      | '1/16W'  | '0402LF'  | 'CHIP'   | 'TMP_QCS32152FB17'(!)   = 'End of Design' | 'Comp-Approve'     | 'CS32152FB17'           |'R0402'| '(R0402-0201)'                 | '21.5K'   | '1%'    | '1/16W'  | 'DISCRETE' | 'RES CHIP 21.5K 1/16W +-1%(0402)'                  | 'CHIP0402'     | ''          | ''            | '20100601'
 '21.5K'      | '1%'      | '1/16W'  | '0402LF'  | 'EMPTY'  | 'TMP_QCS32152FB17'(!)   = 'End of Design' | 'Comp-Approve'     | 'CS32152FB17'           |'R0402'| '(R0402-0201)'                 | '21.5K'   | '1%'    | '1/16W'  | 'IO'       | 'RES CHIP 21.5K 1/16W +-1%(0402)'                  | 'CHIP0402'     | ''          | ''            | '20100601'
 '1'          | '1%'      | '1/4W'   | '1206LF'  | 'CHIP'   | 'TMP_QCS-1006F209'(!)   = 'End of Design' | 'Comp-Approve'     | 'CS-1006F209'           |'R1206'| '(SMR1206AW)'                  | '1'       | '1%'    | '1/4W'   | 'DISCRETE' | 'RES CHIP 1 1/4W +-1%(1206)'                       | 'CHIP1206'     | ''          | ''            | '20100603'
 '1'          | '1%'      | '1/4W'   | '1206LF'  | 'EMPTY'  | 'TMP_QCS-1006F209'(!)   = 'End of Design' | 'Comp-Approve'     | 'CS-1006F209'           |'R1206'| '(SMR1206AW)'                  | '1'       | '1%'    | '1/4W'   | 'IO'       | 'RES CHIP 1 1/4W +-1%(1206)'                       | 'CHIP1206'     | ''          | ''            | '20100603'
 '2K'         | '5%'      | '1/16W'  | '0402LF'  | 'CHIP'   | 'TMP_QCS22002JB29'(!)   = 'End of Design' | 'Comp-Approve'     | 'CS22002JB29'           |'R0402'| '(R0402-0201)'                 | '2K'      | '5%'    | '1/16W'  | 'DISCRETE' | 'RES CHIP 2K(1/16W +-5% 0402)'                     | 'CHIP0402'     | ''          | ''            | '20100603'
 '2K'         | '5%'      | '1/16W'  | '0402LF'  | 'EMPTY'  | 'TMP_QCS22002JB29'(!)   = 'End of Design' | 'Comp-Approve'     | 'CS22002JB29'           |'R0402'| '(R0402-0201)'                 | '2K'      | '5%'    | '1/16W'  | 'IO'       | 'RES CHIP 2K(1/16W +-5% 0402)'                     | 'CHIP0402'     | ''          | ''            | '20100603'
 '430'        | '1%'      | '1/16W'  | '0402LF'  | 'CHIP'   | 'CS14302FB05'(!)        = 'End of Design' | 'Comp-Approve'     | 'CS14302FB05'           |'R0402'| '(R0402-0201)'                 | '430'     | '1%'    | '1/16W'  | 'DISCRETE' | 'RES CHIP 430 1/16W +-1%(0402)'                    | 'CHIP0402'     | ''          | ''            | '20100609'
 '430'        | '1%'      | '1/16W'  | '0402LF'  | 'EMPTY'  | 'CS14302FB05'(!)        = 'End of Design' | 'Comp-Approve'     | 'CS14302FB05'           |'R0402'| '(R0402-0201)'                 | '430'     | '1%'    | '1/16W'  | 'IO'       | 'RES CHIP 430 1/16W +-1%(0402)'                    | 'CHIP0402'     | ''          | ''            | '20100609'
 '422'        | '1%'      | '1/16W'  | '0402LF'  | 'CHIP'   | 'CS14222FB19'(!)        = 'End of Design' | 'Comp-Approve'     | 'CS14222FB19'           |'R0402'| '(R0402-0201)'                 | '422'     | '1%'    | '1/16W'  | 'DISCRETE' | 'RES CHIP 422 1/16W +-1% (0402)'                   | 'CHIP0402'     | ''          | ''            | '20100609'
 '422'        | '1%'      | '1/16W'  | '0402LF'  | 'EMPTY'  | 'CS14222FB19'(!)        = 'End of Design' | 'Comp-Approve'     | 'CS14222FB19'           |'R0402'| '(R0402-0201)'                 | '422'     | '1%'    | '1/16W'  | 'IO'       | 'RES CHIP 422 1/16W +-1% (0402)'                   | 'CHIP0402'     | ''          | ''            | '20100609'
 '120'        | '1%'      | '1/16W'  | '0402LF'  | 'CHIP'   | 'CS11202FB11'(!)        = 'End of Design' | 'Comp-Approve'     | 'CS11202FB11'           |'R0402'| '(R0402-0201)'                 | '120'     | '1%'    | '1/16W'  | 'DISCRETE' | 'RES CHIP 120 1/16W +-1%(0402)'                    | 'CHIP0402'     | ''          | ''            | '20100609'
 '120'        | '1%'      | '1/16W'  | '0402LF'  | 'EMPTY'  | 'CS11202FB11'(!)        = 'End of Design' | 'Comp-Approve'     | 'CS11202FB11'           |'R0402'| '(R0402-0201)'                 | '120'     | '1%'    | '1/16W'  | 'IO'       | 'RES CHIP 120 1/16W +-1%(0402)'                    | 'CHIP0402'     | ''          | ''            | '20100609'
 '866'        | '1%'      | '1/10W'  | '0603LF ' | 'CHIP'   | 'CS18663F919'(!)        = ''              | ''                 | 'CS18663F919'           |'R0603'| '(SMR0603AW)'                  | '866'     | '1%'    | '1/10W ' | 'DISCRETE' | 'RESISTER CHIP 866 1/10W +-1%(0603)'               | 'CHIP0603'     | ''          | ''            | '20100609'
 '866'        | '1%'      | '1/10W'  | '0603LF ' | 'EMPTY'  | 'CS18663F919'(!)        = ''              | ''                 | 'CS18663F919'           |'R0603'| '(SMR0603AW)'                  | '866'     | '1%'    | '1/10W ' | 'IO'       | 'RESISTER CHIP 866 1/10W +-1%(0603)'               | 'CHIP0603'     | ''          | ''            | '20100609'
 '1.74K'      | '1%'      | '1/16W'  | '0402LF'  | 'CHIP'   | 'CS21742FB00'(!)        = 'End of Design' | 'Comp-Approve'     | 'CS21742FB00'           |'R0402'| '(R0402-0201)'                 | '1.74K'   | '1%'    | '1/16W'  | 'DISCRETE' | 'RES CHIP 1.74K 1/16W +-1%(0402)'                  | 'CHIP0402'     | ''          | ''            | '20100610'
 '1.74K'      | '1%'      | '1/16W'  | '0402LF'  | 'EMPTY'  | 'CS21742FB00'(!)        = 'End of Design' | 'Comp-Approve'     | 'CS21742FB00'           |'R0402'| '(R0402-0201)'                 | '1.74K'   | '1%'    | '1/16W'  | 'IO'       | 'RES CHIP 1.74K 1/16W +-1%(0402)'                  | 'CHIP0402'     | ''          | ''            | '20100610'
 '3.48K'      | '1%'      | '1/16W'  | '0402LF'  | 'CHIP'   | 'CS23482FB12'(!)        = 'End of Design' | 'Comp-Approve'     | 'CS23482FB12'           |'R0402'| '(R0402-0201)'                 | '3.48K'   | '1%'    | '1/16W'  | 'DISCRETE' | 'RES CHIP 3.48K 1/16W +-1%( 0402)'                 | 'CHIP0402'     | ''          | ''            | '20100611'
 '3.48K'      | '1%'      | '1/16W'  | '0402LF'  | 'EMPTY'  | 'CS23482FB12'(!)        = 'End of Design' | 'Comp-Approve'     | 'CS23482FB12'           |'R0402'| '(R0402-0201)'                 | '3.48K'   | '1%'    | '1/16W'  | 'IO'       | 'RES CHIP 3.48K 1/16W +-1%( 0402)'                 | 'CHIP0402'     | ''          | ''            | '20100611'
 '154'        | '1%'      | '1/16W'  | '0402LF'  | 'CHIP'   | 'CS11542FB00'(!)        = 'End of Design' | 'Comp-Approve'     | 'CS11542FB00'           |'R0402'| '(R0402-0201)'                 | '154'     | '1%'    | '1/16W'  | 'DISCRETE' | 'RES CHIP 154 1/16W +-1%(0402)'                    | 'CHIP0402'     | ''          | ''            | '20100614'
 '154'        | '1%'      | '1/16W'  | '0402LF'  | 'EMPTY'  | 'CS11542FB00'(!)        = 'End of Design' | 'Comp-Approve'     | 'CS11542FB00'           |'R0402'| '(R0402-0201)'                 | '154'     | '1%'    | '1/16W'  | 'IO'       | 'RES CHIP 154 1/16W +-1%(0402)'                    | 'CHIP0402'     | ''          | ''            | '20100614'
 '402'        | '1%'      | '1/16W'  | '0402LF'  | 'CHIP'   | 'CS14022FB03'(!)        = ''              | ''                 | 'CS14022FB03'           |'R0402'| '(R0402-0201)'                 | '402'     | '1%'    | '1/16W'  | 'DISCRETE' | 'RES CHIP 402 1/16W +-1%(0402)'                    | 'CHIP0402'     | ''          | ''            | '20100614'
 '402'        | '1%'      | '1/16W'  | '0402LF'  | 'EMPTY'  | 'CS14022FB03'(!)        = ''              | ''                 | 'CS14022FB03'           |'R0402'| '(R0402-0201)'                 | '402'     | '1%'    | '1/16W'  | 'IO'       | 'RES CHIP 402 1/16W +-1%(0402)'                    | 'CHIP0402'     | ''          | ''            | '20100614'
 '2.15K'      | '1%'      | '1/16W'  | '0402LF'  | 'CHIP'   | 'CS22152FB07'(!)        = 'End of Design' | 'Comp-Approve'     | 'CS22152FB07'           |'R0402'| '(R0402-0201)'                 | '2.15K'   | '1%'    | '1/16W'  | 'DISCRETE' | 'RES CHIP 2.15K 1/16W +-1%(0402)'                  | 'CHIP0402'     | ''          | ''            | '20100614'
 '2.15K'      | '1%'      | '1/16W'  | '0402LF'  | 'EMPTY'  | 'CS22152FB07'(!)        = 'End of Design' | 'Comp-Approve'     | 'CS22152FB07'           |'R0402'| '(R0402-0201)'                 | '2.15K'   | '1%'    | '1/16W'  | 'IO'       | 'RES CHIP 2.15K 1/16W +-1%(0402)'                  | 'CHIP0402'     | ''          | ''            | '20100614'
 '3.57K'      | '1%'      | '1/16W'  | '0402LF'  | 'CHIP'   | 'CS23572FB11'(!)        = 'End of Design' | 'Comp-Approve'     | 'CS23572FB11'           |'R0402'| '(R0402-0201)'                 | '3.57K'   | '1%'    | '1/16W'  | 'DISCRETE' | 'RES CHIP 3.57K 1/16W +-1%(0402)'                  | 'CHIP0402'     | ''          | ''            | '20100614'
 '3.57K'      | '1%'      | '1/16W'  | '0402LF'  | 'EMPTY'  | 'CS23572FB11'(!)        = 'End of Design' | 'Comp-Approve'     | 'CS23572FB11'           |'R0402'| '(R0402-0201)'                 | '3.57K'   | '1%'    | '1/16W'  | 'IO'       | 'RES CHIP 3.57K 1/16W +-1%(0402)'                  | 'CHIP0402'     | ''          | ''            | '20100614'
 '3.92K'      | '1%'      | '1/16W'  | '0402LF'  | 'CHIP'   | 'CS23922FB13'(!)        = 'End of Design' | 'Comp-Approve'     | 'CS23922FB13'           |'R0402'| '(R0402-0201)'                 | '3.92K'   | '1%'    | '1/16W'  | 'DISCRETE' | 'RES CHIP 3.92K 1/16W +-1% (0402)'                 | 'CHIP0402'     | ''          | ''            | '20100614'
 '3.92K'      | '1%'      | '1/16W'  | '0402LF'  | 'EMPTY'  | 'CS23922FB13'(!)        = 'End of Design' | 'Comp-Approve'     | 'CS23922FB13'           |'R0402'| '(R0402-0201)'                 | '3.92K'   | '1%'    | '1/16W'  | 'IO'       | 'RES CHIP 3.92K 1/16W +-1% (0402)'                 | 'CHIP0402'     | ''          | ''            | '20100614'
 '1.5K'       | '1%'      | '1/16W'  | '0402LF'  | 'CHIP'   | 'CS21502FB14'(!)        = 'End of Design' | 'Comp-Release Qty' | 'CS21502FB14'           |'R0402'| '(R0402-0201)'                 | '1.5K'    | '1%'    | '1/16W'  | 'DISCRETE' | 'RES CHIP 1.5K 1/16W +-1% (0402)'                  | 'CHIP0402'     | ''          | ''            | '20100614'
 '1.5K'       | '1%'      | '1/16W'  | '0402LF'  | 'EMPTY'  | 'CS21502FB14'(!)        = 'End of Design' | 'Comp-Release Qty' | 'CS21502FB14'           |'R0402'| '(R0402-0201)'                 | '1.5K'    | '1%'    | '1/16W'  | 'IO'       | 'RES CHIP 1.5K 1/16W +-1% (0402)'                  | 'CHIP0402'     | ''          | ''            | '20100614'
 '261'        | '1%'      | '1/16W'  | '0402LF'  | 'CHIP'   | 'CS12612FB05'(!)        = ''              | ''                 | 'CS12612FB05'           |'R0402'| '(R0402-0201)'                 | '261'     | '1%'    | '1/16W'  | 'DISCRETE' | 'RES CHIP 261 1/16W +-1%(0402)'                    | 'CHIP0402'     | ''          | ''            | '20100614'
 '261'        | '1%'      | '1/16W'  | '0402LF'  | 'EMPTY'  | 'CS12612FB05'(!)        = ''              | ''                 | 'CS12612FB05'           |'R0402'| '(R0402-0201)'                 | '261'     | '1%'    | '1/16W'  | 'IO'       | 'RES CHIP 261 1/16W +-1%(0402)'                    | 'CHIP0402'     | ''          | ''            | '20100614'
 '20.5K'      | '1%'      | '1/16W'  | '0402LF'  | 'CHIP'   | 'CS32052FB21'(!)        = 'End of Design' | 'Comp-Approve'     | 'CS32052FB21'           |'R0402'| '(R0402-0201)'                 | '20.5K'   | '1%'    | '1/16W'  | 'DISCRETE' | 'RES CHIP 20.5K 1/16W +-1%(0402)'                  | 'CHIP0402'     | ''          | ''            | '20100615'
 '20.5K'      | '1%'      | '1/16W'  | '0402LF'  | 'EMPTY'  | 'CS32052FB21'(!)        = 'End of Design' | 'Comp-Approve'     | 'CS32052FB21'           |'R0402'| '(R0402-0201)'                 | '20.5K'   | '1%'    | '1/16W'  | 'IO'       | 'RES CHIP 20.5K 1/16W +-1%(0402)'                  | 'CHIP0402'     | ''          | ''            | '20100615'
 '34K'        | '1%'      | '1/16W'  | '0402LF'  | 'CHIP'   | 'CS33402FB18'(!)        = 'End of Design' | 'Comp-Approve'     | 'CS33402FB18'           |'R0402'| '(R0402-0201)'                 | '34K'     | '1%'    | '1/16W'  | 'DISCRETE' | 'RES CHIP 34K 1/16W +-1% (0402)'                   | 'CHIP0402'     | ''          | ''            | '20100615'
 '34K'        | '1%'      | '1/16W'  | '0402LF'  | 'EMPTY'  | 'CS33402FB18'(!)        = 'End of Design' | 'Comp-Approve'     | 'CS33402FB18'           |'R0402'| '(R0402-0201)'                 | '34K'     | '1%'    | '1/16W'  | 'IO'       | 'RES CHIP 34K 1/16W +-1% (0402)'                   | 'CHIP0402'     | ''          | ''            | '20100615'
 '8.66K'      | '1%'      | '1/16W'  | '0402LF'  | 'CHIP'   | 'CS28662FB14'(!)        = 'End of Design' | 'Comp-Approve'     | 'CS28662FB14'           |'R0402'| '(R0402-0201)'                 | '8.66K'   | '1%'    | '1/16W'  | 'DISCRETE' | 'RES CHIP 8.66K 1/16W +-1%(0402)'                  | 'CHIP0402'     | ''          | ''            | '20100615'
 '8.66K'      | '1%'      | '1/16W'  | '0402LF'  | 'EMPTY'  | 'CS28662FB14'(!)        = 'End of Design' | 'Comp-Approve'     | 'CS28662FB14'           |'R0402'| '(R0402-0201)'                 | '8.66K'   | '1%'    | '1/16W'  | 'IO'       | 'RES CHIP 8.66K 1/16W +-1%(0402)'                  | 'CHIP0402'     | ''          | ''            | '20100615'
 '54.9'       | '1%'      | '1/16W'  | '0402LF'  | 'CHIP'   | 'CS05492FB19'(!)        = 'End of Design' | 'Comp-Approve'     | 'CS05492FB19'           |'R0402'| '(R0402-0201)'                 | '54.9'    | '1%'    | '1/16W'  | 'DISCRETE' | 'RES CHIP 54.9 1/16W +-1%(0402)'                   | 'CHIP0402'     | ''          | ''            | '20100617'
 '54.9'       | '1%'      | '1/16W'  | '0402LF'  | 'EMPTY'  | 'CS05492FB19'(!)        = 'End of Design' | 'Comp-Approve'     | 'CS05492FB19'           |'R0402'| '(R0402-0201)'                 | '54.9'    | '1%'    | '1/16W'  | 'IO'       | 'RES CHIP 54.9 1/16W +-1%(0402)'                   | 'CHIP0402'     | ''          | ''            | '20100617'
 '4.02K'      | '1%'      | '1/16W'  | '0402LF'  | 'CHIP'   | 'CS24022FB05'(!)        = ''              | ''                 | 'CS24022FB05'           |'R0402'| '(R0402-0201)'                 | '4.02K'   | '1%'    | '1/16W'  | 'DISCRETE' | 'RES CHIP 4.02K 1/16W +-1%(0402)'                  | 'CHIP0402'     | ''          | ''            | '20100617'
 '4.02K'      | '1%'      | '1/16W'  | '0402LF'  | 'EMPTY'  | 'CS24022FB05'(!)        = ''              | ''                 | 'CS24022FB05'           |'R0402'| '(R0402-0201)'                 | '4.02K'   | '1%'    | '1/16W'  | 'IO'       | 'RES CHIP 4.02K 1/16W +-1%(0402)'                  | 'CHIP0402'     | ''          | ''            | '20100617'
 '3.4K'       | '1%'      | '1/16W'  | '0402LF'  | 'CHIP'   | 'CS23402FB08'(!)        = 'End of Design' | 'Comp-Approve'     | 'CS23402FB08'           |'R0402'| '(R0402-0201)'                 | '3.4K'    | '1%'    | '1/16W'  | 'DISCRETE' | 'RES CHIP 3.4K 1/16W +-1%(0402)'                   | 'CHIP0402'     | ''          | ''            | '20100617'
 '3.4K'       | '1%'      | '1/16W'  | '0402LF'  | 'EMPTY'  | 'CS23402FB08'(!)        = 'End of Design' | 'Comp-Approve'     | 'CS23402FB08'           |'R0402'| '(R0402-0201)'                 | '3.4K'    | '1%'    | '1/16W'  | 'IO'       | 'RES CHIP 3.4K 1/16W +-1%(0402)'                   | 'CHIP0402'     | ''          | ''            | '20100617'
 '187K'       | '1%'      | '1/16W'  | '0402LF'  | 'CHIP'   | 'CS41872FB10'(!)        = 'End of Design' | 'Comp-Approve'     | 'CS41872FB10'           |'R0402'| '(R0402-0201)'                 | '187K'    | '1%'    | '1/16W'  | 'DISCRETE' | 'RES CHIP 187K 1/16W +-1%(0402)'                   | 'CHIP0402'     | ''          | ''            | '20100617'
 '187K'       | '1%'      | '1/16W'  | '0402LF'  | 'EMPTY'  | 'CS41872FB10'(!)        = 'End of Design' | 'Comp-Approve'     | 'CS41872FB10'           |'R0402'| '(R0402-0201)'                 | '187K'    | '1%'    | '1/16W'  | 'IO'       | 'RES CHIP 187K 1/16W +-1%(0402)'                   | 'CHIP0402'     | ''          | ''            | '20100617'
 '1M'         | '1%'      | '1/16W'  | '0402LF'  | 'CHIP'   | 'CS51002FB11'(!)        = 'End of Design' | 'Comp-Approve'     | 'CS51002FB11'           |'R0402'| '(R0402-0201)'                 | '1M'      | '1%'    | '1/16W'  | 'DISCRETE' | 'RES CHIP 1M 1/16W +-1% (0402)'                    | 'CHIP0402'     | ''          | ''            | '20100617'
 '1M'         | '1%'      | '1/16W'  | '0402LF'  | 'EMPTY'  | 'CS51002FB11'(!)        = 'End of Design' | 'Comp-Approve'     | 'CS51002FB11'           |'R0402'| '(R0402-0201)'                 | '1M'      | '1%'    | '1/16W'  | 'IO'       | 'RES CHIP 1M 1/16W +-1% (0402)'                    | 'CHIP0402'     | ''          | ''            | '20100617'
 '562'        | '1%'      | '1/16W'  | '0402LF'  | 'CHIP'   | 'CS15622FB08'(!)        = ''              | ''                 | 'CS15622FB08'           |'R0402'| '(R0402-0201)'                 | '562'     | '1%'    | '1/16W'  | 'DISCRETE' | 'RES CIHP 562 1/16W +-1% (0402)'                   | 'CHIP0402'     | ''          | ''            | '20100617'
 '562'        | '1%'      | '1/16W'  | '0402LF'  | 'EMPTY'  | 'CS15622FB08'(!)        = ''              | ''                 | 'CS15622FB08'           |'R0402'| '(R0402-0201)'                 | '562'     | '1%'    | '1/16W'  | 'IO'       | 'RES CIHP 562 1/16W +-1% (0402)'                   | 'CHIP0402'     | ''          | ''            | '20100617'
 '0'          | '5%'      | '1/16W'  | '0402LF'  | 'CHIP'   | 'CS00002JB38'(!)        = 'End of Design' | 'Comp-Approve'     | 'CS00002JB38'           |'R0402'| '(R0402-0201)'                 | '0'       | '5%'    | '1/16W'  | 'DISCRETE' | 'RESISTOR CHIP 0 1/16W +-5%(0402)'                 | 'CHIP0402'     | ''          | ''            | '20100618'
 '0'          | '5%'      | '1/16W'  | '0402LF'  | 'EMPTY'  | 'CS00002JB38'(!)        = 'End of Design' | 'Comp-Approve'     | 'CS00002JB38'           |'R0402'| '(R0402-0201)'                 | '0'       | '5%'    | '1/16W'  | 'IO'       | 'RESISTOR CHIP 0 1/16W +-5%(0402)'                 | 'CHIP0402'     | ''          | ''            | '20100618'
 '4.99K'      | '0.5%'    | '1/16W'  | '0402LF'  | 'CHIP'   | 'CS24992DB00'(!)        = ''              | ''                 | 'CS24992DB00'           |'R0402'| '(R0402-0201)'                 | '4.99K'   | '0.5%'  | '1/16W'  | 'DISCRETE' | 'RES CHIP 4.99K 1/16W +-0.5%(0402)'                | 'CHIP0402'     | ''          | ''            | '20100618'
 '4.99K'      | '0.5%'    | '1/16W'  | '0402LF'  | 'EMPTY'  | 'CS24992DB00'(!)        = ''              | ''                 | 'CS24992DB00'           |'R0402'| '(R0402-0201)'                 | '4.99K'   | '0.5%'  | '1/16W'  | 'IO'       | 'RES CHIP 4.99K 1/16W +-0.5%(0402)'                | 'CHIP0402'     | ''          | ''            | '20100618'
 '210K'       | '1%'      | '1/16W'  | '0402LF'  | 'CHIP'   | 'CS42102FB00'(!)        = 'End of Design' | 'Comp-Approve'     | 'CS42102FB00'           |'R0402'| '(R0402-0201)'                 | '210K'    | '1%'    | '1/16W'  | 'DISCRETE' | 'RES CHIP 210K 1/16W +-1%(0402)'                   | 'CHIP0402'     | ''          | ''            | '20100618'
 '210K'       | '1%'      | '1/16W'  | '0402LF'  | 'EMPTY'  | 'CS42102FB00'(!)        = 'End of Design' | 'Comp-Approve'     | 'CS42102FB00'           |'R0402'| '(R0402-0201)'                 | '210K'    | '1%'    | '1/16W'  | 'IO'       | 'RES CHIP 210K 1/16W +-1%(0402)'                   | 'CHIP0402'     | ''          | ''            | '20100618'
 '84.5K'      | '1%'      | '1/16W'  | '0402LF'  | 'CHIP'   | 'CS38452FB14'(!)        = 'End of Design' | 'Comp-Approve'     | 'CS38452FB14'           |'R0402'| '(R0402-0201)'                 | '84.5K'   | '1%'    | '1/16W'  | 'DISCRETE' | 'RES CHIP 84.5K 1/16W +-1%(0402)'                  | 'CHIP0402'     | ''          | ''            | '20100618'
 '84.5K'      | '1%'      | '1/16W'  | '0402LF'  | 'EMPTY'  | 'CS38452FB14'(!)        = 'End of Design' | 'Comp-Approve'     | 'CS38452FB14'           |'R0402'| '(R0402-0201)'                 | '84.5K'   | '1%'    | '1/16W'  | 'IO'       | 'RES CHIP 84.5K 1/16W +-1%(0402)'                  | 'CHIP0402'     | ''          | ''            | '20100618'
 '133K'       | '1%'      | '1/16W'  | '0402LF'  | 'CHIP'   | 'CS41332FB06'(!)        = 'End of Design' | 'Comp-Approve'     | 'CS41332FB06'           |'R0402'| '(R0402-0201)'                 | '133K'    | '1%'    | '1/16W'  | 'DISCRETE' | 'RES CHIP 133K 1/16W +-1%(0402)'                   | 'CHIP0402'     | ''          | ''            | '20100618'
 '133K'       | '1%'      | '1/16W'  | '0402LF'  | 'EMPTY'  | 'CS41332FB06'(!)        = 'End of Design' | 'Comp-Approve'     | 'CS41332FB06'           |'R0402'| '(R0402-0201)'                 | '133K'    | '1%'    | '1/16W'  | 'IO'       | 'RES CHIP 133K 1/16W +-1%(0402)'                   | 'CHIP0402'     | ''          | ''            | '20100618'
 '205K'       | '1%'      | '1/16W'  | '0402LF'  | 'CHIP'   | 'CS42052FB10'(!)        = 'End of Design' | 'Comp-Approve'     | 'CS42052FB10'           |'R0402'| '(R0402-0201)'                 | '205K'    | '1%'    | '1/16W'  | 'DISCRETE' | 'RES CHIP 205K 1/16W +-1%(0402)'                   | 'CHIP0402'     | ''          | ''            | '20100618'
 '205K'       | '1%'      | '1/16W'  | '0402LF'  | 'EMPTY'  | 'CS42052FB10'(!)        = 'End of Design' | 'Comp-Approve'     | 'CS42052FB10'           |'R0402'| '(R0402-0201)'                 | '205K'    | '1%'    | '1/16W'  | 'IO'       | 'RES CHIP 205K 1/16W +-1%(0402)'                   | 'CHIP0402'     | ''          | ''            | '20100618'
 '6.34K'      | '0.5%'    | '1/10W'  | '0603LF'  | 'CHIP'   | 'CS26343D900'(!)        = 'End of Design' | 'Comp-Approve'     | 'CS26343D900'           |'R0603'| '(SMR0603AW)'                  | '6.34K'   | '0.5%'  | '1/10W'  | 'DISCRETE' | 'RES CHIP 6.34K 1/10W +-0.5%(0603)'                | 'CHIP0603'     | ''          | ''            | '20100618'
 '6.34K'      | '0.5%'    | '1/10W'  | '0603LF'  | 'EMPTY'  | 'CS26343D900'(!)        = 'End of Design' | 'Comp-Approve'     | 'CS26343D900'           |'R0603'| '(SMR0603AW)'                  | '6.34K'   | '0.5%'  | '1/10W'  | 'IO'       | 'RES CHIP 6.34K 1/10W +-0.5%(0603)'                | 'CHIP0603'     | ''          | ''            | '20100618'
 '10K'        | '0.5%'    | '1/10W'  | '0603LF'  | 'CHIP'   | 'CS31003D911'(!)        = ''              | ''                 | 'CS31003D911'           |'R0603'| '(SMR0603AW)'                  | '10K'     | '0.5%'  | '1/10W ' | 'DISCRETE' | 'RESISTOR CHIP 10K 1/10W+-0.5%(0603)'              | 'CHIP0603'     | ''          | ''            | '20100618'
 '10K'        | '0.5%'    | '1/10W'  | '0603LF'  | 'EMPTY'  | 'CS31003D911'(!)        = ''              | ''                 | 'CS31003D911'           |'R0603'| '(SMR0603AW)'                  | '10K'     | '0.5%'  | '1/10W ' | 'IO'       | 'RESISTOR CHIP 10K 1/10W+-0.5%(0603)'              | 'CHIP0603'     | ''          | ''            | '20100618'
 '3.6K'       | '0.5%'    | '1/10W'  | '0603LF'  | 'CHIP'   | 'CS23603D900'(!)        = 'End of Design' | 'Comp-Approve'     | 'CS23603D900'           |'R0603'| '(SMR0603AW)'                  | '3.6K'    | '0.5%'  | '1/10W ' | 'DISCRETE' | 'RES CHIP 3.6K 1/10W +-0.5%(0603)'                 | 'CHIP0603'     | ''          | ''            | '20100621'
 '3.6K'       | '0.5%'    | '1/10W'  | '0603LF'  | 'EMPTY'  | 'CS23603D900'(!)        = 'End of Design' | 'Comp-Approve'     | 'CS23603D900'           |'R0603'| '(SMR0603AW)'                  | '3.6K'    | '0.5%'  | '1/10W ' | 'IO'       | 'RES CHIP 3.6K 1/10W +-0.5%(0603)'                 | 'CHIP0603'     | ''          | ''            | '20100621'
 '24.9K'      | '1%'      | '1/16W'  | '0402LF'  | 'CHIP'   | 'CS32492FB16'(!)        = 'End of Design' | 'Comp-Approve'     | 'CS32492FB16'           |'R0402'| '(R0402-0201)'                 | '24.9K'   | '1%'    | '1/16W'  | 'DISCRETE' | 'RES CHIP 24.9K 1/16W +-1%(0402)'                  | 'CHIP0402'     | ''          | ''            | '20100621'
 '24.9K'      | '1%'      | '1/16W'  | '0402LF'  | 'EMPTY'  | 'CS32492FB16'(!)        = 'End of Design' | 'Comp-Approve'     | 'CS32492FB16'           |'R0402'| '(R0402-0201)'                 | '24.9K'   | '1%'    | '1/16W'  | 'IO'       | 'RES CHIP 24.9K 1/16W +-1%(0402)'                  | 'CHIP0402'     | ''          | ''            | '20100621'
 '330'        | '1%'      | '1/10W'  | '0603LF'  | 'CHIP'   | 'CS13303F917'(!)        = ''              | ''                 | 'CS13303F917'           |'R0603'| '(SMR0603AW)'                  | '330'     | '1%'    | '1/10W'  | 'DISCRETE' | 'RES CHIP 330 1/10W +-1%(0603)'                    | 'CHIP0603'     | ''          | ''            | '20100621'
 '330'        | '1%'      | '1/10W'  | '0603LF'  | 'EMPTY'  | 'CS13303F917'(!)        = ''              | ''                 | 'CS13303F917'           |'R0603'| '(SMR0603AW)'                  | '330'     | '1%'    | '1/10W'  | 'IO'       | 'RES CHIP 330 1/10W +-1%(0603)'                    | 'CHIP0603'     | ''          | ''            | '20100621'
 '47.5K'      | '1%'      | '1/10W'  | '0603LF'  | 'CHIP'   | 'CS34753F911'(!)        = ''              | ''                 | 'CS34753F911'           |'R0603'| '(SMR0603AW)'                  | '47.5K'   | '1%'    | '1/10W ' | 'DISCRETE' | 'RES CHIP 47.5K 1/10W +-1%(0603)'                  | 'CHIP0603'     | ''          | ''            | '20100621'
 '47.5K'      | '1%'      | '1/10W'  | '0603LF'  | 'EMPTY'  | 'CS34753F911'(!)        = ''              | ''                 | 'CS34753F911'           |'R0603'| '(SMR0603AW)'                  | '47.5K'   | '1%'    | '1/10W ' | 'IO'       | 'RES CHIP 47.5K 1/10W +-1%(0603)'                  | 'CHIP0603'     | ''          | ''            | '20100621'
 '47.5K'      | '1%'      | '1/16W'  | '0402LF'  | 'CHIP'   | 'CS34752FB14'(!)        = 'End of Design' | 'Comp-Approve'     | 'CS34752FB14'           |'R0402'| '(R0402-0201)'                 | '47.5K'   | '1%'    | '1/16W'  | 'DISCRETE' | 'RES CHIP 47.5K 1/16W +-1% (0402)'                 | 'CHIP0402'     | ''          | ''            | '20100621'
 '47.5K'      | '1%'      | '1/16W'  | '0402LF'  | 'EMPTY'  | 'CS34752FB14'(!)        = 'End of Design' | 'Comp-Approve'     | 'CS34752FB14'           |'R0402'| '(R0402-0201)'                 | '47.5K'   | '1%'    | '1/16W'  | 'IO'       | 'RES CHIP 47.5K 1/16W +-1% (0402)'                 | 'CHIP0402'     | ''          | ''            | '20100621'
 '130'        | '1%'      | '1/16W'  | '0402LF'  | 'CHIP'   | 'CS11302FB15'(!)        = 'End of Design' | 'Comp-Approve'     | 'CS11302FB15'           |'R0402'| '(R0402-0201)'                 | '130'     | '1%'    | '1/16W'  | 'DISCRETE' | 'RES CHIP 130 1/16W +-1%(0402)'                    | 'CHIP0402'     | ''          | ''            | '20100621'
 '130'        | '1%'      | '1/16W'  | '0402LF'  | 'EMPTY'  | 'CS11302FB15'(!)        = 'End of Design' | 'Comp-Approve'     | 'CS11302FB15'           |'R0402'| '(R0402-0201)'                 | '130'     | '1%'    | '1/16W'  | 'IO'       | 'RES CHIP 130 1/16W +-1%(0402)'                    | 'CHIP0402'     | ''          | ''            | '20100621'
 '23.7K'      | '1%'      | '1/16W'  | '0402LF'  | 'CHIP'   | 'CS32372FB05'(!)        = 'End of Design' | 'Comp-Approve'     | 'CS32372FB05'           |'R0402'| '(R0402-0201)'                 | '23.7K'   | '1%'    | '1/16W'  | 'DISCRETE' | 'RES CHIP 23.7K 1/16W +-1%(0402)'                  | 'CHIP0402'     | ''          | ''            | '20100621'
 '23.7K'      | '1%'      | '1/16W'  | '0402LF'  | 'EMPTY'  | 'CS32372FB05'(!)        = 'End of Design' | 'Comp-Approve'     | 'CS32372FB05'           |'R0402'| '(R0402-0201)'                 | '23.7K'   | '1%'    | '1/16W'  | 'IO'       | 'RES CHIP 23.7K 1/16W +-1%(0402)'                  | 'CHIP0402'     | ''          | ''            | '20100621'
 '6.98K'      | '1%'      | '1/16W'  | '0402LF'  | 'CHIP'   | 'CS26982FB01'(!)        = 'End of Design' | 'Comp-Approve'     | 'CS26982FB01'           |'R0402'| '(R0402-0201)'                 | '6.98K'   | '1%'    | '1/16W'  | 'DISCRETE' | 'RES CHIP 6.98K 1/16W +-1% (0402)'                 | 'CHIP0402'     | ''          | ''            | '20100622'
 '6.98K'      | '1%'      | '1/16W'  | '0402LF'  | 'EMPTY'  | 'CS26982FB01'(!)        = 'End of Design' | 'Comp-Approve'     | 'CS26982FB01'           |'R0402'| '(R0402-0201)'                 | '6.98K'   | '1%'    | '1/16W'  | 'IO'       | 'RES CHIP 6.98K 1/16W +-1% (0402)'                 | 'CHIP0402'     | ''          | ''            | '20100622'
 '845'        | '1%'      | '1/16W'  | '0402LF'  | 'CHIP'   | 'CS18452FB11'(!)        = 'End of Design' | 'Comp-Approve'     | 'CS18452FB11'           |'R0402'| '(R0402-0201)'                 | '845'     | '1%'    | '1/16W'  | 'DISCRETE' | 'RES CHIP 845 1/16W +-1%(0402) '                   | 'CHIP0402'     | ''          | ''            | '20100622'
 '845'        | '1%'      | '1/16W'  | '0402LF'  | 'EMPTY'  | 'CS18452FB11'(!)        = 'End of Design' | 'Comp-Approve'     | 'CS18452FB11'           |'R0402'| '(R0402-0201)'                 | '845'     | '1%'    | '1/16W'  | 'IO'       | 'RES CHIP 845 1/16W +-1%(0402) '                   | 'CHIP0402'     | ''          | ''            | '20100622'
 '1.05K'      | '1%'      | '1/16W'  | '0402LF'  | 'CHIP'   | 'CS21052FB00'(!)        = 'End of Design' | 'Comp-Approve'     | 'CS21052FB00'           |'R0402'| '(R0402-0201)'                 | '1.05K'   | '1%'    | '1/16W'  | 'DISCRETE' | 'RES CHIP 1.05K 1/16W +-1%(0402)'                  | 'CHIP0402'     | ''          | ''            | '20100723'
 '1.05K'      | '1%'      | '1/16W'  | '0402LF'  | 'EMPTY'  | 'CS21052FB00'(!)        = 'End of Design' | 'Comp-Approve'     | 'CS21052FB00'           |'R0402'| '(R0402-0201)'                 | '1.05K'   | '1%'    | '1/16W'  | 'IO'       | 'RES CHIP 1.05K 1/16W +-1%(0402)'                  | 'CHIP0402'     | ''          | ''            | '20100723'
 '1.02K'      | '1%'      | '1/16W'  | '0402LF'  | 'CHIP'   | 'CS21022FB15'(!)        = 'End of Design' | 'Comp-Approve'     | 'CS21022FB15'           |'R0402'| '(R0402-0201)'                 | '1.02K'   | '1%'    | '1/16W'  | 'DISCRETE' | 'RES CHIP 1.02K 1/16W +-1%(0402)'                  | 'CHIP0402'     | ''          | ''            | '20100622'
 '1.02K'      | '1%'      | '1/16W'  | '0402LF'  | 'EMPTY'  | 'CS21022FB15'(!)        = 'End of Design' | 'Comp-Approve'     | 'CS21022FB15'           |'R0402'| '(R0402-0201)'                 | '1.02K'   | '1%'    | '1/16W'  | 'IO'       | 'RES CHIP 1.02K 1/16W +-1%(0402)'                  | 'CHIP0402'     | ''          | ''            | '20100622'
 '115K'       | '1%'      | '1/16W'  | '0402LF'  | 'CHIP'   | 'CS41152FB08'(!)        = 'End of Design' | 'Comp-Approve'     | 'CS41152FB08'           |'R0402'| '(R0402-0201)'                 | '115K'    | '1%'    | '1/16W'  | 'DISCRETE' | 'RES CHIP 115K 1/16W +-1%(0402)'                   | 'CHIP0402'     | ''          | ''            | '20100623'
 '115K'       | '1%'      | '1/16W'  | '0402LF'  | 'EMPTY'  | 'CS41152FB08'(!)        = 'End of Design' | 'Comp-Approve'     | 'CS41152FB08'           |'R0402'| '(R0402-0201)'                 | '115K'    | '1%'    | '1/16W'  | 'IO'       | 'RES CHIP 115K 1/16W +-1%(0402)'                   | 'CHIP0402'     | ''          | ''            | '20100623'
 '28.7K'      | '1%'      | '1/16W'  | '0402LF'  | 'CHIP'   | 'CS32872FB11'(!)        = 'End of Design' | 'Comp-Approve'     | 'CS32872FB11'           |'R0402'| '(R0402-0201)'                 | '28.7K'   | '1%'    | '1/16W'  | 'DISCRETE' | 'RES CHIP 28.7K 1/16W +-1%(0402)'                  | 'CHIP0402'     | ''          | ''            | '20100623'
 '28.7K'      | '1%'      | '1/16W'  | '0402LF'  | 'EMPTY'  | 'CS32872FB11'(!)        = 'End of Design' | 'Comp-Approve'     | 'CS32872FB11'           |'R0402'| '(R0402-0201)'                 | '28.7K'   | '1%'    | '1/16W'  | 'IO'       | 'RES CHIP 28.7K 1/16W +-1%(0402)'                  | 'CHIP0402'     | ''          | ''            | '20100623'
 '6.04K'      | '1%'      | '1/16W'  | '0402LF'  | 'CHIP'   | 'CS26042FB00'(!)        = 'End of Design' | 'Comp-Approve'     | 'CS26042FB00'           |'R0402'| '(R0402-0201)'                 | '6.04K'   | '1%'    | '1/16W'  | 'DISCRETE' | 'RES CHIP 6.04K 1/16W +-1%(0402)'                  | 'CHIP0402'     | ''          | ''            | '20100630'
 '6.04K'      | '1%'      | '1/16W'  | '0402LF'  | 'EMPTY'  | 'CS26042FB00'(!)        = 'End of Design' | 'Comp-Approve'     | 'CS26042FB00'           |'R0402'| '(R0402-0201)'                 | '6.04K'   | '1%'    | '1/16W'  | 'IO'       | 'RES CHIP 6.04K 1/16W +-1%(0402)'                  | 'CHIP0402'     | ''          | ''            | '20100630'
 '45'         | '1%'      | '1/16W'  | '0402LF'  | 'CHIP'   | 'CS04502FB01'(!)        = ''              | ''                 | 'CS04502FB01'           |'R0402'| '(R0402-0201)'                 | '45'      | '1%'    | '1/16W'  | 'DISCRETE' | 'RES CHIP 45 1/16W +-1%(0402)'                     | 'CHIP0402'     | ''          | ''            | '20100630'
 '45'         | '1%'      | '1/16W'  | '0402LF'  | 'EMPTY'  | 'CS04502FB01'(!)        = ''              | ''                 | 'CS04502FB01'           |'R0402'| '(R0402-0201)'                 | '45'      | '1%'    | '1/16W'  | 'IO'       | 'RES CHIP 45 1/16W +-1%(0402)'                     | 'CHIP0402'     | ''          | ''            | '20100630'
 '196K'       | '1%'      | '1/16W'  | '0402LF'  | 'CHIP'   | 'CS41962FB01'(!)        = 'End of Design' | 'Comp-Approve'     | 'CS41962FB01'           |'R0402'| '(R0402-0201)'                 | '196K'    | '1%'    | '1/16W'  | 'DISCRETE' | 'RES CHIP 196K 1/16W +-1% (0402)'                  | 'CHIP0402'     | ''          | ''            | '20100702'
 '196K'       | '1%'      | '1/16W'  | '0402LF'  | 'EMPTY'  | 'CS41962FB01'(!)        = 'End of Design' | 'Comp-Approve'     | 'CS41962FB01'           |'R0402'| '(R0402-0201)'                 | '196K'    | '1%'    | '1/16W'  | 'IO'       | 'RES CHIP 196K 1/16W +-1% (0402)'                  | 'CHIP0402'     | ''          | ''            | '20100702'
 '158K'       | '1%'      | '1/16W'  | '0402LF'  | 'CHIP'   | 'CS41582FB06'(!)        = ''              | ''                 | 'CS41582FB06'           |'R0402'| '(R0402-0201)'                 | '158K'    | '1%'    | '1/16W'  | 'DISCRETE' | 'RES CHIP 158K 1/16W +-1% (0402)'                  | 'CHIP0402'     | ''          | ''            | '20100702'
 '158K'       | '1%'      | '1/16W'  | '0402LF'  | 'EMPTY'  | 'CS41582FB06'(!)        = ''              | ''                 | 'CS41582FB06'           |'R0402'| '(R0402-0201)'                 | '158K'    | '1%'    | '1/16W'  | 'IO'       | 'RES CHIP 158K 1/16W +-1% (0402)'                  | 'CHIP0402'     | ''          | ''            | '20100702'
 '300'        | '1%'      | '1/8W'   | '0805LF'  | 'CHIP'   | 'CS13004FA00'(!)        = ''              | ''                 | 'CS13004FA00'           |'R0805'| '(SMR0805AW)'                  | '300'     | '1%'    | '1/8W'   | 'DISCRETE' | 'RES CHIP 300 1/8W +-1%(0805)'                     | 'CHIP0805'     | ''          | ''            | '20100706'
 '300'        | '1%'      | '1/8W'   | '0805LF'  | 'EMPTY'  | 'CS13004FA00'(!)        = ''              | ''                 | 'CS13004FA00'           |'R0805'| '(SMR0805AW)'                  | '300'     | '1%'    | '1/8W'   | 'IO'       | 'RES CHIP 300 1/8W +-1%(0805)'                     | 'CHIP0805'     | ''          | ''            | '20100706'
 '0.5'        | '5%'      | '1/2W'   | '1210LF'  | 'CHIP'   | 'CS+5007J300'(!)        = ''              | ''                 | 'CS+5007J300'           |'R1210'| '(SMR1210AW)'                  | '0.5'     | '5%'    | '1/2W'   | 'DISCRETE' | 'RES CHIP 0.5 1/2W +-5% (1210)'                    | 'CHIP1210'     | ''          | ''            | '20100706'
 '0.5'        | '5%'      | '1/2W'   | '1210LF'  | 'EMPTY'  | 'CS+5007J300'(!)        = ''              | ''                 | 'CS+5007J300'           |'R1210'| '(SMR1210AW)'                  | '0.5'     | '5%'    | '1/2W'   | 'IO'       | 'RES CHIP 0.5 1/2W +-5% (1210)'                    | 'CHIP1210'     | ''          | ''            | '20100706'
 '499K'       | '1%'      | '1/10W'  | '0603LF'  | 'CHIP'   | 'CS44993F918'(!)        = ''              | ''                 | 'CS44993F918'           |'R0603'| '(SMR0603AW)'                  | '499K'    | '1%'    | '1/10W ' | 'DISCRETE' | 'RES CHIP 499K 1/10W +-1%(0603)'                   | 'CHIP0603'     | ''          | ''            | '20100708'
 '499K'       | '1%'      | '1/10W'  | '0603LF'  | 'EMPTY'  | 'CS44993F918'(!)        = ''              | ''                 | 'CS44993F918'           |'R0603'| '(SMR0603AW)'                  | '499K'    | '1%'    | '1/10W ' | 'IO'       | 'RES CHIP 499K 1/10W +-1%(0603)'                   | 'CHIP0603'     | ''          | ''            | '20100708'
 '33'         | '5%'      | '1/16W'  | '0402LF'  | 'CHIP'   | 'CS03302JB29'(!)        = 'End of Design' | 'Comp-Approve'     | 'CS03302JB29'           |'R0402'| '(R0402-0201)'                 | '33'      | '5%'    | '1/16W'  | 'DISCRETE' | 'RES CHIP 33 1/16W +-5% (0402)'                    | 'CHIP0402'     | ''          | ''            | '20100708'
 '33'         | '5%'      | '1/16W'  | '0402LF'  | 'EMPTY'  | 'CS03302JB29'(!)        = 'End of Design' | 'Comp-Approve'     | 'CS03302JB29'           |'R0402'| '(R0402-0201)'                 | '33'      | '5%'    | '1/16W'  | 'IO'       | 'RES CHIP 33 1/16W +-5% (0402)'                    | 'CHIP0402'     | ''          | ''            | '20100708'
 '330'        | '5%'      | '1/10W'  | '0603LF'  | 'CHIP'   | 'CS13303J943'(!)        = ''              | ''                 | 'CS13303J943'           |'R0603'| '(SMR0603AW)'                  | '330'     | '5%'    | '1/10W ' | 'DISCRETE' | 'RES CHIP 330 1/10W +-5%(0603)'                    | 'CHIP0603'     | ''          | ''            | '20100708'
 '330'        | '5%'      | '1/10W'  | '0603LF'  | 'EMPTY'  | 'CS13303J943'(!)        = ''              | ''                 | 'CS13303J943'           |'R0603'| '(SMR0603AW)'                  | '330'     | '5%'    | '1/10W ' | 'IO'       | 'RES CHIP 330 1/10W +-5%(0603)'                    | 'CHIP0603'     | ''          | ''            | '20100708'
 '4.7K'       | '5%'      | '1/10W'  | '0603LF'  | 'CHIP'   | 'CS24703J942'(!)        = ''              | ''                 | 'CS24703J942'           |'R0603'| '(SMR0603AW)'                  | '4.7K'    | '5%'    | '1/10W ' | 'DISCRETE' | 'RES CHIP 4.7K 1/10W +-5%(0603)'                   | 'CHIP0603'     | ''          | ''            | '20100708'
 '4.7K'       | '5%'      | '1/10W'  | '0603LF'  | 'EMPTY'  | 'CS24703J942'(!)        = ''              | ''                 | 'CS24703J942'           |'R0603'| '(SMR0603AW)'                  | '4.7K'    | '5%'    | '1/10W ' | 'IO'       | 'RES CHIP 4.7K 1/10W +-5%(0603)'                   | 'CHIP0603'     | ''          | ''            | '20100708'
 '100'        | '1%'      | '1/10W'  | '0603LF'  | 'CHIP'   | 'CS11003F953'(!)        = ''              | ''                 | 'CS11003F953'           |'R0603'| '(SMR0603AW)'                  | '100'     | '1%'    | '1/10W ' | 'DISCRETE' | 'RESISTOR CHIP 100 1/10W+-1%(0603)'                | 'CHIP0603'     | ''          | ''            | '20100708'
 '100'        | '1%'      | '1/10W'  | '0603LF'  | 'EMPTY'  | 'CS11003F953'(!)        = ''              | ''                 | 'CS11003F953'           |'R0603'| '(SMR0603AW)'                  | '100'     | '1%'    | '1/10W ' | 'IO'       | 'RESISTOR CHIP 100 1/10W+-1%(0603)'                | 'CHIP0603'     | ''          | ''            | '20100708'
 '1K'         | '1%'      | '1/10W'  | '0603LF'  | 'CHIP'   | 'CS21003F947'(!)        = ''              | ''                 | 'CS21003F947'           |'R0603'| '(SMR0603AW)'                  | '1K'      | '1%'    | '1/10W ' | 'DISCRETE' | 'RESISTOR CHIP 1K,1/10W,+-1%(0603)'                | 'CHIP0603'     | ''          | ''            | '20100708'
 '1K'         | '1%'      | '1/10W'  | '0603LF'  | 'EMPTY'  | 'CS21003F947'(!)        = ''              | ''                 | 'CS21003F947'           |'R0603'| '(SMR0603AW)'                  | '1K'      | '1%'    | '1/10W ' | 'IO'       | 'RESISTOR CHIP 1K,1/10W,+-1%(0603)'                | 'CHIP0603'     | ''          | ''            | '20100708'
 '20K'        | '1%'      | '1/16W'  | '0402LF'  | 'CHIP'   | 'CS32002FB29'(!)        = 'End of Design' | 'Comp-Approve'     | 'CS32002FB29'           |'R0402'| '(R0402-0201)'                 | '20K'     | '1%'    | '1/16W'  | 'DISCRETE' | 'RES CHIP 20K 1/16W +-1%(0402)'                    | 'CHIP0402'     | ''          | ''            | '20100708'
 '20K'        | '1%'      | '1/16W'  | '0402LF'  | 'EMPTY'  | 'CS32002FB29'(!)        = 'End of Design' | 'Comp-Approve'     | 'CS32002FB29'           |'R0402'| '(R0402-0201)'                 | '20K'     | '1%'    | '1/16W'  | 'IO'       | 'RES CHIP 20K 1/16W +-1%(0402)'                    | 'CHIP0402'     | ''          | ''            | '20100708'
 '130'        | '5%'      | '1/16W'  | '0402LF'  | 'CHIP'   | 'CS11302JB17'(!)        = 'End of Design' | 'Comp-Approve'     | 'CS11302JB17'           |'R0402'| '(R0402-0201)'                 | '130'     | '5%'    | '1/16W'  | 'DISCRETE' | 'RES CHIP 130(1/16W,+-5%,0402)'                    | 'CHIP0402'     | ''          | ''            | '20100708'
 '130'        | '5%'      | '1/16W'  | '0402LF'  | 'EMPTY'  | 'CS11302JB17'(!)        = 'End of Design' | 'Comp-Approve'     | 'CS11302JB17'           |'R0402'| '(R0402-0201)'                 | '130'     | '5%'    | '1/16W'  | 'IO'       | 'RES CHIP 130(1/16W,+-5%,0402)'                    | 'CHIP0402'     | ''          | ''            | '20100708'
 '4.7K'       | '1%'      | '1/16W'  | '0402LF'  | 'CHIP'   | 'CS24702FB10'(!)        = 'End of Design' | 'Comp-Approve'     | 'CS24702FB10'           |'R0402'| '(R0402-0201)'                 | '4.7K'    | '1%'    | '1/16W'  | 'DISCRETE' | 'RES CHIP 4.7K 1/16W +-1%(0402)'                   | 'CHIP0402'     | ''          | ''            | '20100708'
 '4.7K'       | '1%'      | '1/16W'  | '0402LF'  | 'EMPTY'  | 'CS24702FB10'(!)        = 'End of Design' | 'Comp-Approve'     | 'CS24702FB10'           |'R0402'| '(R0402-0201)'                 | '4.7K'    | '1%'    | '1/16W'  | 'IO'       | 'RES CHIP 4.7K 1/16W +-1%(0402)'                   | 'CHIP0402'     | ''          | ''            | '20100708'
 '100K'       | '5%'      | '1/16W'  | '0402LF'  | 'CHIP'   | 'CS41002JB20'(!)        = 'End of Design' | 'Comp-Approve'     | 'CS41002JB20'           |'R0402'| '(R0402-0201)'                 | '100K'    | '5%'    | '1/16W'  | 'DISCRETE' | 'RES CHIP 100K 1/16W 5%(0402)'                     | 'CHIP0402'     | ''          | ''            | '20100708'
 '100K'       | '5%'      | '1/16W'  | '0402LF'  | 'EMPTY'  | 'CS41002JB20'(!)        = 'End of Design' | 'Comp-Approve'     | 'CS41002JB20'           |'R0402'| '(R0402-0201)'                 | '100K'    | '5%'    | '1/16W'  | 'IO'       | 'RES CHIP 100K 1/16W 5%(0402)'                     | 'CHIP0402'     | ''          | ''            | '20100708'
 '220'        | '5%'      | '1/16W'  | '0402LF'  | 'CHIP'   | 'CS12202JB24'(!)        = 'End of Design' | 'Comp-Approve'     | 'CS12202JB24'           |'R0402'| '(R0402-0201)'                 | '220'     | '5%'    | '1/16W'  | 'DISCRETE' | 'RES CHIP 220 1/16W +-5%(0402)'                    | 'CHIP0402'     | ''          | ''            | '20100708'
 '220'        | '5%'      | '1/16W'  | '0402LF'  | 'EMPTY'  | 'CS12202JB24'(!)        = 'End of Design' | 'Comp-Approve'     | 'CS12202JB24'           |'R0402'| '(R0402-0201)'                 | '220'     | '5%'    | '1/16W'  | 'IO'       | 'RES CHIP 220 1/16W +-5%(0402)'                    | 'CHIP0402'     | ''          | ''            | '20100708'
 '487'        | '1%'      | '1/16W'  | '0402LF'  | 'CHIP'   | 'CS14872FB05'(!)        = 'End of Design' | 'Comp-Approve'     | 'CS14872FB05'           |'R0402'| '(R0402-0201)'                 | '487'     | '1%'    | '1/16W'  | 'DISCRETE' | 'RES CHIP 487 1/16W +-1%(0402)'                    | 'CHIP0402'     | ''          | ''            | '20100712'
 '487'        | '1%'      | '1/16W'  | '0402LF'  | 'EMPTY'  | 'CS14872FB05'(!)        = 'End of Design' | 'Comp-Approve'     | 'CS14872FB05'           |'R0402'| '(R0402-0201)'                 | '487'     | '1%'    | '1/16W'  | 'IO'       | 'RES CHIP 487 1/16W +-1%(0402)'                    | 'CHIP0402'     | ''          | ''            | '20100712'
 '1.1K'       | '1%'      | '1/16W'  | '0402LF'  | 'CHIP'   | 'CS21102FB10'(!)        = 'End of Design' | 'Comp-Approve'     | 'CS21102FB10'           |'R0402'| '(R0402-0201)'                 | '1.1K'    | '1%'    | '1/16W'  | 'DISCRETE' | 'RES CHIP 1.1K 1/16W +-1% (0402)'                  | 'CHIP0402'     | ''          | ''            | '20100712'
 '1.1K'       | '1%'      | '1/16W'  | '0402LF'  | 'EMPTY'  | 'CS21102FB10'(!)        = 'End of Design' | 'Comp-Approve'     | 'CS21102FB10'           |'R0402'| '(R0402-0201)'                 | '1.1K'    | '1%'    | '1/16W'  | 'IO'       | 'RES CHIP 1.1K 1/16W +-1% (0402)'                  | 'CHIP0402'     | ''          | ''            | '20100712'
 '68'         | '1%'      | '1/16W'  | '0402LF'  | 'CHIP'   | 'CS06802FB07'(!)        = 'End of Design' | 'Comp-Approve'     | 'CS06802FB07'           |'R0402'| '(R0402-0201)'                 | '68'      | '1%'    | '1/16W'  | 'DISCRETE' | 'RES CHIP 68 1/16W +-1%(0402)'                     | 'CHIP0402'     | ''          | ''            | '20100712'
 '68'         | '1%'      | '1/16W'  | '0402LF'  | 'EMPTY'  | 'CS06802FB07'(!)        = 'End of Design' | 'Comp-Approve'     | 'CS06802FB07'           |'R0402'| '(R0402-0201)'                 | '68'      | '1%'    | '1/16W'  | 'IO'       | 'RES CHIP 68 1/16W +-1%(0402)'                     | 'CHIP0402'     | ''          | ''            | '20100712'
 '21K'        | '1%'      | '1/16W'  | '0402LF'  | 'CHIP'   | 'CS32102FB14'(!)        = 'End of Design' | 'Comp-Approve'     | 'CS32102FB14'           |'R0402'| '(R0402-0201)'                 | '21K '    | '1%'    | '1/16W'  | 'DISCRETE' | 'RES CHIP 21K 1/16W +-1%(0402)'                    | 'CHIP0402'     | ''          | ''            | '20100712'
 '21K'        | '1%'      | '1/16W'  | '0402LF'  | 'EMPTY'  | 'CS32102FB14'(!)        = 'End of Design' | 'Comp-Approve'     | 'CS32102FB14'           |'R0402'| '(R0402-0201)'                 | '21K '    | '1%'    | '1/16W'  | 'IO'       | 'RES CHIP 21K 1/16W +-1%(0402)'                    | 'CHIP0402'     | ''          | ''            | '20100712'
 '453'        | '1%'      | '1/16W'  | '0402LF'  | 'CHIP'   | 'CS14532FB14'(!)        = 'End of Design' | 'Comp-Approve'     | 'CS14532FB14'           |'R0402'| '(R0402-0201)'                 | '453'     | '1%'    | '1/16W'  | 'DISCRETE' | 'RES CHIP 453 1/16W +-1% (0402) '                  | 'CHIP0402'     | ''          | ''            | '20100712'
 '453'        | '1%'      | '1/16W'  | '0402LF'  | 'EMPTY'  | 'CS14532FB14'(!)        = 'End of Design' | 'Comp-Approve'     | 'CS14532FB14'           |'R0402'| '(R0402-0201)'                 | '453'     | '1%'    | '1/16W'  | 'IO'       | 'RES CHIP 453 1/16W +-1% (0402) '                  | 'CHIP0402'     | ''          | ''            | '20100712'
 '0'          | '5%'      | '1/8W'   | '0805LF'  | 'CHIP'   | 'CS00004JA40'(!)        = ''              | ''                 | 'CS00004JA40'           |'R0805'| '(SMR0805AW)'                  | '0'       | '5%'    | '1/8W'   | 'DISCRETE' | 'RESISTOR CHIP 0 1/8W +-5%(0805)'                  | 'CHIP0805'     | ''          | ''            | '20100713'
 '0'          | '5%'      | '1/8W'   | '0805LF'  | 'EMPTY'  | 'CS00004JA40'(!)        = ''              | ''                 | 'CS00004JA40'           |'R0805'| '(SMR0805AW)'                  | '0'       | '5%'    | '1/8W'   | 'IO'       | 'RESISTOR CHIP 0 1/8W +-5%(0805)'                  | 'CHIP0805'     | ''          | ''            | '20100713'
 '2.21K'      | '1%'      | '1/16W'  | '0402LF'  | 'CHIP'   | 'CS22212FB02'(!)        = ''              | 'End of Life'      | 'CS22212FB02'           |'R0402_EOL'| '(R0402-0201)'                 | '2.21K'   | '1%'    | '1/16W'  | 'DISCRETE' | 'RES CHIP 2.21K 1/16W +-1% (0402)'                 | 'CHIP0402'     | ''          | ''            | '20100713'
 '2.21K'      | '1%'      | '1/16W'  | '0402LF'  | 'EMPTY'  | 'CS22212FB02'(!)        = ''              | 'End of Life'      | 'CS22212FB02'           |'R0402_EOL'| '(R0402-0201)'                 | '2.21K'   | '1%'    | '1/16W'  | 'IO'       | 'RES CHIP 2.21K 1/16W +-1% (0402)'                 | 'CHIP0402'     | ''          | ''            | '20100713'
 '8.25K'      | '1%'      | '1/16W'  | '0402LF'  | 'CHIP'   | 'CS28252FB07'(!)        = 'End of Design' | 'Comp-Approve'     | 'CS28252FB07'           |'R0402'| '(R0402-0201)'                 | '8.25K'   | '1%'    | '1/16W'  | 'DISCRETE' | 'RES CHIP 8.25K 1/16W +-1% (0402)'                 | 'CHIP0402'     | ''          | ''            | '20100715'
 '8.25K'      | '1%'      | '1/16W'  | '0402LF'  | 'EMPTY'  | 'CS28252FB07'(!)        = 'End of Design' | 'Comp-Approve'     | 'CS28252FB07'           |'R0402'| '(R0402-0201)'                 | '8.25K'   | '1%'    | '1/16W'  | 'IO'       | 'RES CHIP 8.25K 1/16W +-1% (0402)'                 | 'CHIP0402'     | ''          | ''            | '20100715'
 '680  '      | '1%'      | '1/16W'  | '0402LF'  | 'CHIP'   | 'CS16802FB09'(!)        = 'End of Design' | 'Comp-Approve'     | 'CS16802FB09'           |'R0402'| '(R0402-0201)'                 | '680'     | '1%'    | '1/16W'  | 'DISCRETE' | 'RES CHIP 680 1/16W +-1%(0402)'                    | 'CHIP0402'     | ''          | ''            | '20100715'
 '680  '      | '1%'      | '1/16W'  | '0402LF'  | 'EMPTY'  | 'CS16802FB09'(!)        = 'End of Design' | 'Comp-Approve'     | 'CS16802FB09'           |'R0402'| '(R0402-0201)'                 | '680'     | '1%'    | '1/16W'  | 'IO'       | 'RES CHIP 680 1/16W +-1%(0402)'                    | 'CHIP0402'     | ''          | ''            | '20100715'
 '750'        | '1%'      | '1/16W'  | '0402LF'  | 'CHIP'   | 'CS17502FB19'(!)        = 'End of Design' | 'Comp-Approve'     | 'CS17502FB19'           |'R0402'| '(R0402-0201)'                 | '750'     | '1%'    | '1/16W'  | 'DISCRETE' | 'RES CHIP 750 1/16W +-1%(0402)'                    | 'CHIP0402'     | ''          | ''            | '20100715'
 '750'        | '1%'      | '1/16W'  | '0402LF'  | 'EMPTY'  | 'CS17502FB19'(!)        = 'End of Design' | 'Comp-Approve'     | 'CS17502FB19'           |'R0402'| '(R0402-0201)'                 | '750'     | '1%'    | '1/16W'  | 'IO'       | 'RES CHIP 750 1/16W +-1%(0402)'                    | 'CHIP0402'     | ''          | ''            | '20100715'
 '15   '      | '1%'      | '1/16W'  | '0402LF'  | 'CHIP'   | 'CS01502FB11'(!)        = 'End of Design' | 'Comp-Approve'     | 'CS01502FB11'           |'R0402'| '(R0402-0201)'                 | '15'      | '1%'    | '1/16W'  | 'DISCRETE' | 'RES CHIP 15 1/16W +-1%(0402)'                     | 'CHIP0402'     | ''          | ''            | '20100715'
 '15   '      | '1%'      | '1/16W'  | '0402LF'  | 'EMPTY'  | 'CS01502FB11'(!)        = 'End of Design' | 'Comp-Approve'     | 'CS01502FB11'           |'R0402'| '(R0402-0201)'                 | '15'      | '1%'    | '1/16W'  | 'IO'       | 'RES CHIP 15 1/16W +-1%(0402)'                     | 'CHIP0402'     | ''          | ''            | '20100715'
 '1M'         | '5%'      | '1/16W'  | '0402LF'  | 'CHIP'   | 'CS51002JB21'(!)        = 'End of Design' | 'Comp-Approve'     | 'CS51002JB21'           |'R0402'| '(R0402-0201)'                 | '1M'      | '5%'    | '1/16W'  | 'DISCRETE' | 'RES CHIP 1M 1/16W +-5% (0402)'                    | 'CHIP0402'     | ''          | ''            | '20100715'
 '1M'         | '5%'      | '1/16W'  | '0402LF'  | 'EMPTY'  | 'CS51002JB21'(!)        = 'End of Design' | 'Comp-Approve'     | 'CS51002JB21'           |'R0402'| '(R0402-0201)'                 | '1M'      | '5%'    | '1/16W'  | 'IO'       | 'RES CHIP 1M 1/16W +-5% (0402)'                    | 'CHIP0402'     | ''          | ''            | '20100715'
 '47   '      | '5%'      | '1/16W'  | '0402LF'  | 'CHIP'   | 'CS04702JB18'(!)        = 'End of Design' | 'Comp-Approve'     | 'CS04702JB18'           |'R0402'| '(R0402-0201)'                 | '47'      | '5%'    | '1/16W'  | 'DISCRETE' | 'RES CHIP 47 1/16W +-5%(0402)'                     | 'CHIP0402'     | ''          | ''            | '20100715'
 '47   '      | '5%'      | '1/16W'  | '0402LF'  | 'EMPTY'  | 'CS04702JB18'(!)        = 'End of Design' | 'Comp-Approve'     | 'CS04702JB18'           |'R0402'| '(R0402-0201)'                 | '47'      | '5%'    | '1/16W'  | 'IO'       | 'RES CHIP 47 1/16W +-5%(0402)'                     | 'CHIP0402'     | ''          | ''            | '20100715'
 '330  '      | '5%'      | '1/16W'  | '0402LF'  | 'CHIP'   | 'CS13302JB21'(!)        = 'End of Design' | 'Comp-Approve'     | 'CS13302JB21'           |'R0402'| '(R0402-0201)'                 | '330'     | '5%'    | '1/16W'  | 'DISCRETE' | 'RES CHIP 330(1/16W +-5% 0402)'                    | 'CHIP0402'     | ''          | ''            | '20100715'
 '330  '      | '5%'      | '1/16W'  | '0402LF'  | 'EMPTY'  | 'CS13302JB21'(!)        = 'End of Design' | 'Comp-Approve'     | 'CS13302JB21'           |'R0402'| '(R0402-0201)'                 | '330'     | '5%'    | '1/16W'  | 'IO'       | 'RES CHIP 330(1/16W +-5% 0402)'                    | 'CHIP0402'     | ''          | ''            | '20100715'
 '470  '      | '5%'      | '1/16W'  | '0402LF'  | 'CHIP'   | 'CS14702JB28'(!)        = 'End of Design' | 'Comp-Approve'     | 'CS14702JB28'           |'R0402'| '(R0402-0201)'                 | '470'     | '5%'    | '1/16W'  | 'DISCRETE' | 'RES CHIP 470 1/16W +-5% (0402)'                   | 'CHIP0402'     | ''          | ''            | '20100715'
 '470  '      | '5%'      | '1/16W'  | '0402LF'  | 'EMPTY'  | 'CS14702JB28'(!)        = 'End of Design' | 'Comp-Approve'     | 'CS14702JB28'           |'R0402'| '(R0402-0201)'                 | '470'     | '5%'    | '1/16W'  | 'IO'       | 'RES CHIP 470 1/16W +-5% (0402)'                   | 'CHIP0402'     | ''          | ''            | '20100715'
 '2.2K'       | '5%'      | '1/16W'  | '0402LF'  | 'CHIP'   | 'CS22202JB18'(!)        = 'End of Design' | 'Comp-Approve'     | 'CS22202JB18'           |'R0402'| '(R0402-0201)'                 | '2.2K'    | '5%'    | '1/16W'  | 'DISCRETE' | 'RES CHIP 2.2K 1/16W +-5%(0402)'                   | 'CHIP0402'     | ''          | ''            | '20100715'
 '2.2K'       | '5%'      | '1/16W'  | '0402LF'  | 'EMPTY'  | 'CS22202JB18'(!)        = 'End of Design' | 'Comp-Approve'     | 'CS22202JB18'           |'R0402'| '(R0402-0201)'                 | '2.2K'    | '5%'    | '1/16W'  | 'IO'       | 'RES CHIP 2.2K 1/16W +-5%(0402)'                   | 'CHIP0402'     | ''          | ''            | '20100715'
 '4.7K '      | '5%'      | '1/16W'  | '0402LF'  | 'CHIP'   | 'CS24702JB03'(!)        = 'End of Design' | 'Comp-Approve'     | 'CS24702JB03'           |'R0402'| '(R0402-0201)'                 | '4.7K'    | '5%'    | '1/16W'  | 'DISCRETE' | 'RES CHIP 4.7K 1/16W +-5% (0402)'                  | 'CHIP0402'     | ''          | ''            | '20100715'
 '4.7K '      | '5%'      | '1/16W'  | '0402LF'  | 'EMPTY'  | 'CS24702JB03'(!)        = 'End of Design' | 'Comp-Approve'     | 'CS24702JB03'           |'R0402'| '(R0402-0201)'                 | '4.7K'    | '5%'    | '1/16W'  | 'IO'       | 'RES CHIP 4.7K 1/16W +-5% (0402)'                  | 'CHIP0402'     | ''          | ''            | '20100715'
 '4.7K '      | '5%'      | '1/16W'  | '0402LF'  | 'CHIP'   | 'CS24702JB11'(!)        = ''              | ''                 | 'CS24702JB11'           |'R0402'| '(R0402-0201)'                 | '4.7K'    | '5%'    | '1/16W'  | 'DISCRETE' | 'RES CHIP 4.7K 1/16W +-5% (0402)ES-PAL'            | 'CHIP0402'     | ''          | ''            | '20100715'
 '4.7K '      | '5%'      | '1/16W'  | '0402LF'  | 'EMPTY'  | 'CS24702JB11'(!)        = ''              | ''                 | 'CS24702JB11'           |'R0402'| '(R0402-0201)'                 | '4.7K'    | '5%'    | '1/16W'  | 'IO'       | 'RES CHIP 4.7K 1/16W +-5% (0402)ES-PAL'            | 'CHIP0402'     | ''          | ''            | '20100715'
 '220K '      | '5%'      | '1/10W'  | '0603LF'  | 'CHIP'   | 'CS42203J900'(!)        = 'End of Design' | 'Comp-Approve'     | 'CS42203J900'           |'R0603'| '(SMR0603AW)'                  | '220K'    | '5%'    | '1/10W ' | 'DISCRETE' | 'RESISTOR CHIP 220K 1/10W +-5%(1608)'              | 'CHIP0603'     | ''          | ''            | '20100715'
 '220K '      | '5%'      | '1/10W'  | '0603LF'  | 'EMPTY'  | 'CS42203J900'(!)        = 'End of Design' | 'Comp-Approve'     | 'CS42203J900'           |'R0603'| '(SMR0603AW)'                  | '220K'    | '5%'    | '1/10W ' | 'IO'       | 'RESISTOR CHIP 220K 1/10W +-5%(1608)'              | 'CHIP0603'     | ''          | ''            | '20100715'
 '0    '      | '1%'      | '1/10W'  | '0603LF'  | 'CHIP'   | 'CS00003F916'(!)        = 'End of Design' | 'Comp-Approve'     | 'CS00003F916'           |'R0603'| '(SMR0603AW)'                  | '0'       | '1%'    | '1/10W ' | 'DISCRETE' | 'RES CHIP 0 1/10W +-1% (0603)'                     | 'CHIP0603'     | ''          | ''            | '20100715'
 '0    '      | '1%'      | '1/10W'  | '0603LF'  | 'EMPTY'  | 'CS00003F916'(!)        = 'End of Design' | 'Comp-Approve'     | 'CS00003F916'           |'R0603'| '(SMR0603AW)'                  | '0'       | '1%'    | '1/10W ' | 'IO'       | 'RES CHIP 0 1/10W +-1% (0603)'                     | 'CHIP0603'     | ''          | ''            | '20100715'
 '0'          | '5%'      | '1/10W'  | '0603LF'  | 'CHIP'   | 'CS00003J900'(!)        = 'End of Design' | 'Comp-Approve'     | 'CS00003J900'           |'R0603'| '(SMR0603AW)'                  | '0'       | '5%'    | '1/10W ' | 'DISCRETE' | 'RESISTOR CHIP 0 1/10W+-5%(0603)'                  | 'CHIP0603'     | ''          | ''            | '20100715'
 '0'          | '5%'      | '1/10W'  | '0603LF'  | 'EMPTY'  | 'CS00003J900'(!)        = 'End of Design' | 'Comp-Approve'     | 'CS00003J900'           |'R0603'| '(SMR0603AW)'                  | '0'       | '5%'    | '1/10W ' | 'IO'       | 'RESISTOR CHIP 0 1/10W+-5%(0603)'                  | 'CHIP0603'     | ''          | ''            | '20100715'
 '0.001'      | '1%'      | '2W   '  | '2512LF'  | 'CHIP'   | 'CS+001AF104'(!)        = ''              | 'End of Life'      | 'CS+001AF104'           |'R2512A_EOL'| '(SMR2512AW)'                  | '0.001'   | '1%'    | '2W    ' | 'DISCRETE' | 'RES CHIP 0.001 2W(+-1%,2512) L-F'                 | 'CHIP2512'     | ''          | ''            | '20100715'
 '0.001'      | '1%'      | '2W   '  | '2512LF'  | 'EMPTY'  | 'CS+001AF104'(!)        = ''              | 'End of Life'      | 'CS+001AF104'           |'R2512A_EOL'| '(SMR2512AW)'                  | '0.001'   | '1%'    | '2W    ' | 'IO'       | 'RES CHIP 0.001 2W(+-1%,2512) L-F'                 | 'CHIP2512'     | ''          | ''            | '20100715'
 '49.9'       | '1%'      | '1/16W'  | '0402LF'  | 'CHIP'   | 'CS04992FB31'(!)        = 'End of Design' | 'Comp-Approve'     | 'CS04992FB31'           |'R0402'| '(R0402_OCTAGONXA,R0402-0201)' | '49.9'    | '1%'    | '1/16W ' | 'DISCRETE' | 'RES CHIP 49.9 1/16W +-1% (0402)'                  | 'CHIP0402'     | ''          | ''            | '20100716'
 '49.9'       | '1%'      | '1/16W'  | '0402LF'  | 'EMPTY'  | 'CS04992FB31'(!)        = 'End of Design' | 'Comp-Approve'     | 'CS04992FB31'           |'R0402'| '(R0402_OCTAGONXA,R0402-0201)' | '49.9'    | '1%'    | '1/16W ' | 'IO'       | 'RES CHIP 49.9 1/16W +-1% (0402)'                  | 'CHIP0402'     | ''          | ''            | '20100716'
 '226      '  | '0.1%'    | '1/16W'  | '0402LF'  | 'CHIP'   | 'CS12262BB00'(!)        = ''              | ''                 | 'CS12262BB00'           |'R0402'| '(R0402-0201)'                 | '226'     | '0.1%'  | '1/16W ' | 'DISCRETE' | 'RES CHIP 226 1/16W 0.1% (0402)'                   | 'CHIP0402'     | ''          | ''            | '20100716'
 '226      '  | '0.1%'    | '1/16W'  | '0402LF'  | 'EMPTY'  | 'CS12262BB00'(!)        = ''              | ''                 | 'CS12262BB00'           |'R0402'| '(R0402-0201)'                 | '226'     | '0.1%'  | '1/16W ' | 'IO'       | 'RES CHIP 226 1/16W 0.1% (0402)'                   | 'CHIP0402'     | ''          | ''            | '20100716'
 '2.21K    '  | '1%  '    | '1/16W'  | '0402LF'  | 'CHIP'   | 'CS22212FB11'(!)        = 'End of Design' | 'Comp-Approve'     | 'CS22212FB11'           |'R0402'| '(R0402-0201)'                 | '2.21K'   | '1%  '  | '1/16W ' | 'DISCRETE' | 'RES CHIP 2.21K 1/16W +-1% (0402)'                 | 'CHIP0402'     | ''          | ''            | '20100716'
 '2.21K    '  | '1%  '    | '1/16W'  | '0402LF'  | 'EMPTY'  | 'CS22212FB11'(!)        = 'End of Design' | 'Comp-Approve'     | 'CS22212FB11'           |'R0402'| '(R0402-0201)'                 | '2.21K'   | '1%  '  | '1/16W ' | 'IO'       | 'RES CHIP 2.21K 1/16W +-1% (0402)'                 | 'CHIP0402'     | ''          | ''            | '20100716'
 '3K       '  | '1%  '    | '1/16W'  | '0402LF'  | 'CHIP'   | 'CS23002FB11'(!)        = 'End of Design' | 'Comp-Approve'     | 'CS23002FB11'           |'R0402'| '(R0402-0201)'                 | '3K'      | '1%  '  | '1/16W ' | 'DISCRETE' | 'RES CHIP 3K 1/16W +-1%(0402)'                     | 'CHIP0402'     | ''          | ''            | '20100716'
 '3K       '  | '1%  '    | '1/16W'  | '0402LF'  | 'EMPTY'  | 'CS23002FB11'(!)        = 'End of Design' | 'Comp-Approve'     | 'CS23002FB11'           |'R0402'| '(R0402-0201)'                 | '3K'      | '1%  '  | '1/16W ' | 'IO'       | 'RES CHIP 3K 1/16W +-1%(0402)'                     | 'CHIP0402'     | ''          | ''            | '20100716'
 '6.2K'       | '1%'      | '1/16W'  | '0402LF'  | 'CHIP'   | 'CS26202FB17'(!)        = 'End of Design' | 'Comp-Approve'     | 'CS26202FB17'           |'R0402'| '(R0402-0201)'                 | '6.2K'    | '1%'    | '1/16W'  | 'DISCRETE' | 'RES CHIP 6.2K 1/16W +-1%(0402)'                   | 'CHIP0402'     | ''          | ''            | '20100716'
 '6.2K'       | '1%'      | '1/16W'  | '0402LF'  | 'EMPTY'  | 'CS26202FB17'(!)        = 'End of Design' | 'Comp-Approve'     | 'CS26202FB17'           |'R0402'| '(R0402-0201)'                 | '6.2K'    | '1%'    | '1/16W'  | 'IO'       | 'RES CHIP 6.2K 1/16W +-1%(0402)'                   | 'CHIP0402'     | ''          | ''            | '20100716'
 '10K      '  | '0.1%'    | '1/16W'  | '0402LF'  | 'CHIP'   | 'CS31002BB02'(!)        = ''              | ''                 | 'CS31002BB02'           |'R0402'| '(R0402-0201)'                 | '10K'     | '0.1%'  | '1/16W'  | 'DISCRETE' | 'RES CHIP 10K 1/16W+-0.1%(0402)JET ASSIGN'         | 'CHIP0402'     | ''          | ''            | '20100716'
 '10K      '  | '0.1%'    | '1/16W'  | '0402LF'  | 'EMPTY'  | 'CS31002BB02'(!)        = ''              | ''                 | 'CS31002BB02'           |'R0402'| '(R0402-0201)'                 | '10K'     | '0.1%'  | '1/16W'  | 'IO'       | 'RES CHIP 10K 1/16W+-0.1%(0402)JET ASSIGN'         | 'CHIP0402'     | ''          | ''            | '20100716'
 '22K      '  | '5%  '    | '1/16W'  | '0402LF'  | 'CHIP'   | 'CS32202JB28'(!)        = 'End of Design' | 'Comp-Approve'     | 'CS32202JB28'           |'R0402'| '(R0402-0201)'                 | '22K'     | '5%'    | '1/16W'  | 'DISCRETE' | 'RES CHIP 22K 1/16W +-5% (0402)'                   | 'CHIP0402'     | ''          | ''            | '20100716'
 '22K      '  | '5%  '    | '1/16W'  | '0402LF'  | 'EMPTY'  | 'CS32202JB28'(!)        = 'End of Design' | 'Comp-Approve'     | 'CS32202JB28'           |'R0402'| '(R0402-0201)'                 | '22K'     | '5%'    | '1/16W'  | 'IO'       | 'RES CHIP 22K 1/16W +-5% (0402)'                   | 'CHIP0402'     | ''          | ''            | '20100716'
 '30.1K    '  | '1%  '    | '1/16W'  | '0402LF'  | 'CHIP'   | 'CS33012FB18'(!)        = 'End of Design' | 'Comp-Approve'     | 'CS33012FB18'           |'R0402'| '(R0402-0201)'                 | '30.1K'   | '1%  '  | '1/16W'  | 'DISCRETE' | 'RES CHIP 30.1K 1/16W +-1%(0402)'                  | 'CHIP0402'     | ''          | ''            | '20100716'
 '30.1K    '  | '1%  '    | '1/16W'  | '0402LF'  | 'EMPTY'  | 'CS33012FB18'(!)        = 'End of Design' | 'Comp-Approve'     | 'CS33012FB18'           |'R0402'| '(R0402-0201)'                 | '30.1K'   | '1%  '  | '1/16W'  | 'IO'       | 'RES CHIP 30.1K 1/16W +-1%(0402)'                  | 'CHIP0402'     | ''          | ''            | '20100716'
 '33K'        | '0.1%'    | '1/16W'  | '0402LF'  | 'CHIP'   | 'CS33302BB00'(!)        = ''              | ''                 | 'CS33302BB00'           |'R0402'| '(R0402-0201)'                 | '33K'     | '0.1%'  | '1/16W'  | 'DISCRETE' | 'RES CHIP 33K 1/16W 0.1% (0402)'                   | 'CHIP0402'     | ''          | ''            | '20100716'
 '33K'        | '0.1%'    | '1/16W'  | '0402LF'  | 'EMPTY'  | 'CS33302BB00'(!)        = ''              | ''                 | 'CS33302BB00'           |'R0402'| '(R0402-0201)'                 | '33K'     | '0.1%'  | '1/16W'  | 'IO'       | 'RES CHIP 33K 1/16W 0.1% (0402)'                   | 'CHIP0402'     | ''          | ''            | '20100716'
 '100      '  | '5%  '    | '1/10W'  | '0603LF'  | 'CHIP'   | 'CS11003J947'(!)        = ''              | ''                 | 'CS11003J947'           |'R0603'| '(SMR0603AW)'                  | '100'     | '5%'    | '1/10W'  | 'DISCRETE' | 'RESISTOR CHIP 100 1/10W +-5%(0603)EP'             | 'CHIP0603'     | ''          | ''            | '20100716'
 '100      '  | '5%  '    | '1/10W'  | '0603LF'  | 'EMPTY'  | 'CS11003J947'(!)        = ''              | ''                 | 'CS11003J947'           |'R0603'| '(SMR0603AW)'                  | '100'     | '5%'    | '1/10W'  | 'IO'       | 'RESISTOR CHIP 100 1/10W +-5%(0603)EP'             | 'CHIP0603'     | ''          | ''            | '20100716'
 '180      '  | '1%  '    | '1/10W'  | '0603LF'  | 'CHIP'   | 'CS11803F910'(!)        = 'End of Design' | 'Comp-Approve'     | 'CS11803F910'           |'R0603'| '(SMR0603AW)'                  | '180'     | '1%'    | '1/10W'  | 'DISCRETE' | 'RES CHIP 180 1/10W +-1%(0603)EP'                  | 'CHIP0603'     | ''          | ''            | '20100716'
 '180      '  | '1%  '    | '1/10W'  | '0603LF'  | 'EMPTY'  | 'CS11803F910'(!)        = 'End of Design' | 'Comp-Approve'     | 'CS11803F910'           |'R0603'| '(SMR0603AW)'                  | '180'     | '1%'    | '1/10W'  | 'IO'       | 'RES CHIP 180 1/10W +-1%(0603)EP'                  | 'CHIP0603'     | ''          | ''            | '20100716'
 '200      '  | '1%  '    | '1/10W'  | '0603LF'  | 'CHIP'   | 'CS12003F930'(!)        = ''              | ''                 | 'CS12003F930'           |'R0603'| '(SMR0603AW)'                  | '200'     | '1%'    | '1/10W'  | 'DISCRETE' | 'RES CHIP 200 1/10W 1% (0603)EP'                   | 'CHIP0603'     | ''          | ''            | '20100716'
 '200      '  | '1%  '    | '1/10W'  | '0603LF'  | 'EMPTY'  | 'CS12003F930'(!)        = ''              | ''                 | 'CS12003F930'           |'R0603'| '(SMR0603AW)'                  | '200'     | '1%'    | '1/10W'  | 'IO'       | 'RES CHIP 200 1/10W 1% (0603)EP'                   | 'CHIP0603'     | ''          | ''            | '20100716'
 '1K       '  | '5%  '    | '1/10W'  | '0603LF'  | 'CHIP'   | 'CS21003J949'(!)        = ''              | ''                 | 'CS21003J949'           |'R0603'| '(SMR0603AW)'                  | '1K'      | '5%'    | '1/10W'  | 'DISCRETE' | 'RES CHIP 1K 1/10W +-5%(0603)'                     | 'CHIP0603'     | ''          | ''            | '20100716'
 '1K       '  | '5%  '    | '1/10W'  | '0603LF'  | 'EMPTY'  | 'CS21003J949'(!)        = ''              | ''                 | 'CS21003J949'           |'R0603'| '(SMR0603AW)'                  | '1K'      | '5%'    | '1/10W'  | 'IO'       | 'RES CHIP 1K 1/10W +-5%(0603)'                     | 'CHIP0603'     | ''          | ''            | '20100716'
 '54.9      ' | '1%  '    | '1/10W'  | '0603LF'  | 'CHIP'   | 'CS05493F931'(!)        = ''              | ''                 | 'CS05493F931'           |'R0603'| '(SMR0603AW)'                  | '54.9'    | '1%'    | '1/10W'  | 'DISCRETE' | 'RES CHIP 54.9 1/10W +-1%(0603)'                   | 'CHIP0603'     | ''          | ''            | '20100718'
 '54.9      ' | '1%  '    | '1/10W'  | '0603LF'  | 'EMPTY'  | 'CS05493F931'(!)        = ''              | ''                 | 'CS05493F931'           |'R0603'| '(SMR0603AW)'                  | '54.9'    | '1%'    | '1/10W'  | 'IO'       | 'RES CHIP 54.9 1/10W +-1%(0603)'                   | 'CHIP0603'     | ''          | ''            | '20100718'
 '2.15K     ' | '1%  '    | '1/10W'  | '0603LF'  | 'CHIP'   | 'CS22153F920'(!)        = ''              | ''                 | 'CS22153F920'           |'R0603'| '(SMR0603AW)'                  | '2.15K'   | '1%'    | '1/10W'  | 'DISCRETE' | 'RES CHIP 2.15K 1/10W +-1%(0603)'                  | 'CHIP0603'     | ''          | ''            | '20100718'
 '2.15K     ' | '1%  '    | '1/10W'  | '0603LF'  | 'EMPTY'  | 'CS22153F920'(!)        = ''              | ''                 | 'CS22153F920'           |'R0603'| '(SMR0603AW)'                  | '2.15K'   | '1%'    | '1/10W'  | 'IO'       | 'RES CHIP 2.15K 1/10W +-1%(0603)'                  | 'CHIP0603'     | ''          | ''            | '20100718'
 '3.4K      ' | '1%  '    | '1/10W'  | '0603LF'  | 'CHIP'   | 'CS23403F912'(!)        = ''              | ''                 | 'CS23403F912'           |'R0603'| '(SMR0603AW)'                  | '3.4K'    | '1%'    | '1/10W'  | 'DISCRETE' | 'RESISTOR CHIP 3.4K 1/10W+-1%(0603)'               | 'CHIP0603'     | ''          | ''            | '20100718'
 '3.4K      ' | '1%  '    | '1/10W'  | '0603LF'  | 'EMPTY'  | 'CS23403F912'(!)        = ''              | ''                 | 'CS23403F912'           |'R0603'| '(SMR0603AW)'                  | '3.4K'    | '1%'    | '1/10W'  | 'IO'       | 'RESISTOR CHIP 3.4K 1/10W+-1%(0603)'               | 'CHIP0603'     | ''          | ''            | '20100718'
 '10K       ' | '1%  '    | '1/10W'  | '0603LF'  | 'CHIP'   | 'CS31003F949'(!)        = ''              | ''                 | 'CS31003F949'           |'R0603'| '(SMR0603AW)'                  | '10K'     | '1%'    | '1/10W'  | 'DISCRETE' | 'RESISTOR CHIP 10K 1/10W+-1%(0603)'                | 'CHIP0603'     | ''          | ''            | '20100718'
 '10K       ' | '1%  '    | '1/10W'  | '0603LF'  | 'EMPTY'  | 'CS31003F949'(!)        = ''              | ''                 | 'CS31003F949'           |'R0603'| '(SMR0603AW)'                  | '10K'     | '1%'    | '1/10W'  | 'IO'       | 'RESISTOR CHIP 10K 1/10W+-1%(0603)'                | 'CHIP0603'     | ''          | ''            | '20100718'
 '511      '  | '1%  '    | '1/16W'  | '0402LF'  | 'CHIP'   | 'CS15112FB13'(!)        = 'End of Design' | 'Comp-Approve'     | 'CS15112FB13'           |'R0402'| '(R0402-0201)'                 | '511'     | '1%'    | '1/16W'  | 'DISCRETE' | 'RES CHIP 511 1/16W +-1%(0402)'                    | 'CHIP0402'     | ''          | ''            | '20100720'
 '511      '  | '1%  '    | '1/16W'  | '0402LF'  | 'EMPTY'  | 'CS15112FB13'(!)        = 'End of Design' | 'Comp-Approve'     | 'CS15112FB13'           |'R0402'| '(R0402-0201)'                 | '511'     | '1%'    | '1/16W'  | 'IO'       | 'RES CHIP 511 1/16W +-1%(0402)'                    | 'CHIP0402'     | ''          | ''            | '20100720'
 '604      '  | '1%  '    | '1/16W'  | '0402LF'  | 'CHIP'   | 'CS16042FB24'(!)        = 'End of Design' | 'Comp-Approve'     | 'CS16042FB24'           |'R0402'| '(R0402-0201)'                 | '604'     | '1%'    | '1/16W'  | 'DISCRETE' | 'RES CHIP 604 1/16W +-1%(0402)'                    | 'CHIP0402'     | ''          | ''            | '20100720'
 '604      '  | '1%  '    | '1/16W'  | '0402LF'  | 'EMPTY'  | 'CS16042FB24'(!)        = 'End of Design' | 'Comp-Approve'     | 'CS16042FB24'           |'R0402'| '(R0402-0201)'                 | '604'     | '1%'    | '1/16W'  | 'IO'       | 'RES CHIP 604 1/16W +-1%(0402)'                    | 'CHIP0402'     | ''          | ''            | '20100720'
 '13.7K    '  | '1%  '    | '1/16W'  | '0402LF'  | 'CHIP'   | 'CS31372FB11'(!)        = 'End of Design' | 'Comp-Approve'     | 'CS31372FB11'           |'R0402'| '(R0402-0201)'                 | '13.7K'   | '1%'    | '1/16W'  | 'DISCRETE' | 'RES CHIP 13.7K 1/16W +-1%(0402)'                  | 'CHIP0402'     | ''          | ''            | '20100720'
 '13.7K    '  | '1%  '    | '1/16W'  | '0402LF'  | 'EMPTY'  | 'CS31372FB11'(!)        = 'End of Design' | 'Comp-Approve'     | 'CS31372FB11'           |'R0402'| '(R0402-0201)'                 | '13.7K'   | '1%'    | '1/16W'  | 'IO'       | 'RES CHIP 13.7K 1/16W +-1%(0402)'                  | 'CHIP0402'     | ''          | ''            | '20100720'
 '18.7K    '  | '1%  '    | '1/16W'  | '0402LF'  | 'CHIP'   | 'CS31872FB19'(!)        = 'End of Design' | 'Comp-Approve'     | 'CS31872FB19'           |'R0402'| '(R0402-0201)'                 | '18.7k'   | '1%'    | '1/16W'  | 'DISCRETE' | 'RES CHIP 18.7K 1/16W +-1%(0402)'                  | 'CHIP0402'     | ''          | ''            | '20100720'
 '18.7K    '  | '1%  '    | '1/16W'  | '0402LF'  | 'EMPTY'  | 'CS31872FB19'(!)        = 'End of Design' | 'Comp-Approve'     | 'CS31872FB19'           |'R0402'| '(R0402-0201)'                 | '18.7k'   | '1%'    | '1/16W'  | 'IO'       | 'RES CHIP 18.7K 1/16W +-1%(0402)'                  | 'CHIP0402'     | ''          | ''            | '20100720'
 '2.21K    '  | '0.5%  '  | '1/10W'  | '0603LF'  | 'CHIP'   | 'CS22213D906'(!)        = ''              | ''                 | 'CS22213D906'           |'R0603'| '(SMR0603AW)'                  | '2.21K'   | '0.5%'  | '1/10W'  | 'DISCRETE' | 'RESISTOR CHIP 2.21K 1/10W+-0.5%(0603)L-F'         | 'CHIP0603'     | ''          | ''            | '20100727'
 '2.21K    '  | '0.5%  '  | '1/10W'  | '0603LF'  | 'EMPTY'  | 'CS22213D906'(!)        = ''              | ''                 | 'CS22213D906'           |'R0603'| '(SMR0603AW)'                  | '2.21K'   | '0.5%'  | '1/10W'  | 'IO'       | 'RESISTOR CHIP 2.21K 1/10W+-0.5%(0603)L-F'         | 'CHIP0603'     | ''          | ''            | '20100727'
 '33K    '    | '1%  '    | '1/16W'  | '0402LF'  | 'CHIP'   | 'CS33302FB14'(!)        = 'End of Design' | 'Comp-Approve'     | 'CS33302FB14'           |'R0402'| '(R0402-0201)'                 | '33K'     | '1%'    | '1/16W'  | 'DISCRETE' | 'RES CHIP 33K 1/16W +-1%(0402)'                    | 'CHIP0402'     | ''          | ''            | '20100802'
 '33K    '    | '1%  '    | '1/16W'  | '0402LF'  | 'EMPTY'  | 'CS33302FB14'(!)        = 'End of Design' | 'Comp-Approve'     | 'CS33302FB14'           |'R0402'| '(R0402-0201)'                 | '33K'     | '1%'    | '1/16W'  | 'IO'       | 'RES CHIP 33K 1/16W +-1%(0402)'                    | 'CHIP0402'     | ''          | ''            | '20100802'
 '22'         | '5%'      | '1/16W'  | '0402LF'  | 'CHIP'   | 'CS02202JB22'(!)        = 'End of Design' | 'Comp-Approve'     | 'CS02202JB22'           |'R0402'| '(R0402-0201)'                 | '22'      | '5%'    | '1/16W'  | 'DISCRETE' | 'RES CHIP 22 1/16W 5%(0402)'                       | 'CHIP0402'     | ''          | ''            | '20100811'
 '22'         | '5%'      | '1/16W'  | '0402LF'  | 'EMPTY'  | 'CS02202JB22'(!)        = 'End of Design' | 'Comp-Approve'     | 'CS02202JB22'           |'R0402'| '(R0402-0201)'                 | '22'      | '5%'    | '1/16W'  | 'IO'       | 'RES CHIP 22 1/16W 5%(0402)'                       | 'CHIP0402'     | ''          | ''            | '20100811'
 '22.1     '  | '1%  '    | '1/16W'  | '0402LF'  | 'CHIP'   | 'CS02212FB09'(!)        = 'End of Design' | 'Comp-Approve'     | 'CS02212FB09'           |'R0402'| '(R0402-0201)'                 | '22.1'    | '1%'    | '1/16W'  | 'DISCRETE' | 'RES CHIP 22.1 1/16W +-1%(0402) L-F'               | 'CHIP0402'     | ''          | ''            | '20100811'
 '22.1     '  | '1%  '    | '1/16W'  | '0402LF'  | 'EMPTY'  | 'CS02212FB09'(!)        = 'End of Design' | 'Comp-Approve'     | 'CS02212FB09'           |'R0402'| '(R0402-0201)'                 | '22.1'    | '1%'    | '1/16W'  | 'IO'       | 'RES CHIP 22.1 1/16W +-1%(0402) L-F'               | 'CHIP0402'     | ''          | ''            | '20100811'
 '33'         | '1%'      | '1/16W'  | '0402LF'  | 'CHIP'   | 'CS03302FB19'(!)        = 'End of Design' | 'Comp-Approve'     | 'CS03302FB19'           |'R0402'| '(R0402-0201)'                 | '33'      | '1%'    | '1/16W'  | 'DISCRETE' | 'RES CHIP 33 1/16W +-1%(0402)'                     | 'CHIP0402'     | ''          | ''            | '20100811'
 '33'         | '1%'      | '1/16W'  | '0402LF'  | 'EMPTY'  | 'CS03302FB19'(!)        = 'End of Design' | 'Comp-Approve'     | 'CS03302FB19'           |'R0402'| '(R0402-0201)'                 | '33'      | '1%'    | '1/16W'  | 'IO'       | 'RES CHIP 33 1/16W +-1%(0402)'                     | 'CHIP0402'     | ''          | ''            | '20100811'
 '75'         | '1%'      | '1/16W'  | '0402LF'  | 'CHIP'   | 'CS07502FB17'(!)        = 'End of Design' | 'Comp-Approve'     | 'CS07502FB17'           |'R0402'| '(R0402-0201)'                 | '75'      | '1%'    | '1/16W'  | 'DISCRETE' | 'RES CHIP 75 1/16W +-1% (0402)'                    | 'CHIP0402'     | ''          | ''            | '20100811'
 '75'         | '1%'      | '1/16W'  | '0402LF'  | 'EMPTY'  | 'CS07502FB17'(!)        = 'End of Design' | 'Comp-Approve'     | 'CS07502FB17'           |'R0402'| '(R0402-0201)'                 | '75'      | '1%'    | '1/16W'  | 'IO'       | 'RES CHIP 75 1/16W +-1% (0402)'                    | 'CHIP0402'     | ''          | ''            | '20100811'
 '2.7K     '  | '5%  '    | '1/16W'  | '0402LF'  | 'CHIP'   | 'CS22702JB16'(!)        = 'End of Design' | 'Comp-Approve'     | 'CS22702JB16'           |'R0402'| '(R0402-0201)'                 | '2.7K'    | '5%'    | '1/16W'  | 'DISCRETE' | 'RES CHIP 2.7K 1/16W +-5%(0402)'                   | 'CHIP0402'     | ''          | ''            | '20100811'
 '2.7K     '  | '5%  '    | '1/16W'  | '0402LF'  | 'EMPTY'  | 'CS22702JB16'(!)        = 'End of Design' | 'Comp-Approve'     | 'CS22702JB16'           |'R0402'| '(R0402-0201)'                 | '2.7K'    | '5%'    | '1/16W'  | 'IO'       | 'RES CHIP 2.7K 1/16W +-5%(0402)'                   | 'CHIP0402'     | ''          | ''            | '20100811'
 '8.2K     '  | '5%  '    | '1/16W'  | '0402LF'  | 'CHIP'   | 'CS28202JB14'(!)        = 'End of Design' | 'Comp-Approve'     | 'CS28202JB14'           |'R0402'| '(R0402-0201)'                 | '8.2K'    | '5%'    | '1/16W'  | 'DISCRETE' | 'RES CHIP 8.2K 1/16W +-5% (0402)'                  | 'CHIP0402'     | ''          | ''            | '20100811'
 '8.2K     '  | '5%  '    | '1/16W'  | '0402LF'  | 'EMPTY'  | 'CS28202JB14'(!)        = 'End of Design' | 'Comp-Approve'     | 'CS28202JB14'           |'R0402'| '(R0402-0201)'                 | '8.2K'    | '5%'    | '1/16W'  | 'IO'       | 'RES CHIP 8.2K 1/16W +-5% (0402)'                  | 'CHIP0402'     | ''          | ''            | '20100811'
 '270K     '  | '5%  '    | '1/16W'  | '0402LF'  | 'CHIP'   | 'CS42702JB10'(!)        = 'End of Design' | 'Comp-Approve'     | 'CS42702JB10'           |'R0402'| '(R0402-0201)'                 | '270K'    | '5%'    | '1/16W'  | 'DISCRETE' | 'RES CHIP 270K(1/16W,+-5%,0402)'                   | 'CHIP0402'     | ''          | ''            | '20100811'
 '270K     '  | '5%  '    | '1/16W'  | '0402LF'  | 'EMPTY'  | 'CS42702JB10'(!)        = 'End of Design' | 'Comp-Approve'     | 'CS42702JB10'           |'R0402'| '(R0402-0201)'                 | '270K'    | '5%'    | '1/16W'  | 'IO'       | 'RES CHIP 270K(1/16W,+-5%,0402)'                   | 'CHIP0402'     | ''          | ''            | '20100811'
 '1.21K    '  | '1%  '    | '1/10W'  | '0603LF'  | 'CHIP'   | 'CS21213F914'(!)        = 'End of Design' | 'Comp-Approve'     | 'CS21213F914'           |'R0603'| '(SMR0603AW)'                  | '1.21K'   | '1%'    | '1/10W'  | 'DISCRETE' | 'RES CHIP 1.21K 1/10W +-1% (0603) EP'              | 'CHIP0603'     | ''          | ''            | '20100811'
 '1.21K    '  | '1%  '    | '1/10W'  | '0603LF'  | 'EMPTY'  | 'CS21213F914'(!)        = 'End of Design' | 'Comp-Approve'     | 'CS21213F914'           |'R0603'| '(SMR0603AW)'                  | '1.21K'   | '1%'    | '1/10W'  | 'IO'       | 'RES CHIP 1.21K 1/10W +-1% (0603) EP'              | 'CHIP0603'     | ''          | ''            | '20100811'
 '1.5K'       | '1%'      | '1/10W'  | '0603LF'  | 'CHIP'   | 'CS21503F911'(!)        = ''              | ''                 | 'CS21503F911'           |'R0603'| '(SMR0603AW)'                  | '1.5K'    | '1%'    | '1/10W ' | 'DISCRETE' | 'RESISTOR CHIP 1.5K 1/10W +-1%(1608)'              | 'CHIP0603'     | ''          | ''            | '20100811'
 '1.5K'       | '1%'      | '1/10W'  | '0603LF'  | 'EMPTY'  | 'CS21503F911'(!)        = ''              | ''                 | 'CS21503F911'           |'R0603'| '(SMR0603AW)'                  | '1.5K'    | '1%'    | '1/10W ' | 'IO'       | 'RESISTOR CHIP 1.5K 1/10W +-1%(1608)'              | 'CHIP0603'     | ''          | ''            | '20100811'
 '2.1K'       | '1%'      | '1/10W'  | '0603LF'  | 'CHIP'   | 'CS22103F901'(!)        = ''              | ''                 | 'CS22103F901'           |'R0603'| '(SMR0603AW)'                  | '2.1K'    | '1%'    | '1/10W ' | 'DISCRETE' | 'RES CHIP 2.1K 1/10W +-1% (0603)'                  | 'CHIP0603'     | ''          | ''            | '20100811'
 '2.1K'       | '1%'      | '1/10W'  | '0603LF'  | 'EMPTY'  | 'CS22103F901'(!)        = ''              | ''                 | 'CS22103F901'           |'R0603'| '(SMR0603AW)'                  | '2.1K'    | '1%'    | '1/10W ' | 'IO'       | 'RES CHIP 2.1K 1/10W +-1% (0603)'                  | 'CHIP0603'     | ''          | ''            | '20100811'
 '44.2'       | '1%'      | '1/10W'  | '0603LF'  | 'CHIP'   | 'CS04423F911'(!)        = ''              | ''                 | 'CS04423F911'           |'R0603'| '(SMR0603AW)'                  | '44.2'    | '1%'    | '1/10W ' | 'DISCRETE' | 'RES CHIP 44.2 1/10W +-1%(0603)L-F'                | 'CHIP0603'     | ''          | ''            | '20100811'
 '44.2'       | '1%'      | '1/10W'  | '0603LF'  | 'EMPTY'  | 'CS04423F911'(!)        = ''              | ''                 | 'CS04423F911'           |'R0603'| '(SMR0603AW)'                  | '44.2'    | '1%'    | '1/10W ' | 'IO'       | 'RES CHIP 44.2 1/10W +-1%(0603)L-F'                | 'CHIP0603'     | ''          | ''            | '20100811'
 '1.1K'       | '1%'      | '1/10W'  | '0603LF'  | 'CHIP'   | 'CS21103F916'(!)        = ''              | ''                 | 'CS21103F916'           |'R0603'| '(SMR0603AW)'                  | '1.1K'    | '1%'    | '1/10W ' | 'DISCRETE' | 'RES CHIP 1.1K 1/10W +-1%(0603)'                   | 'CHIP0603'     | ''          | ''            | '20100811'
 '1.1K'       | '1%'      | '1/10W'  | '0603LF'  | 'EMPTY'  | 'CS21103F916'(!)        = ''              | ''                 | 'CS21103F916'           |'R0603'| '(SMR0603AW)'                  | '1.1K'    | '1%'    | '1/10W ' | 'IO'       | 'RES CHIP 1.1K 1/10W +-1%(0603)'                   | 'CHIP0603'     | ''          | ''            | '20100811'
 '240'        | '5%'      | '1/16W'  | '0402LF'  | 'CHIP'   | 'CS12402JB13'(!)        = 'End of Design' | 'Comp-Approve'     | 'CS12402JB13'           |'R0402'| '(R0402-0201)'                 | '240'     | '5%'    | '1/16W'  | 'DISCRETE' | 'RES CHIP 240 1/16W +-5%(0402)'                    | 'CHIP0402'     | ''          | ''            | '20100817'
 '240'        | '5%'      | '1/16W'  | '0402LF'  | 'EMPTY'  | 'CS12402JB13'(!)        = 'End of Design' | 'Comp-Approve'     | 'CS12402JB13'           |'R0402'| '(R0402-0201)'                 | '240'     | '5%'    | '1/16W'  | 'IO'       | 'RES CHIP 240 1/16W +-5%(0402)'                    | 'CHIP0402'     | ''          | ''            | '20100817'
 '240'        | '1%'      | '1/16W'  | '0402LF'  | 'CHIP'   | 'CS12402FB03'(!)        = 'End of Design' | 'Comp-Release Qty' | 'CS12402FB03'           |'R0402'| '(R0402-0201)'                 | '240'     | '1%'    | '1/16W'  | 'DISCRETE' | 'RES CHIP 240 1/16W +-1%(0402)'                    | 'CHIP0402'     | ''          | ''            | '20100827'
 '240'        | '1%'      | '1/16W'  | '0402LF'  | 'EMPTY'  | 'CS12402FB03'(!)        = 'End of Design' | 'Comp-Release Qty' | 'CS12402FB03'           |'R0402'| '(R0402-0201)'                 | '240'     | '1%'    | '1/16W'  | 'IO'       | 'RES CHIP 240 1/16W +-1%(0402)'                    | 'CHIP0402'     | ''          | ''            | '20100827'
 '5.1'        | '5%'      | '1/16W'  | '0402LF'  | 'CHIP'   | 'CS-5102JB03'(!)        = 'End of Design' | 'Comp-Approve'     | 'CS-5102JB03'           |'R0402'| '(R0402-0201)'                 | '5.1'     | '5%'    | '1/16W ' | 'DISCRETE' | 'RES CHIP 5.1 1/16W +-5%(0402)'                    | 'CHIP0402'     | ''          | ''            | '20100827'
 '5.1'        | '5%'      | '1/16W'  | '0402LF'  | 'EMPTY'  | 'CS-5102JB03'(!)        = 'End of Design' | 'Comp-Approve'     | 'CS-5102JB03'           |'R0402'| '(R0402-0201)'                 | '5.1'     | '5%'    | '1/16W ' | 'IO'       | 'RES CHIP 5.1 1/16W +-5%(0402)'                    | 'CHIP0402'     | ''          | ''            | '20100827'
 '82'         | '5%'      | '1/16W'  | '0402LF'  | 'CHIP'   | 'CS08202JB11'(!)        = 'End of Design' | 'Comp-Approve'     | 'CS08202JB11'           |'R0402'| '(R0402-0201)'                 | '82'      | '5%'    | '1/16W'  | 'DISCRETE' | 'RES CHIP 82 1/16W +-5% (0402)'                    | 'CHIP0402'     | ''          | ''            | '20100827'
 '82'         | '5%'      | '1/16W'  | '0402LF'  | 'EMPTY'  | 'CS08202JB11'(!)        = 'End of Design' | 'Comp-Approve'     | 'CS08202JB11'           |'R0402'| '(R0402-0201)'                 | '82'      | '5%'    | '1/16W'  | 'IO'       | 'RES CHIP 82 1/16W +-5% (0402)'                    | 'CHIP0402'     | ''          | ''            | '20100827'
 '36'         | '5%'      | '1/16W'  | '0402LF'  | 'CHIP'   | 'CS03602JB01'(!)        = 'End of Design' | 'End of Life'      | 'CS03602JB01'           |'R0402_EOL'| '(R0402-0201)'                 | '82'      | '5%'    | '1/16W'  | 'DISCRETE' | 'RES CHIP 36 1/16W +-5%(0402)'                     | 'CHIP0402'     | ''          | ''            | '20100827'
 '36'         | '5%'      | '1/16W'  | '0402LF'  | 'EMPTY'  | 'CS03602JB01'(!)        = 'End of Design' | 'End of Life'      | 'CS03602JB01'           |'R0402_EOL'| '(R0402-0201)'                 | '82'      | '5%'    | '1/16W'  | 'IO'       | 'RES CHIP 36 1/16W +-5%(0402)'                     | 'CHIP0402'     | ''          | ''            | '20100827'
 '37.4'       | '1%'      | '1/16W'  | '0402LF'  | 'CHIP'   | 'CS03742FB11'(!)        = 'End of Design' | 'Comp-Approve'     | 'CS03742FB11'           |'R0402'| '(R0402-0201)'                 | '37.4'    | '1%  '  | '1/16W'  | 'DISCRETE' | 'RES CHIP 37.4 1/16W +-1%(0402)'                   | 'CHIP0402'     | ''          | ''            | '20100831'
 '37.4'       | '1%'      | '1/16W'  | '0402LF'  | 'EMPTY'  | 'CS03742FB11'(!)        = 'End of Design' | 'Comp-Approve'     | 'CS03742FB11'           |'R0402'| '(R0402-0201)'                 | '37.4'    | '1%  '  | '1/16W'  | 'IO'       | 'RES CHIP 37.4 1/16W +-1%(0402)'                   | 'CHIP0402'     | ''          | ''            | '20100831'
 '200'        | '1%'      | '1/16W'  | '0402LF'  | 'CHIP'   | 'CS12002FB25'(!)        = 'End of Design' | 'Comp-Approve'     | 'CS12002FB25'           |'R0402'| '(R0402-0201)'                 | '200'     | '1%'    | '1/16W'  | 'DISCRETE' | 'RES CHIP 200 1/16W +-1%(0402)'                    | 'CHIP0402'     | ''          | ''            | '20100831'
 '200'        | '1%'      | '1/16W'  | '0402LF'  | 'EMPTY'  | 'CS12002FB25'(!)        = 'End of Design' | 'Comp-Approve'     | 'CS12002FB25'           |'R0402'| '(R0402-0201)'                 | '200'     | '1%'    | '1/16W'  | 'IO'       | 'RES CHIP 200 1/16W +-1%(0402)'                    | 'CHIP0402'     | ''          | ''            | '20100831'
 '26.1 '      | '1%'      | '1/16W'  | '0402LF'  | 'CHIP'   | 'CS02612FB00'(!)        = 'End of Design' | 'Comp-Approve'     | 'CS02612FB00'           |'R0402'| '(R0402-0201)'                 | '26.1'    | '1%'    | '1/16W ' | 'DISCRETE' | 'RES CHIP 26.1 1/16W +-1%(0402)'                   | 'CHIP0402'     | ''          | ''            | '20100831'
 '26.1 '      | '1%'      | '1/16W'  | '0402LF'  | 'EMPTY'  | 'CS02612FB00'(!)        = 'End of Design' | 'Comp-Approve'     | 'CS02612FB00'           |'R0402'| '(R0402-0201)'                 | '26.1'    | '1%'    | '1/16W ' | 'IO'       | 'RES CHIP 26.1 1/16W +-1%(0402)'                   | 'CHIP0402'     | ''          | ''            | '20100831'
 '20'         | '5%'      | '1/16W'  | '0402LF'  | 'CHIP'   | 'CS02002JB17'(!)        = 'End of Design' | 'Comp-Approve'     | 'CS02002JB17'           |'R0402'| '(R0402-0201)'                 | '20'      | '5%'    | '1/16W'  | 'DISCRETE' | 'RES CHIP 20 1/16W +-5% (0402)'                    | 'CHIP0402'     | ''          | ''            | '20100831'
 '20'         | '5%'      | '1/16W'  | '0402LF'  | 'EMPTY'  | 'CS02002JB17'(!)        = 'End of Design' | 'Comp-Approve'     | 'CS02002JB17'           |'R0402'| '(R0402-0201)'                 | '20'      | '5%'    | '1/16W'  | 'IO'       | 'RES CHIP 20 1/16W +-5% (0402)'                    | 'CHIP0402'     | ''          | ''            | '20100831'
 '75'         | '5%'      | '1/16W'  | '0402LF'  | 'CHIP'   | 'CS07502JB27'(!)        = 'End of Design' | 'Comp-Approve'     | 'CS07502JB27'           |'R0402'| '(R0402-0201)'                 | '75'      | '5%'    | '1/16W'  | 'DISCRETE' | 'RES CHIP 75 1/16W +-5% (0402)'                    | 'CHIP0402'     | ''          | ''            | '20100831'
 '75'         | '5%'      | '1/16W'  | '0402LF'  | 'EMPTY'  | 'CS07502JB27'(!)        = 'End of Design' | 'Comp-Approve'     | 'CS07502JB27'           |'R0402'| '(R0402-0201)'                 | '75'      | '5%'    | '1/16W'  | 'IO'       | 'RES CHIP 75 1/16W +-5% (0402)'                    | 'CHIP0402'     | ''          | ''            | '20100831'
 '1.2K '      | '5%'      | '1/16W'  | '0402LF'  | 'CHIP'   | 'CS21202JB15'(!)        = 'End of Design' | 'Comp-Approve'     | 'CS21202JB15'           |'R0402'| '(R0402-0201)'                 | '1.2K'    | '5%'    | '1/16W'  | 'DISCRETE' | 'RES CHIP 1.2K 1/16W +-5% (0402)'                  | 'CHIP0402'     | ''          | ''            | '20100831'
 '1.2K '      | '5%'      | '1/16W'  | '0402LF'  | 'EMPTY'  | 'CS21202JB15'(!)        = 'End of Design' | 'Comp-Approve'     | 'CS21202JB15'           |'R0402'| '(R0402-0201)'                 | '1.2K'    | '5%'    | '1/16W'  | 'IO'       | 'RES CHIP 1.2K 1/16W +-5% (0402)'                  | 'CHIP0402'     | ''          | ''            | '20100831'
 '1.54K'      | '1%'      | '1/10W'  | '0603LF'  | 'CHIP'   | 'CS21543F927'(!)        = ''              | ''                 | 'CS21543F927'           |'R0603'| '(SMR0603AW)'                  | '1.54K'   | '5%'    | '1/10W'  | 'DISCRETE' | 'RESISTOR CHIP 1.54K 1/10W+-1%(0603)'              | 'CHIP0603'     | ''          | ''            | '20100831'
 '1.54K'      | '1%'      | '1/10W'  | '0603LF'  | 'EMPTY'  | 'CS21543F927'(!)        = ''              | ''                 | 'CS21543F927'           |'R0603'| '(SMR0603AW)'                  | '1.54K'   | '5%'    | '1/10W'  | 'IO'       | 'RESISTOR CHIP 1.54K 1/10W+-1%(0603)'              | 'CHIP0603'     | ''          | ''            | '20100831'
 '294'        | '1%'      | '1/16W'  | '0402LF'  | 'CHIP'   | 'CS12942FB00'(!)        = 'End of Design' | 'Comp-Approve'     | 'CS12942FB00'           |'R0402'| '(R0402-0201)'                 | '294'     | '1%'    | '1/16W'  | 'DISCRETE' | 'RES CHIP 294 1/16W +-1%(0402)'                    | 'CHIP0402'     | ''          | ''            | '20100909'
 '294'        | '1%'      | '1/16W'  | '0402LF'  | 'EMPTY'  | 'CS12942FB00'(!)        = 'End of Design' | 'Comp-Approve'     | 'CS12942FB00'           |'R0402'| '(R0402-0201)'                 | '294'     | '1%'    | '1/16W'  | 'IO'       | 'RES CHIP 294 1/16W +-1%(0402)'                    | 'CHIP0402'     | ''          | ''            | '20100909'
 '180'        | '1%'      | '1/16W'  | '0402LF'  | 'CHIP'   | 'CS11802FB05'(!)        = 'End of Design' | 'Comp-Approve'     | 'CS11802FB05'           |'R0402'| '(R0402-0201)'                 | '180'     | '1%'    | '1/16W'  | 'DISCRETE' | 'RES CHIP 180 1/16W +-1% (0402)'                   | 'CHIP0402'     | ''          | ''            | '20100913'
 '180'        | '1%'      | '1/16W'  | '0402LF'  | 'EMPTY'  | 'CS11802FB05'(!)        = 'End of Design' | 'Comp-Approve'     | 'CS11802FB05'           |'R0402'| '(R0402-0201)'                 | '180'     | '1%'    | '1/16W'  | 'IO'       | 'RES CHIP 180 1/16W +-1% (0402)'                   | 'CHIP0402'     | ''          | ''            | '20100913'
 '2.67K'      | '1%'      | '1/16W'  | '0402LF'  | 'CHIP'   | 'CS22672FB12'(!)        = 'End of Design' | 'Comp-Approve'     | 'CS22672FB12'           |'R0402'| '(R0402-0201)'                 | '2.67K'   | '1%'    | '1/16W'  | 'DISCRETE' | 'RES CHIP 2.67K 1/16W +-1%(0402)'                  | 'CHIP0402'     | ''          | ''            | '20100919'
 '2.67K'      | '1%'      | '1/16W'  | '0402LF'  | 'EMPTY'  | 'CS22672FB12'(!)        = 'End of Design' | 'Comp-Approve'     | 'CS22672FB12'           |'R0402'| '(R0402-0201)'                 | '2.67K'   | '1%'    | '1/16W'  | 'IO'       | 'RES CHIP 2.67K 1/16W +-1%(0402)'                  | 'CHIP0402'     | ''          | ''            | '20100919'
 '294K'       | '1%'      | '1/16W'  | '0402LF'  | 'CHIP'   | 'CS42942FB13'(!)        = 'End of Design' | 'Comp-Approve'     | 'CS42942FB13'           |'R0402'| '(R0402-0201)'                 | '294K'    | '1%'    | '1/16W'  | 'DISCRETE' | 'RES CHIP 294K 1/16W +-1%(0402)'                   | 'CHIP0402'     | ''          | ''            | '20100919'
 '294K'       | '1%'      | '1/16W'  | '0402LF'  | 'EMPTY'  | 'CS42942FB13'(!)        = 'End of Design' | 'Comp-Approve'     | 'CS42942FB13'           |'R0402'| '(R0402-0201)'                 | '294K'    | '1%'    | '1/16W'  | 'IO'       | 'RES CHIP 294K 1/16W +-1%(0402)'                   | 'CHIP0402'     | ''          | ''            | '20100919'
 '27.4'       | '1%'      | '1/16W'  | '0402LF'  | 'CHIP'   | 'CS02742FB19'(!)        = 'End of Design' | 'Comp-Release Qty' | 'CS02742FB19'           |'R0402'| '(R0402-0201)'                 | '27.4'    | '1%'    | '1/16W'  | 'DISCRETE' | 'RES CHIP 27.4 1/16W +-1%(0402)'                   | 'CHIP0402'     | ''          | ''            | '20100923'
 '27.4'       | '1%'      | '1/16W'  | '0402LF'  | 'EMPTY'  | 'CS02742FB19'(!)        = 'End of Design' | 'Comp-Release Qty' | 'CS02742FB19'           |'R0402'| '(R0402-0201)'                 | '27.4'    | '1%'    | '1/16W'  | 'IO'       | 'RES CHIP 27.4 1/16W +-1%(0402)'                   | 'CHIP0402'     | ''          | ''            | '20100923'
 '39'         | '5%'      | '1/16W'  | '0402LF'  | 'CHIP'   | 'CS03902JB21'(!)        = 'End of Design' | 'Comp-Approve'     | 'CS03902JB21'           |'R0402'| '(R0402-0201)'                 | '39'      | '5%'    | '1/16W'  | 'DISCRETE' | 'RES CHIP 39 1/16W +-5%(0402)'                     | 'CHIP0402'     | ''          | ''            | '20100923'
 '39'         | '5%'      | '1/16W'  | '0402LF'  | 'EMPTY'  | 'CS03902JB21'(!)        = 'End of Design' | 'Comp-Approve'     | 'CS03902JB21'           |'R0402'| '(R0402-0201)'                 | '39'      | '5%'    | '1/16W'  | 'IO'       | 'RES CHIP 39 1/16W +-5%(0402)'                     | 'CHIP0402'     | ''          | ''            | '20100923'
 '42.2'       | '1%'      | '1/16W'  | '0402LF'  | 'CHIP'   | 'CS04222FB01'(!)        = 'End of Design' | 'Comp-Approve'     | 'CS04222FB01'           |'R0402'| '(R0402-0201)'                 | '42.2'    | '1%'    | '1/16W'  | 'DISCRETE' | 'RES CHIP 42.2 1/16W +-1%(0402)'                   | 'CHIP0402'     | ''          | ''            | '20100923'
 '42.2'       | '1%'      | '1/16W'  | '0402LF'  | 'EMPTY'  | 'CS04222FB01'(!)        = 'End of Design' | 'Comp-Approve'     | 'CS04222FB01'           |'R0402'| '(R0402-0201)'                 | '42.2'    | '1%'    | '1/16W'  | 'IO'       | 'RES CHIP 42.2 1/16W +-1%(0402)'                   | 'CHIP0402'     | ''          | ''            | '20100923'
 '475'        | '1%'      | '1/16W'  | '0402LF'  | 'CHIP'   | 'CS14752FB11'(!)        = 'End of Design' | 'Comp-Approve'     | 'CS14752FB11'           |'R0402'| '(R0402-0201)'                 | '475'     | '1%'    | '1/16W'  | 'DISCRETE' | 'RES CHIP 475 1/16W +-1%(0402)'                    | 'CHIP0402'     | ''          | ''            | '20100923'
 '475'        | '1%'      | '1/16W'  | '0402LF'  | 'EMPTY'  | 'CS14752FB11'(!)        = 'End of Design' | 'Comp-Approve'     | 'CS14752FB11'           |'R0402'| '(R0402-0201)'                 | '475'     | '1%'    | '1/16W'  | 'IO'       | 'RES CHIP 475 1/16W +-1%(0402)'                    | 'CHIP0402'     | ''          | ''            | '20100923'
 '2.74K'      | '1%'      | '1/16W'  | '0402LF'  | 'CHIP'   | 'CS22742FB00'(!)        = 'End of Design' | 'Comp-Approve'     | 'CS22742FB00'           |'R0402'| '(R0402-0201)'                 | '2.74K'   | '1%'    | '1/16W'  | 'DISCRETE' | 'RES CHIP 2.74K 1/16W +-1%(0402)'                  | 'CHIP0402'     | ''          | ''            | '20100923'
 '2.74K'      | '1%'      | '1/16W'  | '0402LF'  | 'EMPTY'  | 'CS22742FB00'(!)        = 'End of Design' | 'Comp-Approve'     | 'CS22742FB00'           |'R0402'| '(R0402-0201)'                 | '2.74K'   | '1%'    | '1/16W'  | 'IO'       | 'RES CHIP 2.74K 1/16W +-1%(0402)'                  | 'CHIP0402'     | ''          | ''            | '20100923'
 '2.74K'      | '1%'      | '1/10W'  | '0603LF'  | 'CHIP'   | 'CS22743F935'(!)        = ''              | ''                 | 'CS22743F935'           |'R0603'| '(SMR0603AW)'                  | '2.74K'   | '1%'    | '1/10W'  | 'DISCRETE' | 'RES CHIP 2.74K 1/10W +-1%(0603) EP'               | 'CHIP0402'     | ''          | ''            | '20100923'
 '2.74K'      | '1%'      | '1/10W'  | '0603LF'  | 'EMPTY'  | 'CS22743F935'(!)        = ''              | ''                 | 'CS22743F935'           |'R0603'| '(SMR0603AW)'                  | '2.74K'   | '1%'    | '1/10W'  | 'IO'       | 'RES CHIP 2.74K 1/10W +-1%(0603) EP'               | 'CHIP0402'     | ''          | ''            | '20100923'
 '0.015'      | '1%'      | '1/2W'   | '2010LF'  | 'CHIP'   | 'CS+0157FJ00'(!)        = 'End of Design' | 'Comp-Release Qty' | 'CS+0157FJ00'           |'R2010XA'| '(SMR2010AW)'                  | '0.015'   | '1%'    | '1/2W'   | 'DISCRETE' | 'RES CHIP 0.015 1/2W +-1%(2010)'                   | 'CHIP2010'     | ''          | ''            | '20100927'
 '0.015'      | '1%'      | '1/2W'   | '2010LF'  | 'EMPTY'  | 'CS+0157FJ00'(!)        = 'End of Design' | 'Comp-Release Qty' | 'CS+0157FJ00'           |'R2010XA'| '(SMR2010AW)'                  | '0.015'   | '1%'    | '1/2W'   | 'IO'       | 'RES CHIP 0.015 1/2W +-1%(2010)'                   | 'CHIP2010'     | ''          | ''            | '20100927'
 '274'        | '1%'      | '1/10W'  | '0603LF'  | 'CHIP'   | 'CS12743F900'(!)        = 'End of Design' | 'Comp-Approve'     | 'CS12743F900'           |'R0603'| '(SMR0603AW)'                  | '274'     | '1%'    | '1/10W'  | 'DISCRETE' | 'RES CHIP 274 1/10W +-1%(0603)'                    | 'CHIP0603'     | ''          | ''            | '20100927'
 '274'        | '1%'      | '1/10W'  | '0603LF'  | 'EMPTY'  | 'CS12743F900'(!)        = 'End of Design' | 'Comp-Approve'     | 'CS12743F900'           |'R0603'| '(SMR0603AW)'                  | '274'     | '1%'    | '1/10W'  | 'IO'       | 'RES CHIP 274 1/10W +-1%(0603)'                    | 'CHIP0603'     | ''          | ''            | '20100927'
 '412'        | '1%'      | '1/16W'  | '0402LF'  | 'CHIP'   | 'CS14122FB15'(!)        = 'End of Design' | 'Comp-Approve'     | 'CS14122FB15'           |'R0402'| '(R0402-0201)'                 | '412'     | '1%'    | '1/16W'  | 'DISCRETE' | 'RESISTOR CHIP 412 1/16W +-1%(0402)'               | 'CHIP0402'     | ''          | ''            | '20100929'
 '412'        | '1%'      | '1/16W'  | '0402LF'  | 'EMPTY'  | 'CS14122FB15'(!)        = 'End of Design' | 'Comp-Approve'     | 'CS14122FB15'           |'R0402'| '(R0402-0201)'                 | '412'     | '1%'    | '1/16W'  | 'IO'       | 'RESISTOR CHIP 412 1/16W +-1%(0402)'               | 'CHIP0402'     | ''          | ''            | '20100929'
 '200K'       | '1%'      | '1/16W'  | '0402LF'  | 'CHIP'   | 'CS42002FB12'(!)        = 'End of Design' | 'Comp-Approve'     | 'CS42002FB12'           |'R0402'| '(R0402-0201)'                 | '200K'    | '1%'    | '1/16W'  | 'DISCRETE' | 'RES CHIP 200K 1/16W+-1%(0402)'                    | 'CHIP0402'     | ''          | ''            | '20100929'
 '200K'       | '1%'      | '1/16W'  | '0402LF'  | 'EMPTY'  | 'CS42002FB12'(!)        = 'End of Design' | 'Comp-Approve'     | 'CS42002FB12'           |'R0402'| '(R0402-0201)'                 | '200K'    | '1%'    | '1/16W'  | 'IO'       | 'RES CHIP 200K 1/16W+-1%(0402)'                    | 'CHIP0402'     | ''          | ''            | '20100929'
 '9.1K'       | '1%'      | '1/16W'  | '0402LF'  | 'CHIP'   | 'CS29102FB10'(!)        = 'End of Design' | 'Comp-Approve'     | 'CS29102FB10'           |'R0402'| '(R0402-0201)'                 | '9.1K'    | '1%'    | '1/16W'  | 'DISCRETE' | 'RES CHIP 9.1K 1/16W +-1%(0402)'                   | 'CHIP0402'     | ''          | ''            | '20101001'
 '9.1K'       | '1%'      | '1/16W'  | '0402LF'  | 'EMPTY'  | 'CS29102FB10'(!)        = 'End of Design' | 'Comp-Approve'     | 'CS29102FB10'           |'R0402'| '(R0402-0201)'                 | '9.1K'    | '1%'    | '1/16W'  | 'IO'       | 'RES CHIP 9.1K 1/16W +-1%(0402)'                   | 'CHIP0402'     | ''          | ''            | '20101001'
 '9.31K'      | '1%'      | '1/16W'  | '0402LF'  | 'CHIP'   | 'CS29312FB13'(!)        = 'End of Design' | 'Comp-Approve'     | 'CS29312FB13'           |'R0402'| '(R0402-0201)'                 | '9.31K'   | '1%'    | '1/16W'  | 'DISCRETE' | 'RES CHIP 9.31K 1/16W +-1%(0402)'                  | 'CHIP0402'     | ''          | ''            | '20101001'
 '9.31K'      | '1%'      | '1/16W'  | '0402LF'  | 'EMPTY'  | 'CS29312FB13'(!)        = 'End of Design' | 'Comp-Approve'     | 'CS29312FB13'           |'R0402'| '(R0402-0201)'                 | '9.31K'   | '1%'    | '1/16W'  | 'IO'       | 'RES CHIP 9.31K 1/16W +-1%(0402)'                  | 'CHIP0402'     | ''          | ''            | '20101001'
 '0.1'        | '1%'      | '1/4W'   | '0805LF'  | 'CHIP'   | 'CS+1006FA18'(!)        = ''              | ''                 | 'CS+1006FA18'           |'R0805'| '(SMR0805AW)'                  | '0.1'     | '1%'    | '1/4W'   | 'DISCRETE' | 'RES CHIP 0.1 1/4W +-1%(0805)EU'                   | 'CHIP0805'     | ''          | ''            | '20100930'
 '0.1'        | '1%'      | '1/4W'   | '0805LF'  | 'EMPTY'  | 'CS+1006FA18'(!)        = ''              | ''                 | 'CS+1006FA18'           |'R0805'| '(SMR0805AW)'                  | '0.1'     | '1%'    | '1/4W'   | 'IO'       | 'RES CHIP 0.1 1/4W +-1%(0805)EU'                   | 'CHIP0805'     | ''          | ''            | '20100930'
 '22'         | '1%'      | '1/16W'  | '0402LF'  | 'CHIP'   | 'CS02202FB12'(!)        = 'End of Design' | 'Comp-Approve'     | 'CS02202FB12'           |'R0402'| '(R0402-0201)'                 | '22'      | '1%'    | '1/16W'  | 'DISCRETE' | 'RES CHIP 22 1/16W +-1%(0402)'                     | 'CHIP0402'     | ''          | ''            | '20100930'
 '22'         | '1%'      | '1/16W'  | '0402LF'  | 'EMPTY'  | 'CS02202FB12'(!)        = 'End of Design' | 'Comp-Approve'     | 'CS02202FB12'           |'R0402'| '(R0402-0201)'                 | '22'      | '1%'    | '1/16W'  | 'IO'       | 'RES CHIP 22 1/16W +-1%(0402)'                     | 'CHIP0402'     | ''          | ''            | '20100930'
 '22'         | '5%'      | '1/8W'   | '0805LF'  | 'CHIP'   | 'CS02204JA18'(!)        = ''              | ''                 | 'CS02204JA18'           |'R0805'| '(SMR0805AW)'                  | '22'      | '5%'    | '1/8W'   | 'DISCRETE' | 'RES CHIP 22 1/8W +-5%(0805)'                      | 'CHIP0805'     | ''          | ''            | '20100930'
 '22'         | '5%'      | '1/8W'   | '0805LF'  | 'EMPTY'  | 'CS02204JA18'(!)        = ''              | ''                 | 'CS02204JA18'           |'R0805'| '(SMR0805AW)'                  | '22'      | '5%'    | '1/8W'   | 'IO'       | 'RES CHIP 22 1/8W +-5%(0805)'                      | 'CHIP0805'     | ''          | ''            | '20100930'
 '24.9'       | '1%'      | '1/16W'  | '0402LF'  | 'CHIP'   | 'CS02492FB29'(!)        = 'End of Design' | 'Comp-Approve'     | 'CS02492FB29'           |'R0402'| '(R0402-0201)'                 | '24.9'    | '1%'    | '1/16W'  | 'DISCRETE' | 'RES CHIP 24.9 1/16W +-1%(0402)'                   | 'CHIP0402'     | ''          | ''            | '20100930'
 '24.9'       | '1%'      | '1/16W'  | '0402LF'  | 'EMPTY'  | 'CS02492FB29'(!)        = 'End of Design' | 'Comp-Approve'     | 'CS02492FB29'           |'R0402'| '(R0402-0201)'                 | '24.9'    | '1%'    | '1/16W'  | 'IO'       | 'RES CHIP 24.9 1/16W +-1%(0402)'                   | 'CHIP0402'     | ''          | ''            | '20100930'
 '51'         | '5%'      | '1/16W'  | '0402LF'  | 'CHIP'   | 'CS05102JB35'(!)        = 'End of Design' | 'Comp-Approve'     | 'CS05102JB35'           |'R0402'| '(R0402-0201)'                 | '51'      | '5%'    | '1/16W'  | 'DISCRETE' | 'RES CHIP 51 1/16W +-5%(0402)'                     | 'CHIP0402'     | ''          | ''            | '20100930'
 '51'         | '5%'      | '1/16W'  | '0402LF'  | 'EMPTY'  | 'CS05102JB35'(!)        = 'End of Design' | 'Comp-Approve'     | 'CS05102JB35'           |'R0402'| '(R0402-0201)'                 | '51'      | '5%'    | '1/16W'  | 'IO'       | 'RES CHIP 51 1/16W +-5%(0402)'                     | 'CHIP0402'     | ''          | ''            | '20100930'
 '51.1'       | '1%'      | '1/10W'  | '0603LF'  | 'CHIP'   | 'CS05113F918'(!)        = ''              | ''                 | 'CS05113F918'           |'R0603'| '(SMR0603AW)'                  | '51.1'    | '1%'    | '1/10W'  | 'DISCRETE' | 'RES CHIP 51.1 1/10W +-1%(0603)'                   | 'CHIP0603'     | ''          | ''            | '20100930'
 '51.1'       | '1%'      | '1/10W'  | '0603LF'  | 'EMPTY'  | 'CS05113F918'(!)        = ''              | ''                 | 'CS05113F918'           |'R0603'| '(SMR0603AW)'                  | '51.1'    | '1%'    | '1/10W'  | 'IO'       | 'RES CHIP 51.1 1/10W +-1%(0603)'                   | 'CHIP0603'     | ''          | ''            | '20100930'
 '169'        | '1%'      | '1/16W'  | '0402LF'  | 'CHIP'   | 'CS11692FB09'(!)        = 'End of Design' | 'Comp-Approve'     | 'CS11692FB09'           |'R0402'| '(R0402-0201)'                 | '169'     | '1%'    | '1/16W'  | 'DISCRETE' | 'RES CHIP 169 1/16W +-1%(0402)'                    | 'CHIP0402'     | ''          | ''            | '20100930'
 '169'        | '1%'      | '1/16W'  | '0402LF'  | 'EMPTY'  | 'CS11692FB09'(!)        = 'End of Design' | 'Comp-Approve'     | 'CS11692FB09'           |'R0402'| '(R0402-0201)'                 | '169'     | '1%'    | '1/16W'  | 'IO'       | 'RES CHIP 169 1/16W +-1%(0402)'                    | 'CHIP0402'     | ''          | ''            | '20100930'
 '200'        | '5%'      | '1/10W'  | '0603LF'  | 'CHIP'   | 'CS12003J940'(!)        = 'End of Design' | 'Comp-Approve'     | 'CS12003J940'           |'R0603'| '(SMR0603AW)'                  | '200'     | '5%'    | '1/10W'  | 'DISCRETE' | 'RESISTOR CHIP 200 1/10W+-5%(0603)'                | 'CHIP0603'     | ''          | ''            | '20100930'
 '200'        | '5%'      | '1/10W'  | '0603LF'  | 'EMPTY'  | 'CS12003J940'(!)        = 'End of Design' | 'Comp-Approve'     | 'CS12003J940'           |'R0603'| '(SMR0603AW)'                  | '200'     | '5%'    | '1/10W'  | 'IO'       | 'RESISTOR CHIP 200 1/10W+-5%(0603)'                | 'CHIP0603'     | ''          | ''            | '20100930'
 '392'        | '1%'      | '1/16W'  | '0402LF'  | 'CHIP'   | 'CS13922FB11'(!)        = 'End of Design' | 'Comp-Approve'     | 'CS13922FB11'           |'R0402'| '(R0402-0201)'                 | '392'     | '1%'    | '1/16W'  | 'DISCRETE' | 'RES CHIP 392 1/16W +-1%(0402)'                    | 'CHIP0402'     | ''          | ''            | '20100930'
 '392'        | '1%'      | '1/16W'  | '0402LF'  | 'EMPTY'  | 'CS13922FB11'(!)        = 'End of Design' | 'Comp-Approve'     | 'CS13922FB11'           |'R0402'| '(R0402-0201)'                 | '392'     | '1%'    | '1/16W'  | 'IO'       | 'RES CHIP 392 1/16W +-1%(0402)'                    | 'CHIP0402'     | ''          | ''            | '20100930'
 '510'        | '5%'      | '1/16W'  | '0402LF'  | 'CHIP'   | 'CS15102JB00'(!)        = 'End of Design' | 'Comp-Approve'     | 'CS15102JB00'           |'R0402'| '(R0402-0201)'                 | '510'     | '5%'    | '1/16W'  | 'DISCRETE' | 'RES CHIP 510 1/16W +-5%(0402)'                    | 'CHIP0402'     | ''          | ''            | '20100930'
 '510'        | '5%'      | '1/16W'  | '0402LF'  | 'EMPTY'  | 'CS15102JB00'(!)        = 'End of Design' | 'Comp-Approve'     | 'CS15102JB00'           |'R0402'| '(R0402-0201)'                 | '510'     | '5%'    | '1/16W'  | 'IO'       | 'RES CHIP 510 1/16W +-5%(0402)'                    | 'CHIP0402'     | ''          | ''            | '20100930'
 '1.27K'      | '1%'      | '1/16W'  | '0402LF'  | 'CHIP'   | 'CS21272FB15'(!)        = 'End of Design' | 'Comp-Approve'     | 'CS21272FB15'           |'R0402'| '(R0402-0201)'                 | '1.27K'   | '1%'    | '1/16W'  | 'DISCRETE' | 'RES CHIP 1.27K 1/16W +-1% (0402)'                 | 'CHIP0402'     | ''          | ''            | '20100930'
 '1.27K'      | '1%'      | '1/16W'  | '0402LF'  | 'EMPTY'  | 'CS21272FB15'(!)        = 'End of Design' | 'Comp-Approve'     | 'CS21272FB15'           |'R0402'| '(R0402-0201)'                 | '1.27K'   | '1%'    | '1/16W'  | 'IO'       | 'RES CHIP 1.27K 1/16W +-1% (0402)'                 | 'CHIP0402'     | ''          | ''            | '20100930'
 '2.2'        | '1%'      | '1/8W'   | '0805LF'  | 'CHIP'   | 'CS-2204FA00'(!)        = 'End of Design' | 'Comp-Approve'     | 'CS-2204FA00'           |'R0805'| '(SMR0805AW)'                  | '2.2'     | '1%'    | '1/8W'   | 'DISCRETE' | 'RES CHIP 2.2 1/8W +-1%(0805)'                     | 'CHIP0805'     | ''          | ''            | '20100930'
 '2.2'        | '1%'      | '1/8W'   | '0805LF'  | 'EMPTY'  | 'CS-2204FA00'(!)        = 'End of Design' | 'Comp-Approve'     | 'CS-2204FA00'           |'R0805'| '(SMR0805AW)'                  | '2.2'     | '1%'    | '1/8W'   | 'IO'       | 'RES CHIP 2.2 1/8W +-1%(0805)'                     | 'CHIP0805'     | ''          | ''            | '20100930'
 '3.01K'      | '1%'      | '1/16W'  | '0402LF'  | 'CHIP'   | 'CS23012FB16'(!)        = 'End of Design' | 'Comp-Approve'     | 'CS23012FB16'           |'R0402'| '(R0402-0201)'                 | '3.01K'   | '1%'    | '1/16W'  | 'DISCRETE' | 'RES CHIP 3.01K 1/16W +-1%(0402)'                  | 'CHIP0402'     | ''          | ''            | '20100930'
 '3.01K'      | '1%'      | '1/16W'  | '0402LF'  | 'EMPTY'  | 'CS23012FB16'(!)        = 'End of Design' | 'Comp-Approve'     | 'CS23012FB16'           |'R0402'| '(R0402-0201)'                 | '3.01K'   | '1%'    | '1/16W'  | 'IO'       | 'RES CHIP 3.01K 1/16W +-1%(0402)'                  | 'CHIP0402'     | ''          | ''            | '20100930'
 '3.65K'      | '1%'      | '1/16W'  | '0402LF'  | 'CHIP'   | 'CS23652FB08'(!)        = 'End of Design' | 'Comp-Approve'     | 'CS23652FB08'           |'R0402'| '(R0402-0201)'                 | '3.65K'   | '1%'    | '1/16W'  | 'DISCRETE' | 'RES CHIP 3.65K 1/16W +-1%(0402)'                  | 'CHIP0402'     | ''          | ''            | '20100930'
 '3.65K'      | '1%'      | '1/16W'  | '0402LF'  | 'EMPTY'  | 'CS23652FB08'(!)        = 'End of Design' | 'Comp-Approve'     | 'CS23652FB08'           |'R0402'| '(R0402-0201)'                 | '3.65K'   | '1%'    | '1/16W'  | 'IO'       | 'RES CHIP 3.65K 1/16W +-1%(0402)'                  | 'CHIP0402'     | ''          | ''            | '20100930'
 '4.75K'      | '1%'      | '1/16W'  | '0402LF'  | 'CHIP'   | 'CS24752FB12'(!)        = 'End of Design' | 'Comp-Approve'     | 'CS24752FB12'           |'R0402'| '(R0402-0201)'                 | '4.75K'   | '1%'    | '1/16W'  | 'DISCRETE' | 'RES CHIP 4.75K 1/16W +-1%(0402)'                  | 'CHIP0402'     | ''          | ''            | '20100930'
 '4.75K'      | '1%'      | '1/16W'  | '0402LF'  | 'EMPTY'  | 'CS24752FB12'(!)        = 'End of Design' | 'Comp-Approve'     | 'CS24752FB12'           |'R0402'| '(R0402-0201)'                 | '4.75K'   | '1%'    | '1/16W'  | 'IO'       | 'RES CHIP 4.75K 1/16W +-1%(0402)'                  | 'CHIP0402'     | ''          | ''            | '20100930'
 '30K'        | '1%'      | '1/16W'  | '0402LF'  | 'CHIP'   | 'CS33002FB13'(!)        = 'End of Design' | 'Comp-Approve'     | 'CS33002FB13'           |'R0402'| '(R0402-0201)'                 | '30K'     | '1%'    | '1/16W'  | 'DISCRETE' | 'RES CHIP 30K 1/16W +-1%(0402)'                    | 'CHIP0402'     | ''          | ''            | '20100930'
 '30K'        | '1%'      | '1/16W'  | '0402LF'  | 'EMPTY'  | 'CS33002FB13'(!)        = 'End of Design' | 'Comp-Approve'     | 'CS33002FB13'           |'R0402'| '(R0402-0201)'                 | '30K'     | '1%'    | '1/16W'  | 'IO'       | 'RES CHIP 30K 1/16W +-1%(0402)'                    | 'CHIP0402'     | ''          | ''            | '20100930'
 '33K'        | '1%'      | '1/10W'  | '0603LF'  | 'CHIP'   | 'CS33303F911'(!)        = 'End of Design' | 'Comp-Approve'     | 'CS33303F911'           |'R0603'| '(SMR0603AW)'                  | '33K'     | '1%'    | '1/10W'  | 'DISCRETE' | 'RES CHIP 33K 1/10W +-1%(0603)'                    | 'CHIP0603'     | ''          | ''            | '20100930'
 '33K'        | '1%'      | '1/10W'  | '0603LF'  | 'EMPTY'  | 'CS33303F911'(!)        = 'End of Design' | 'Comp-Approve'     | 'CS33303F911'           |'R0603'| '(SMR0603AW)'                  | '33K'     | '1%'    | '1/10W'  | 'IO'       | 'RES CHIP 33K 1/10W +-1%(0603)'                    | 'CHIP0603'     | ''          | ''            | '20100930'
 '36K'        | '1%'      | '1/16W'  | '0402LF'  | 'CHIP'   | 'CS33602FB15'(!)        = 'End of Design' | 'Comp-Approve'     | 'CS33602FB15'           |'R0402'| '(R0402-0201)'                 | '36K'     | '1%'    | '1/16W'  | 'DISCRETE' | 'RES CHIP 36K 1/16W +-1%(0402)'                    | 'CHIP0402'     | ''          | ''            | '20100930'
 '36K'        | '1%'      | '1/16W'  | '0402LF'  | 'EMPTY'  | 'CS33602FB15'(!)        = 'End of Design' | 'Comp-Approve'     | 'CS33602FB15'           |'R0402'| '(R0402-0201)'                 | '36K'     | '1%'    | '1/16W'  | 'IO'       | 'RES CHIP 36K 1/16W +-1%(0402)'                    | 'CHIP0402'     | ''          | ''            | '20100930'
 '130K'       | '1%'      | '1/16W'  | '0402LF'  | 'CHIP'   | 'CS41302FB00'(!)        = 'End of Design' | 'Comp-Approve'     | 'CS41302FB00'           |'R0402'| '(R0402-0201)'                 | '130K'    | '1%'    | '1/16W'  | 'DISCRETE' | 'RES CHIP 130K 1/16W +-1%(0402)'                   | 'CHIP0402'     | ''          | ''            | '20100930'
 '130K'       | '1%'      | '1/16W'  | '0402LF'  | 'EMPTY'  | 'CS41302FB00'(!)        = 'End of Design' | 'Comp-Approve'     | 'CS41302FB00'           |'R0402'| '(R0402-0201)'                 | '130K'    | '1%'    | '1/16W'  | 'IO'       | 'RES CHIP 130K 1/16W +-1%(0402)'                   | 'CHIP0402'     | ''          | ''            | '20100930'
 '330K'       | '5%'      | '1/16W'  | '0402LF'  | 'CHIP'   | 'CS43302JB18'(!)        = 'End of Design' | 'Comp-Approve'     | 'CS43302JB18'           |'R0402'| '(R0402-0201)'                 | '330K'    | '5%'    | '1/16W'  | 'DISCRETE' | 'RES CHIP 330K 1/16W +-5% (0402)'                  | 'CHIP0402'     | ''          | ''            | '20100930'
 '330K'       | '5%'      | '1/16W'  | '0402LF'  | 'EMPTY'  | 'CS43302JB18'(!)        = 'End of Design' | 'Comp-Approve'     | 'CS43302JB18'           |'R0402'| '(R0402-0201)'                 | '330K'    | '5%'    | '1/16W'  | 'IO'       | 'RES CHIP 330K 1/16W +-5% (0402)'                  | 'CHIP0402'     | ''          | ''            | '20100930'
 '10M'        | '5%'      | '1/10W'  | '0603LF'  | 'CHIP'   | 'CS61003J946'(!)        = ''              | ''                 | 'CS61003J946'           |'R0603'| '(SMR0603AW)'                  | '10M'     | '5%'    | '1/10W'  | 'DISCRETE' | 'RES CHIP 10M 1/10W +-5%(0603)EP'                  | 'CHIP0603'     | ''          | ''            | '20100930'
 '10M'        | '5%'      | '1/10W'  | '0603LF'  | 'EMPTY'  | 'CS61003J946'(!)        = ''              | ''                 | 'CS61003J946'           |'R0603'| '(SMR0603AW)'                  | '10M'     | '5%'    | '1/10W'  | 'IO'       | 'RES CHIP 10M 1/10W +-5%(0603)EP'                  | 'CHIP0603'     | ''          | ''            | '20100930'
 '499K'       | '1%'      | '1/16W'  | '0402LF'  | 'CHIP'   | 'CS44992FB11'(!)        = 'End of Design' | 'Comp-Approve'     | 'CS44992FB11'           |'R0402'| '(R0402-0201)'                 | '499K'    | '1%'    | '1/16W'  | 'DISCRETE' | 'RES CHIP 499K 1/16W +-1% (0402)'                  | 'CHIP0603'     | ''          | ''            | '20101005'
 '499K'       | '1%'      | '1/16W'  | '0402LF'  | 'EMPTY'  | 'CS44992FB11'(!)        = 'End of Design' | 'Comp-Approve'     | 'CS44992FB11'           |'R0402'| '(R0402-0201)'                 | '499K'    | '1%'    | '1/16W'  | 'IO'       | 'RES CHIP 499K 1/16W +-1% (0402)'                  | 'CHIP0603'     | ''          | ''            | '20101005'
 '42.2'       | '1%'      | '1/10W'  | '0603LF'  | 'CHIP'   | 'CS04223F900'(!)        = ''              | ''                 | 'CS04223F900'           |'R0603'| '(SMR0603AW)'                  | '42.2'    | '1%'    | '1/10W'  | 'DISCRETE' | 'RES CHIP 42.2 1/10W +-1%(0603)'                   | 'CHIP0603'     | ''          | ''            | '20101006'
 '42.2'       | '1%'      | '1/10W'  | '0603LF'  | 'EMPTY'  | 'CS04223F900'(!)        = ''              | ''                 | 'CS04223F900'           |'R0603'| '(SMR0603AW)'                  | '42.2'    | '1%'    | '1/10W'  | 'IO'       | 'RES CHIP 42.2 1/10W +-1%(0603)'                   | 'CHIP0603'     | ''          | ''            | '20101006'
 '402'        | '1%'      | '1/16W'  | '0402LF'  | 'CHIP'   | 'CS14022FB11'(!)        = 'End of Design' | 'Comp-Approve'     | 'CS14022FB11'           |'R0402'| '(R0402-0201)'                 | '402'     | '1%'    | '1/16W'  | 'DISCRETE' | 'RES CHIP 402 1/16W +-1%( 0402)'                   | 'CHIP0402'     | ''          | ''            | '20101006'
 '402'        | '1%'      | '1/16W'  | '0402LF'  | 'EMPTY'  | 'CS14022FB11'(!)        = 'End of Design' | 'Comp-Approve'     | 'CS14022FB11'           |'R0402'| '(R0402-0201)'                 | '402'     | '1%'    | '1/16W'  | 'IO'       | 'RES CHIP 402 1/16W +-1%( 0402)'                   | 'CHIP0402'     | ''          | ''            | '20101006'
 '976'        | '1%'      | '1/16W'  | '0402LF'  | 'CHIP'   | 'CS19762FB19'(!)        = 'End of Design' | 'Comp-Approve'     | 'CS19762FB19'           |'R0402'| '(R0402-0201)'                 | '976'     | '1%'    | '1/16W'  | 'DISCRETE' | 'RES CHIP 976 1/16W +-1%(0402)'                    | 'CHIP0402'     | ''          | ''            | '20101006'
 '976'        | '1%'      | '1/16W'  | '0402LF'  | 'EMPTY'  | 'CS19762FB19'(!)        = 'End of Design' | 'Comp-Approve'     | 'CS19762FB19'           |'R0402'| '(R0402-0201)'                 | '976'     | '1%'    | '1/16W'  | 'IO'       | 'RES CHIP 976 1/16W +-1%(0402)'                    | 'CHIP0402'     | ''          | ''            | '20101006'
 '1.07K'      | '1%'      | '1/16W'  | '0402LF'  | 'CHIP'   | 'CS21072FB18'(!)        = 'End of Design' | 'Comp-Approve'     | 'CS21072FB18'           |'R0402'| '(R0402-0201)'                 | '1.07K'   | '1%'    | '1/16W'  | 'DISCRETE' | 'RES CHIP 1.07K 1/16W,+-1%(0402)'                  | 'CHIP0402'     | ''          | ''            | '20101006'
 '1.07K'      | '1%'      | '1/16W'  | '0402LF'  | 'EMPTY'  | 'CS21072FB18'(!)        = 'End of Design' | 'Comp-Approve'     | 'CS21072FB18'           |'R0402'| '(R0402-0201)'                 | '1.07K'   | '1%'    | '1/16W'  | 'IO'       | 'RES CHIP 1.07K 1/16W,+-1%(0402)'                  | 'CHIP0402'     | ''          | ''            | '20101006'
 '220K'       | '5%'      | '1/10W'  | '0603LF'  | 'CHIP'   | 'CS42203J918'(!)        = ''              | ''                 | 'CS42203J918'           |'R0603'| '(SMR0603AW)'                  | '220K'    | '5%'    | '1/10W'  | 'DISCRETE' | 'RESISTOR CHIP 220K 1/10W +-5%(1608)'              | 'CHIP0603'     | ''          | ''            | '20101006'
 '220K'       | '5%'      | '1/10W'  | '0603LF'  | 'EMPTY'  | 'CS42203J918'(!)        = ''              | ''                 | 'CS42203J918'           |'R0603'| '(SMR0603AW)'                  | '220K'    | '5%'    | '1/10W'  | 'IO'       | 'RESISTOR CHIP 220K 1/10W +-5%(1608)'              | 'CHIP0603'     | ''          | ''            | '20101006'
 '330K'       | '1%'      | '1/10W'  | '0603LF'  | 'CHIP'   | 'CS43303F912'(!)        = 'End of Design' | 'Comp-Approve'     | 'CS43303F912'           |'R0603'| '(SMR0603AW)'                  | '330K'    | '1%'    | '1/10W'  | 'DISCRETE' | 'RES CHIP 330K 1/10W +-1%(0603)'                   | 'CHIP0603'     | ''          | ''            | '20101006'
 '330K'       | '1%'      | '1/10W'  | '0603LF'  | 'EMPTY'  | 'CS43303F912'(!)        = 'End of Design' | 'Comp-Approve'     | 'CS43303F912'           |'R0603'| '(SMR0603AW)'                  | '330K'    | '1%'    | '1/10W'  | 'IO'       | 'RES CHIP 330K 1/10W +-1%(0603)'                   | 'CHIP0603'     | ''          | ''            | '20101006'
 '2.2'        | '5%'      | '1/10W'  | '0603LF'  | 'CHIP'   | 'CS-2203J913'(!)        = ''              | ''                 | 'CS-2203J913'           |'R0603'| '(SMR0603AW)'                  | '2.2'     | '5%'    | '1/10W'  | 'DISCRETE' | 'RESISTER CHIP 2.2 1/10W+-5%(0603)'                | 'CHIP0603'     | ''          | ''            | '20101006'
 '2.2'        | '5%'      | '1/10W'  | '0603LF'  | 'EMPTY'  | 'CS-2203J913'(!)        = ''              | ''                 | 'CS-2203J913'           |'R0603'| '(SMR0603AW)'                  | '2.2'     | '5%'    | '1/10W'  | 'IO'       | 'RESISTER CHIP 2.2 1/10W+-5%(0603)'                | 'CHIP0603'     | ''          | ''            | '20101006'
 '150'        | '1%'      | '1/10W'  | '0603LF'  | 'CHIP'   | 'CS11503F943'(!)        = ''              | ''                 | 'CS11503F943'           |'R0603'| '(SMR0603AW)'                  | '150'     | '1%'    | '1/10W'  | 'DISCRETE' | 'RESISTOR CHIP 150,1/10W,+-1%(0603)'               | 'CHIP0603'     | ''          | ''            | '20101008'
 '150'        | '1%'      | '1/10W'  | '0603LF'  | 'EMPTY'  | 'CS11503F943'(!)        = ''              | ''                 | 'CS11503F943'           |'R0603'| '(SMR0603AW)'                  | '150'     | '1%'    | '1/10W'  | 'IO'       | 'RESISTOR CHIP 150,1/10W,+-1%(0603)'               | 'CHIP0603'     | ''          | ''            | '20101008'
 '75'         | '1%'      | '1/10W'  | '0603LF'  | 'CHIP'   | 'CS07503F930'(!)        = 'End of Design' | 'Comp-Approve'     | 'CS07503F930'           |'R0603'| '(SMR0603AW)'                  | '75'      | '1%'    | '1/10W'  | 'DISCRETE' | 'RESISTOR CHIP 75 1/10W +-1%(1608)'                | 'CHIP0603'     | ''          | ''            | '20101008'
 '75'         | '1%'      | '1/10W'  | '0603LF'  | 'EMPTY'  | 'CS07503F930'(!)        = 'End of Design' | 'Comp-Approve'     | 'CS07503F930'           |'R0603'| '(SMR0603AW)'                  | '75'      | '1%'    | '1/10W'  | 'IO'       | 'RESISTOR CHIP 75 1/10W +-1%(1608)'                | 'CHIP0603'     | ''          | ''            | '20101008'
 '22.6'       | '1%'      | '1/16W'  | '0402LF'  | 'CHIP'   | 'CS02262FB10'(!)        = 'End of Design' | 'Comp-Approve'     | 'CS02262FB10'           |'R0402'| '(R0402-0201)'                 | '22.6'    | '1%'    | '1/16W'  | 'DISCRETE' | 'RES CHIP 22.6 1/16W +-1%(0402)'                   | 'CHIP0402'     | ''          | ''            | '20101008'
 '22.6'       | '1%'      | '1/16W'  | '0402LF'  | 'EMPTY'  | 'CS02262FB10'(!)        = 'End of Design' | 'Comp-Approve'     | 'CS02262FB10'           |'R0402'| '(R0402-0201)'                 | '22.6'    | '1%'    | '1/16W'  | 'IO'       | 'RES CHIP 22.6 1/16W +-1%(0402)'                   | 'CHIP0402'     | ''          | ''            | '20101008'
 '2'          | '5%'      | '1/10W'  | '0603LF'  | 'CHIP'   | 'CS-2003J932'(!)        = 'End of Design' | 'Comp-Approve'     | 'CS-2003J932'           |'R0603'| '(SMR0603AW)'                  | '2'       | '5%'    | '1/10W'  | 'DISCRETE' | 'RESISTOR CHIP 2 1/10W+-5%(0603)EP'                | 'CHIP0603'     | ''          | ''            | '20101008'
 '2'          | '5%'      | '1/10W'  | '0603LF'  | 'EMPTY'  | 'CS-2003J932'(!)        = 'End of Design' | 'Comp-Approve'     | 'CS-2003J932'           |'R0603'| '(SMR0603AW)'                  | '2'       | '5%'    | '1/10W'  | 'IO'       | 'RESISTOR CHIP 2 1/10W+-5%(0603)EP'                | 'CHIP0603'     | ''          | ''            | '20101008'
 '1.24K'      | '1%'      | '1/16W'  | '0402LF'  | 'CHIP'   | 'CS21242FB20'(!)        = 'End of Design' | 'Comp-Approve'     | 'CS21242FB20'           |'R0402'| '(R0402-0201)'                 | '1.24K'   | '1%'    | '1/16W'  | 'DISCRETE' | 'RES CHIP 1.24K 1/16W +-1%(0402)'                  | 'CHIP0402'     | ''          | ''            | '20101008'
 '1.24K'      | '1%'      | '1/16W'  | '0402LF'  | 'EMPTY'  | 'CS21242FB20'(!)        = 'End of Design' | 'Comp-Approve'     | 'CS21242FB20'           |'R0402'| '(R0402-0201)'                 | '1.24K'   | '1%'    | '1/16W'  | 'IO'       | 'RES CHIP 1.24K 1/16W +-1%(0402)'                  | 'CHIP0402'     | ''          | ''            | '20101008'
 '10M'        | '5%'      | '1/16W'  | '0402LF'  | 'CHIP'   | 'CS61002JB23'(!)        = 'End of Design' | 'Comp-Approve'     | 'CS61002JB23'           |'R0402'| '(R0402-0201)'                 | '10M'     | '5%'    | '1/16W'  | 'DISCRETE' | 'RES CHIP 10M 1/16W +-5% (0402)'                   | 'CHIP0402'     | ''          | ''            | '20101013'
 '10M'        | '5%'      | '1/16W'  | '0402LF'  | 'EMPTY'  | 'CS61002JB23'(!)        = 'End of Design' | 'Comp-Approve'     | 'CS61002JB23'           |'R0402'| '(R0402-0201)'                 | '10M'     | '5%'    | '1/16W'  | 'IO'       | 'RES CHIP 10M 1/16W +-5% (0402)'                   | 'CHIP0402'     | ''          | ''            | '20101013'
 '806'        | '1%'      | '1/16W'  | '0402LF'  | 'CHIP'   | 'CS18062FB29'(!)        = 'End of Design' | 'Comp-Approve'     | 'CS18062FB29'           |'R0402'| '(R0402-0201)'                 | '806'     | '1%'    | '1/16W'  | 'DISCRETE' | 'RES CHIP 806 1/16W +-1%(0402)'                    | 'CHIP0402'     | ''          | ''            | '20101015'
 '806'        | '1%'      | '1/16W'  | '0402LF'  | 'EMPTY'  | 'CS18062FB29'(!)        = 'End of Design' | 'Comp-Approve'     | 'CS18062FB29'           |'R0402'| '(R0402-0201)'                 | '806'     | '1%'    | '1/16W'  | 'IO'       | 'RES CHIP 806 1/16W +-1%(0402)'                    | 'CHIP0402'     | ''          | ''            | '20101015'
 '43'         | '5%'      | '1/16W'  | '0402LF'  | 'CHIP'   | 'CS04302JB13'(!)        = 'End of Design' | 'Comp-Approve'     | 'CS04302JB13'           |'R0402'| '(R0402-0201)'                 | '43'      | '5%'    | '1/16W'  | 'DISCRETE' | 'RES CHIP 43 1/16W +-5%( 0402 )'                   | 'CHIP0402'     | ''          | ''            | '20101018'
 '43'         | '5%'      | '1/16W'  | '0402LF'  | 'EMPTY'  | 'CS04302JB13'(!)        = 'End of Design' | 'Comp-Approve'     | 'CS04302JB13'           |'R0402'| '(R0402-0201)'                 | '43'      | '5%'    | '1/16W'  | 'IO'       | 'RES CHIP 43 1/16W +-5%( 0402 )'                   | 'CHIP0402'     | ''          | ''            | '20101018'
 '0.4'        | '1%'      | '1/10W'  | '0603LF'  | 'CHIP'   | 'CS+4003F900'(!)        = ''              | ''                 | 'CS+4003F900'           |'R0603'| '(SMR0603AW)'                  | '0.4'     | '1%'    | '1/10W'  | 'DISCRETE' | 'RESISTOR CHIP 0.4 1/10W +-1%(0603)'               | 'CHIP0603'     | ''          | ''            | '20101018'
 '0.4'        | '1%'      | '1/10W'  | '0603LF'  | 'EMPTY'  | 'CS+4003F900'(!)        = ''              | ''                 | 'CS+4003F900'           |'R0603'| '(SMR0603AW)'                  | '0.4'     | '1%'    | '1/10W'  | 'IO'       | 'RESISTOR CHIP 0.4 1/10W +-1%(0603)'               | 'CHIP0603'     | ''          | ''            | '20101018'
 '2.32K'      | '1%'      | '1/16W'  | '0402LF'  | 'CHIP'   | 'CS22322FB01'(!)        = 'End of Design' | 'Comp-Approve'     | 'CS22322FB01'           |'R0402'| '(R0402-0201)'                 | '2.32K'   | '1%'    | '1/16W'  | 'DISCRETE' | 'RESISTOR CHIP 2.32K 1/16W +-1%(0402)'             | 'CHIP0402'     | ''          | ''            | '20101028'
 '2.32K'      | '1%'      | '1/16W'  | '0402LF'  | 'EMPTY'  | 'CS22322FB01'(!)        = 'End of Design' | 'Comp-Approve'     | 'CS22322FB01'           |'R0402'| '(R0402-0201)'                 | '2.32K'   | '1%'    | '1/16W'  | 'IO'       | 'RESISTOR CHIP 2.32K 1/16W +-1%(0402)'             | 'CHIP0402'     | ''          | ''            | '20101028'
 '36.5K'      | '1%'      | '1/16W'  | '0402LF'  | 'CHIP'   | 'CS33652FB18'(!)        = 'End of Design' | 'Comp-Approve'     | 'CS33652FB18'           |'R0402'| '(R0402-0201)'                 | '36.5K'   | '1%'    | '1/16W'  | 'DISCRETE' | 'RES CHIP 36.5K 1/16W +-1%(0402)'                  | 'CHIP0402'     | ''          | ''            | '20101028'
 '36.5K'      | '1%'      | '1/16W'  | '0402LF'  | 'EMPTY'  | 'CS33652FB18'(!)        = 'End of Design' | 'Comp-Approve'     | 'CS33652FB18'           |'R0402'| '(R0402-0201)'                 | '36.5K'   | '1%'    | '1/16W'  | 'IO'       | 'RES CHIP 36.5K 1/16W +-1%(0402)'                  | 'CHIP0402'     | ''          | ''            | '20101028'
 '1.8'        | '1%'      | '1/10W'  | '0603LF'  | 'CHIP'   | 'CS-1803F900'(!)        = 'End of Design' | 'P/N Release'      | 'CS-1803F900'           |'R0603'| '(SMR0603AW)'                  | '1.8'     | '1%'    | '1/10W'  | 'DISCRETE' | 'RES CHIP 1.8 1/10W +-1%(0603)'                    | 'CHIP0603'     | ''          | ''            | '20101101'
 '1.8'        | '1%'      | '1/10W'  | '0603LF'  | 'EMPTY'  | 'CS-1803F900'(!)        = 'End of Design' | 'P/N Release'      | 'CS-1803F900'           |'R0603'| '(SMR0603AW)'                  | '1.8'     | '1%'    | '1/10W'  | 'IO'       | 'RES CHIP 1.8 1/10W +-1%(0603)'                    | 'CHIP0603'     | ''          | ''            | '20101101'
 '1.8'        | '5%'      | '1/10W'  | '0603LF'  | 'CHIP'   | 'CS-1803J900'(!)        = 'End of Design' | 'Comp-Approve'     | 'CS-1803J900'           |'R0603'| '(SMR0603AW)'                  | '1.8'     | '5%'    | '1/10W'  | 'DISCRETE' | 'RES CHIP 1.8 1/10W +-5%(0603)'                    | 'CHIP0603'     | ''          | ''            | '20101101'
 '1.8'        | '5%'      | '1/10W'  | '0603LF'  | 'EMPTY'  | 'CS-1803J900'(!)        = 'End of Design' | 'Comp-Approve'     | 'CS-1803J900'           |'R0603'| '(SMR0603AW)'                  | '1.8'     | '5%'    | '1/10W'  | 'IO'       | 'RES CHIP 1.8 1/10W +-5%(0603)'                    | 'CHIP0603'     | ''          | ''            | '20101101'
 '0.0005'     | '1%'      | '3W'     | '2512LF'  | 'CHIP'   | 'CS0000DFR00'(!)        = ''              | ''                 | 'CS0000DFR00'           |'R2512A'| '(SMR2512AW)'                  | '0.0005'  | '1%'    | '3W'     | 'DISCRETE' | 'RES CHIP 0.0005 3W +-1%(2512)'                    | 'CHIP2512'     | ''          | ''            | '20101105'
 '0.0005'     | '1%'      | '3W'     | '2512LF'  | 'EMPTY'  | 'CS0000DFR00'(!)        = ''              | ''                 | 'CS0000DFR00'           |'R2512A'| '(SMR2512AW)'                  | '0.0005'  | '1%'    | '3W'     | 'IO'       | 'RES CHIP 0.0005 3W +-1%(2512)'                    | 'CHIP2512'     | ''          | ''            | '20101105'
 '14.7K'      | '1%'      | '1/16W'  | '0402LF'  | 'CHIP'   | 'CS31472FB14'(!)        = 'End of Design' | 'Comp-Approve'     | 'CS31472FB14'           |'R0402'| '(R0402-0201)'                 | '14.7K'   | '1%'    | '1/16W'  | 'DISCRETE' | 'RES CHIP 14.7K 1/16W +-1% (0402)'                 | 'CHIP0402'     | ''          | ''            | '20101213'
 '14.7K'      | '1%'      | '1/16W'  | '0402LF'  | 'EMPTY'  | 'CS31472FB14'(!)        = 'End of Design' | 'Comp-Approve'     | 'CS31472FB14'           |'R0402'| '(R0402-0201)'                 | '14.7K'   | '1%'    | '1/16W'  | 'IO'       | 'RES CHIP 14.7K 1/16W +-1% (0402)'                 | 'CHIP0402'     | ''          | ''            | '20101213'
 '64.9K'      | '1%'      | '1/16W'  | '0402LF'  | 'CHIP'   | 'CS36492FB17'(!)        = 'End of Design' | 'Comp-Approve'     | 'CS36492FB17'           |'R0402'| '(R0402-0201)'                 | '64.9K'   | '1%'    | '1/16W'  | 'DISCRETE' | 'RES CHIP 64.9K 1/16W +-1%(0402)'                  | 'CHIP0402'     | ''          | ''            | '20101221'
 '64.9K'      | '1%'      | '1/16W'  | '0402LF'  | 'EMPTY'  | 'CS36492FB17'(!)        = 'End of Design' | 'Comp-Approve'     | 'CS36492FB17'           |'R0402'| '(R0402-0201)'                 | '64.9K'   | '1%'    | '1/16W'  | 'IO'       | 'RES CHIP 64.9K 1/16W +-1%(0402)'                  | 'CHIP0402'     | ''          | ''            | '20101221'
 '7.5K'       | '1%'      | '1/10W'  | '0603LF'  | 'CHIP'   | 'CS27503F917'(!)        = 'End of Design' | 'Comp-Approve'     | 'CS27503F917'           |'R0603'| '(SMR0603AW)'                  | '7.5K'    | '1%'    | '1/10W'  | 'DISCRETE' | 'RES CHIP 7.5K 1/10W +-1%(0603)'                   | 'CHIP0603'     | ''          | ''            | '20101221'
 '7.5K'       | '1%'      | '1/10W'  | '0603LF'  | 'EMPTY'  | 'CS27503F917'(!)        = 'End of Design' | 'Comp-Approve'     | 'CS27503F917'           |'R0603'| '(SMR0603AW)'                  | '7.5K'    | '1%'    | '1/10W'  | 'IO'       | 'RES CHIP 7.5K 1/10W +-1%(0603)'                   | 'CHIP0603'     | ''          | ''            | '20101221'
 '499'        | '1%'      | '1/10W'  | '0603LF'  | 'CHIP'   | 'CS14993F939'(!)        = ''              | ''                 | 'CS14993F939'           |'R0603'| '(SMR0603AW)'                  | '499'     | '1%'    | '1/10W'  | 'DISCRETE' | 'RESISTOR CHIP 499 1/10W +-1%(0603)'               | 'CHIP0603'     | ''          | ''            | '20101221'
 '499'        | '1%'      | '1/10W'  | '0603LF'  | 'EMPTY'  | 'CS14993F939'(!)        = ''              | ''                 | 'CS14993F939'           |'R0603'| '(SMR0603AW)'                  | '499'     | '1%'    | '1/10W'  | 'IO'       | 'RESISTOR CHIP 499 1/10W +-1%(0603)'               | 'CHIP0603'     | ''          | ''            | '20101221'
 '150K'       | '1%'      | '1/10W'  | '0603LF'  | 'CHIP'   | 'CS41503F906'(!)        = ''              | ''                 | 'CS41503F906'           |'R0603'| '(SMR0603AW)'                  | '150K'    | '1%'    | '1/10W'  | 'DISCRETE' | 'RES CHIP 150K 1/10W +-1%(0603)'                   | 'CHIP0603'     | ''          | ''            | '20110106'
 '150K'       | '1%'      | '1/10W'  | '0603LF'  | 'EMPTY'  | 'CS41503F906'(!)        = ''              | ''                 | 'CS41503F906'           |'R0603'| '(SMR0603AW)'                  | '150K'    | '1%'    | '1/10W'  | 'IO'       | 'RES CHIP 150K 1/10W +-1%(0603)'                   | 'CHIP0603'     | ''          | ''            | '20110106'
 '499'        | '1%'      | '1/10W'  | '0603LF'  | 'CHIP'   | 'CS41503F914'(!)        = 'End of Design' | 'Comp-Approve'     | 'CS41503F914'           |'R0603'| '(SMR0603AW)'                  | '499'     | '1%'    | '1/10W'  | 'DISCRETE' | 'RES CHIP 150K 1/10W +-1%(0603)'                   | 'CHIP0603'     | ''          | ''            | '20110106'
 '499'        | '1%'      | '1/10W'  | '0603LF'  | 'EMPTY'  | 'CS41503F914'(!)        = 'End of Design' | 'Comp-Approve'     | 'CS41503F914'           |'R0603'| '(SMR0603AW)'                  | '499'     | '1%'    | '1/10W'  | 'IO'       | 'RES CHIP 150K 1/10W +-1%(0603)'                   | 'CHIP0603'     | ''          | ''            | '20110106'
 '0.004'      | '1%'      | '1W'     | '2512LF'  | 'CHIP'   | 'CS+0048FR00'(!)        = ''              | ''                 | 'CS+0048FR00'           |'R2512A'| '(SMR2512AW)'                  | '0.004'   | '1%'    | '1W'     | 'DISCRETE' | 'RES CHIP 0.004 1W +-1%(2512)'                     | 'CHIP2512'     | ''          | ''            | '20110106'
 '0.004'      | '1%'      | '1W'     | '2512LF'  | 'EMPTY'  | 'CS+0048FR00'(!)        = ''              | ''                 | 'CS+0048FR00'           |'R2512A'| '(SMR2512AW)'                  | '0.004'   | '1%'    | '1W'     | 'IO'       | 'RES CHIP 0.004 1W +-1%(2512)'                     | 'CHIP2512'     | ''          | ''            | '20110106'
 '0'          | '1%'      | '1/2W'   | '1206LF'  | 'CHIP'   | 'CS00007F209'(!)        = 'End of Design' | 'Comp-Approve'     | 'CS00007F209'           |'R1206'| '(SMR1206AW)'                  | '0'       | '1%'    | '1/2W'   | 'DISCRETE' | 'RESISTOR CHIP 0 1/2W 1%(1206)'                    | 'CHIP1206'     | ''          | ''            | '20110113'
 '0'          | '1%'      | '1/2W'   | '1206LF'  | 'EMPTY'  | 'CS00007F209'(!)        = 'End of Design' | 'Comp-Approve'     | 'CS00007F209'           |'R1206'| '(SMR1206AW)'                  | '0'       | '1%'    | '1/2W'   | 'IO'       | 'RESISTOR CHIP 0 1/2W 1%(1206)'                    | 'CHIP1206'     | ''          | ''            | '20110113'
 '75'         | '1%'      | '1/8W'   | '0805LF'  | 'CHIP'   | 'CS07504FA11'(!)        = ''              | ''                 | 'CS07504FA11'           |'R0805'| '(SMR0805AW)'                  | '75'      | '1%'    | '1/8W'   | 'DISCRETE' | 'RES CHIP 75 1/8W +-1%(0805)'                      | 'CHIP0805'     | ''          | ''            | '20110113'
 '75'         | '1%'      | '1/8W'   | '0805LF'  | 'EMPTY'  | 'CS07504FA11'(!)        = ''              | ''                 | 'CS07504FA11'           |'R0805'| '(SMR0805AW)'                  | '75'      | '1%'    | '1/8W'   | 'IO'       | 'RES CHIP 75 1/8W +-1%(0805)'                      | 'CHIP0805'     | ''          | ''            | '20110113'
 '118'        | '1%'      | '1/16W'  | '0402LF'  | 'CHIP'   | 'CS11182FB00'(!)        = 'End of Design' | 'Comp-Approve'     | 'CS11182FB00'           |'R0402'| '(R0402-0201)'                 | '118'     | '1%'    | '1/16W'  | 'DISCRETE' | 'RES CHIP 118 1/16W +-1%(0402)'                    | 'CHIP0402'     | ''          | ''            | '20110113'
 '118'        | '1%'      | '1/16W'  | '0402LF'  | 'EMPTY'  | 'CS11182FB00'(!)        = 'End of Design' | 'Comp-Approve'     | 'CS11182FB00'           |'R0402'| '(R0402-0201)'                 | '118'     | '1%'    | '1/16W'  | 'IO'       | 'RES CHIP 118 1/16W +-1%(0402)'                    | 'CHIP0402'     | ''          | ''            | '20110113'
 '140'        | '1%'      | '1/16W'  | '0402LF'  | 'CHIP'   | 'CS11402FB19'(!)        = 'End of Design' | 'Comp-Approve'     | 'CS11402FB19'           |'R0402'| '(R0402-0201)'                 | '140'     | '1%'    | '1/16W'  | 'DISCRETE' | 'RES CHIP 140 1/16W +-1%(0402)'                    | 'CHIP0402'     | ''          | ''            | '20110113'
 '140'        | '1%'      | '1/16W'  | '0402LF'  | 'EMPTY'  | 'CS11402FB19'(!)        = 'End of Design' | 'Comp-Approve'     | 'CS11402FB19'           |'R0402'| '(R0402-0201)'                 | '140'     | '1%'    | '1/16W'  | 'IO'       | 'RES CHIP 140 1/16W +-1%(0402)'                    | 'CHIP0402'     | ''          | ''            | '20110113'
 '4.99M'      | '1%'      | '1/16W'  | '0402LF'  | 'CHIP'   | 'CS54992FB00'(!)        = 'End of Design' | 'Comp-Release Qty' | 'CS54992FB00'           |'R0402'| '(R0402-0201)'                 | '4.99M'   | '1%'    | '1/16W'  | 'DISCRETE' | 'RES CHIP 4.99M 1/16W +-1%(0402)'                  | 'CHIP0402'     | ''          | ''            | '20110113'
 '4.99M'      | '1%'      | '1/16W'  | '0402LF'  | 'EMPTY'  | 'CS54992FB00'(!)        = 'End of Design' | 'Comp-Release Qty' | 'CS54992FB00'           |'R0402'| '(R0402-0201)'                 | '4.99M'   | '1%'    | '1/16W'  | 'IO'       | 'RES CHIP 4.99M 1/16W +-1%(0402)'                  | 'CHIP0402'     | ''          | ''            | '20110113'
 '10M'        | '1%'      | '1/16W'  | '0402LF'  | 'CHIP'   | 'CS61002FB00'(!)        = 'End of Design' | 'Comp-Approve'     | 'CS61002FB00'           |'R0402'| '(R0402-0201)'                 | '10M'     | '1%'    | '1/16W'  | 'DISCRETE' | 'RES CHIP 10M 1/16W +-1%(0402)'                    | 'CHIP0402'     | ''          | ''            | '20110113'
 '10M'        | '1%'      | '1/16W'  | '0402LF'  | 'EMPTY'  | 'CS61002FB00'(!)        = 'End of Design' | 'Comp-Approve'     | 'CS61002FB00'           |'R0402'| '(R0402-0201)'                 | '10M'     | '1%'    | '1/16W'  | 'IO'       | 'RES CHIP 10M 1/16W +-1%(0402)'                    | 'CHIP0402'     | ''          | ''            | '20110113'
 '31.6'       | '1%'      | '1/16W'  | '0402LF'  | 'CHIP'   | 'CS03162FB01'(!)        = ''              | ''                 | 'CS03162FB01'           |'R0402'| '(R0402-0201)'                 | '31.6'    | '1%'    | '1/16W'  | 'DISCRETE' | 'RES CHIP 31.6 1/16W +-1%(0402)'                   | 'CHIP0402'     | ''          | ''            | '20110124'
 '31.6'       | '1%'      | '1/16W'  | '0402LF'  | 'EMPTY'  | 'CS03162FB01'(!)        = ''              | ''                 | 'CS03162FB01'           |'R0402'| '(R0402-0201)'                 | '31.6'    | '1%'    | '1/16W'  | 'IO'       | 'RES CHIP 31.6 1/16W +-1%(0402)'                   | 'CHIP0402'     | ''          | ''            | '20110124'
 '931'        | '1%'      | '1/16W'  | '0402LF'  | 'CHIP'   | 'CS19312FB00'(!)        = 'End of Design' | 'Comp-Approve'     | 'CS19312FB00'           |'R0402'| '(R0402-0201)'                 | '931'     | '1%'    | '1/16W'  | 'DISCRETE' | 'RES CHIP 931 1/16W +-1%(0402)HF'                  | 'CHIP0402'     | ''          | ''            | '20110128'
 '931'        | '1%'      | '1/16W'  | '0402LF'  | 'EMPTY'  | 'CS19312FB00'(!)        = 'End of Design' | 'Comp-Approve'     | 'CS19312FB00'           |'R0402'| '(R0402-0201)'                 | '931'     | '1%'    | '1/16W'  | 'IO'       | 'RES CHIP 931 1/16W +-1%(0402)HF'                  | 'CHIP0402'     | ''          | ''            | '20110128'
 '576'        | '1%'      | '1/16W'  | '0402LF'  | 'CHIP'   | 'CS15762FB26'(!)        = 'End of Design' | 'Comp-Release Qty' | 'CS15762FB26'           |'R0402'| '(R0402-0201)'                 | '576'     | '1%'    | '1/16W'  | 'DISCRETE' | 'RES CHIP 576 1/16W +-1%(0402)'                    | 'CHIP0402'     | ''          | ''            | '20110128'
 '576'        | '1%'      | '1/16W'  | '0402LF'  | 'EMPTY'  | 'CS15762FB26'(!)        = 'End of Design' | 'Comp-Release Qty' | 'CS15762FB26'           |'R0402'| '(R0402-0201)'                 | '576'     | '1%'    | '1/16W'  | 'IO'       | 'RES CHIP 576 1/16W +-1%(0402)'                    | 'CHIP0402'     | ''          | ''            | '20110128'
 '365'        | '1%'      | '1/16W'  | '0402LF'  | 'CHIP'   | 'CS13652FB14'(!)        = 'End of Design' | 'Comp-Approve'     | 'CS13652FB14'           |'R0402'| '(R0402-0201)'                 | '365'     | '1%'    | '1/16W'  | 'DISCRETE' | 'RES CHIP 365 1/16W +-1% (0402)'                   | 'CHIP0402'     | ''          | ''            | '20110128'
 '365'        | '1%'      | '1/16W'  | '0402LF'  | 'EMPTY'  | 'CS13652FB14'(!)        = 'End of Design' | 'Comp-Approve'     | 'CS13652FB14'           |'R0402'| '(R0402-0201)'                 | '365'     | '1%'    | '1/16W'  | 'IO'       | 'RES CHIP 365 1/16W +-1% (0402)'                   | 'CHIP0402'     | ''          | ''            | '20110128'
 '12.4K'      | '1%'      | '1/16W'  | '0402LF'  | 'CHIP'   | 'CS31242FB13'(!)        = 'End of Design' | 'Comp-Approve'     | 'CS31242FB13'           |'R0402'| '(R0402-0201)'                 | '12.4K'   | '1%'    | '1/16W'  | 'DISCRETE' | 'RES CHIP 12.4k 1/16W +-1% (0402)'                 | 'CHIP0402'     | ''          | ''            | '20110215'
 '12.4K'      | '1%'      | '1/16W'  | '0402LF'  | 'EMPTY'  | 'CS31242FB13'(!)        = 'End of Design' | 'Comp-Approve'     | 'CS31242FB13'           |'R0402'| '(R0402-0201)'                 | '12.4K'   | '1%'    | '1/16W'  | 'IO'       | 'RES CHIP 12.4k 1/16W +-1% (0402)'                 | 'CHIP0402'     | ''          | ''            | '20110215'
 '0.001'      | '1%'      | '1W'     | '2512LF'  | 'CHIP'   | 'CS+0018F111'(!)        = 'End of Design' | 'Comp-Approve'     | 'CS+0018F111'           |'R2512XE'| '(SMR2512AW)'                  | '0.001'   | '1%'    | '1W'     | 'DISCRETE' | 'RES CHIP 0.001 1W +-1% (2512)'                    | 'CHIP2512'     | ''          | ''            | '20110405'
 '0.001'      | '1%'      | '1W'     | '2512LF'  | 'EMPTY'  | 'CS+0018F111'(!)        = 'End of Design' | 'Comp-Approve'     | 'CS+0018F111'           |'R2512XE'| '(SMR2512AW)'                  | '0.001'   | '1%'    | '1W'     | 'IO'       | 'RES CHIP 0.001 1W +-1% (2512)'                    | 'CHIP2512'     | ''          | ''            | '20110405'
 '49.9'       | '1%'      | '1/8W'   | '0805LF'  | 'CHIP'   | 'CS04994FA00'(!)        = ''              | ''                 | 'CS04994FA00'           |'R0805'| '(SMR0805AW)'                  | '49.9'    | '1%'    | '1/8W'   | 'DISCRETE' | 'RES CHIP 49.9 1/8W +-1% (0805)'                   | 'CHIP0805'     | ''          | ''            | '20110221'
 '49.9'       | '1%'      | '1/8W'   | '0805LF'  | 'EMPTY'  | 'CS04994FA00'(!)        = ''              | ''                 | 'CS04994FA00'           |'R0805'| '(SMR0805AW)'                  | '49.9'    | '1%'    | '1/8W'   | 'IO'       | 'RES CHIP 49.9 1/8W +-1% (0805)'                   | 'CHIP0805'     | ''          | ''            | '20110221'
 '10'         | '1%'      | '1/10W'  | '0603LF'  | 'CHIP'   | 'CS01003F935'(!)        = ''              | ''                 | 'CS01003F935'           |'R0603'| '(SMR0603AW)'                  | '10'      | '1%'    | '1/10W'  | 'DISCRETE' | 'RES CHIP 10 1/10W +-1% (0603)'                    | 'CHIP0603'     | ''          | ''            | '20110221'
 '10'         | '1%'      | '1/10W'  | '0603LF'  | 'EMPTY'  | 'CS01003F935'(!)        = ''              | ''                 | 'CS01003F935'           |'R0603'| '(SMR0603AW)'                  | '10'      | '1%'    | '1/10W'  | 'IO'       | 'RES CHIP 10 1/10W +-1% (0603)'                    | 'CHIP0603'     | ''          | ''            | '20110221'
 '0.402'      | '1%'      | '1/10W'  | '0603LF'  | 'CHIP'   | 'CS+4023F900'(!)        = ''              | ''                 | 'CS+4023F900'           |'R0603'| '(SMR0603AW)'                  | '0.402'   | '1%'    | '1/10W'  | 'DISCRETE' | 'RES CHIP 0.402 1/10W +-1%(0603)'                  | 'CHIP0603'     | ''          | ''            | '20110302'
 '0.402'      | '1%'      | '1/10W'  | '0603LF'  | 'EMPTY'  | 'CS+4023F900'(!)        = ''              | ''                 | 'CS+4023F900'           |'R0603'| '(SMR0603AW)'                  | '0.402'   | '1%'    | '1/10W'  | 'IO'       | 'RES CHIP 0.402 1/10W +-1%(0603)'                  | 'CHIP0603'     | ''          | ''            | '20110302'
 '0.1'        | '1%'      | '1/10W'  | '0603LF'  | 'CHIP'   | 'CS+1003F900'(!)        = ''              | ''                 | 'CS+1003F900'           |'R0603'| '(SMR0603AW)'                  | '0.1'     | '1%'    | '1/10W'  | 'DISCRETE' | 'RES CHIP 0.1 1/10W +-1%(0603)'                    | 'CHIP0603'     | ''          | ''            | '20110302'
 '0.1'        | '1%'      | '1/10W'  | '0603LF'  | 'EMPTY'  | 'CS+1003F900'(!)        = ''              | ''                 | 'CS+1003F900'           |'R0603'| '(SMR0603AW)'                  | '0.1'     | '1%'    | '1/10W'  | 'IO'       | 'RES CHIP 0.1 1/10W +-1%(0603)'                    | 'CHIP0603'     | ''          | ''            | '20110302'
 '270'        | '1%'      | '1/16W'  | '0402LF'  | 'CHIP'   | 'CS12702FB12'(!)        = 'End of Design' | 'Comp-Approve'     | 'CS12702FB12'           |'R0402'| '(R0402-0201)'                 | '270'     | '1%'    | '1/16W'  | 'DISCRETE' | 'RES CHIP 270 1/16W +-1%(0402)'                    | 'CHIP0402'     | ''          | ''            | '20110303'
 '270'        | '1%'      | '1/16W'  | '0402LF'  | 'EMPTY'  | 'CS12702FB12'(!)        = 'End of Design' | 'Comp-Approve'     | 'CS12702FB12'           |'R0402'| '(R0402-0201)'                 | '270'     | '1%'    | '1/16W'  | 'IO'       | 'RES CHIP 270 1/16W +-1%(0402)'                    | 'CHIP0402'     | ''          | ''            | '20110303'
 '0.05'       | '1%'      | '1W'     | '2512LF'  | 'CHIP'   | 'CS+0508FR00'(!)        = ''              | ''                 | 'CS+0508FR00'           |'R2512XB'| '(SMR2512AW)'                  | '0.05'    | '1%'    | '1W'     | 'DISCRETE' | 'RES CHIP 0.05 1W +-1% (2512)'                     | 'CHIP2512'     | ''          | ''            | '20110304'
 '0.05'       | '1%'      | '1W'     | '2512LF'  | 'EMPTY'  | 'CS+0508FR00'(!)        = ''              | ''                 | 'CS+0508FR00'           |'R2512XB'| '(SMR2512AW)'                  | '0.05'    | '1%'    | '1W'     | 'IO'       | 'RES CHIP 0.05 1W +-1% (2512)'                     | 'CHIP2512'     | ''          | ''            | '20110304'
 '0.05'       | '1%'      | '1W'     | '3720LF'  | 'CHIP'   | 'CS+0508FL11'(!)        = ''              | ''                 | 'CS+0508FL11'           |'R3720'| '(SMR3720AW)'                  | '0.05'    | '1%'    | '1W'     | 'DISCRETE' | 'RES CHIP 0.05 1W +-1%(3720)'                      | 'CHIP3720'     | ''          | ''            | '20110304'
 '0.05'       | '1%'      | '1W'     | '3720LF'  | 'EMPTY'  | 'CS+0508FL11'(!)        = ''              | ''                 | 'CS+0508FL11'           |'R3720'| '(SMR3720AW)'                  | '0.05'    | '1%'    | '1W'     | 'IO'       | 'RES CHIP 0.05 1W +-1%(3720)'                      | 'CHIP3720'     | ''          | ''            | '20110304'
 '523'        | '1%'      | '1/16W'  | '0402LF'  | 'CHIP'   | 'CS15232FB00'(!)        = 'End of Design' | 'Comp-Approve'     | 'CS15232FB00'           |'R0402'| '(R0402-0201)'                 | '523'     | '1%'    | '1/16W'  | 'DISCRETE' | 'RES CHIP 523 1/16W +-1%(0402)'                    | 'CHIP0402'     | ''          | ''            | '20110308'
 '523'        | '1%'      | '1/16W'  | '0402LF'  | 'EMPTY'  | 'CS15232FB00'(!)        = 'End of Design' | 'Comp-Approve'     | 'CS15232FB00'           |'R0402'| '(R0402-0201)'                 | '523'     | '1%'    | '1/16W'  | 'IO'       | 'RES CHIP 523 1/16W +-1%(0402)'                    | 'CHIP0402'     | ''          | ''            | '20110308'
 '19.6K'      | '1%'      | '1/16W'  | '0402LF'  | 'CHIP'   | 'CS31962FB18'(!)        = 'End of Design' | 'Comp-Approve'     | 'CS31962FB18'           |'R0402'| '(R0402-0201)'                 | '19.6K'   | '1%'    | '1/16W'  | 'DISCRETE' | 'RES CHIP 19.6K 1/16W +-1% (0402)'                 | 'CHIP0402'     | ''          | ''            | '20110308'
 '19.6K'      | '1%'      | '1/16W'  | '0402LF'  | 'EMPTY'  | 'CS31962FB18'(!)        = 'End of Design' | 'Comp-Approve'     | 'CS31962FB18'           |'R0402'| '(R0402-0201)'                 | '19.6K'   | '1%'    | '1/16W'  | 'IO'       | 'RES CHIP 19.6K 1/16W +-1% (0402)'                 | 'CHIP0402'     | ''          | ''            | '20110308'
 '46.4K'      | '1%'      | '1/16W'  | '0402LF'  | 'CHIP'   | 'CS34642FB16'(!)        = 'End of Design' | 'Comp-Approve'     | 'CS34642FB16'           |'R0402'| '(R0402-0201)'                 | '46.4K'   | '1%'    | '1/16W'  | 'DISCRETE' | 'RES CHIP 46.4K 1/16W +-1%(0402)'                  | 'CHIP0402'     | ''          | ''            | '20110314'
 '46.4K'      | '1%'      | '1/16W'  | '0402LF'  | 'EMPTY'  | 'CS34642FB16'(!)        = 'End of Design' | 'Comp-Approve'     | 'CS34642FB16'           |'R0402'| '(R0402-0201)'                 | '46.4K'   | '1%'    | '1/16W'  | 'IO'       | 'RES CHIP 46.4K 1/16W +-1%(0402)'                  | 'CHIP0402'     | ''          | ''            | '20110314'
 '43K'        | '1%'      | '1/16W'  | '0402LF'  | 'CHIP'   | 'CS34302FB17'(!)        = 'End of Design' | 'Comp-Approve'     | 'CS34302FB17'           |'R0402'| '(R0402-0201)'                 | '43K'     | '1%'    | '1/16W'  | 'DISCRETE' | 'RES CHIP 43K 1/16W +-1% (0402)'                   | 'CHIP0402'     | ''          | ''            | '20110316'
 '43K'        | '1%'      | '1/16W'  | '0402LF'  | 'EMPTY'  | 'CS34302FB17'(!)        = 'End of Design' | 'Comp-Approve'     | 'CS34302FB17'           |'R0402'| '(R0402-0201)'                 | '43K'     | '1%'    | '1/16W'  | 'IO'       | 'RES CHIP 43K 1/16W +-1% (0402)'                   | 'CHIP0402'     | ''          | ''            | '20110316'
 '1.2K'       | '1%'      | '1/10W'  | '0603LF'  | 'CHIP'   | 'CS21203F910'(!)        = 'End of Design' | 'Comp-Approve'     | 'CS21203F910'           |'R0603'| '(SMR0603AW)'                  | '1.2K'    | '1%'    | '1/10W'  | 'DISCRETE' | 'RES CHIP 1.2K 1/10W +-1%(0603)'                   | 'CHIP0603'     | ''          | ''            | '20110316'
 '1.2K'       | '1%'      | '1/10W'  | '0603LF'  | 'EMPTY'  | 'CS21203F910'(!)        = 'End of Design' | 'Comp-Approve'     | 'CS21203F910'           |'R0603'| '(SMR0603AW)'                  | '1.2K'    | '1%'    | '1/10W'  | 'IO'       | 'RES CHIP 1.2K 1/10W +-1%(0603)'                   | 'CHIP0603'     | ''          | ''            | '20110316'
 '680'        | '1%'      | '1/10W'  | '0603LF'  | 'CHIP'   | 'CS16803F913'(!)        = 'End of Design' | 'Comp-Approve'     | 'CS16803F913'           |'R0603'| '(SMR0603AW)'                  | '680'     | '1%'    | '1/10W'  | 'DISCRETE' | 'RES CHIP 680 1/10W +-1%(0603)'                    | 'CHIP0603'     | ''          | ''            | '20110317'
 '680'        | '1%'      | '1/10W'  | '0603LF'  | 'EMPTY'  | 'CS16803F913'(!)        = 'End of Design' | 'Comp-Approve'     | 'CS16803F913'           |'R0603'| '(SMR0603AW)'                  | '680'     | '1%'    | '1/10W'  | 'IO'       | 'RES CHIP 680 1/10W +-1%(0603)'                    | 'CHIP0603'     | ''          | ''            | '20110317'
 '150K'       | '5%'      | '1/16W'  | '0402LF'  | 'CHIP'   | 'CS41502JB10'(!)        = 'End of Design' | 'Comp-Approve'     | 'CS41502JB10'           |'R0402'| '(R0402-0201)'                 | '150K'    | '5%'    | '1/16W'  | 'DISCRETE' | 'RES CHIP 150K 1/16W+-5%(0402)'                    | 'CHIP0402'     | ''          | ''            | '20110321'
 '150K'       | '5%'      | '1/16W'  | '0402LF'  | 'EMPTY'  | 'CS41502JB10'(!)        = 'End of Design' | 'Comp-Approve'     | 'CS41502JB10'           |'R0402'| '(R0402-0201)'                 | '150K'    | '5%'    | '1/16W'  | 'IO'       | 'RES CHIP 150K 1/16W+-5%(0402)'                    | 'CHIP0402'     | ''          | ''            | '20110321'
 '124K'       | '1%'      | '1/16W'  | '0402LF'  | 'CHIP'   | 'CS41242FB15'(!)        = 'End of Design' | 'Comp-Approve'     | 'CS41242FB15'           |'R0402'| '(R0402-0201)'                 | '124K'    | '1%'    | '1/16W'  | 'DISCRETE' | 'RES CHIP 124K 1/16W +-1%( 0402)'                  | 'CHIP0402'     | ''          | ''            | '20110328'
 '124K'       | '1%'      | '1/16W'  | '0402LF'  | 'EMPTY'  | 'CS41242FB15'(!)        = 'End of Design' | 'Comp-Approve'     | 'CS41242FB15'           |'R0402'| '(R0402-0201)'                 | '124K'    | '1%'    | '1/16W'  | 'IO'       | 'RES CHIP 124K 1/16W +-1%( 0402)'                  | 'CHIP0402'     | ''          | ''            | '20110328'
 '180'        | '1%'      | '1/16W'  | '0402LF'  | 'CHIP'   | 'CS11802FB13'(!)        = 'End of Design' | 'Comp-Approve'     | 'CS11802FB13'           |'R0402'| '(R0402-0201)'                 | '180'     | '1%'    | '1/16W'  | 'DISCRETE' | 'RES CHIP 180 1/16W +-1% (0402)'                   | 'CHIP0402'     | ''          | ''            | '20110331'
 '180'        | '1%'      | '1/16W'  | '0402LF'  | 'EMPTY'  | 'CS11802FB13'(!)        = 'End of Design' | 'Comp-Approve'     | 'CS11802FB13'           |'R0402'| '(R0402-0201)'                 | '180'     | '1%'    | '1/16W'  | 'IO'       | 'RES CHIP 180 1/16W +-1% (0402)'                   | 'CHIP0402'     | ''          | ''            | '20110331'
 '8.25K'      | '1%'      | '1/16W'  | '0402LF'  | 'CHIP'   | 'CS28252FB15'(!)        = 'End of Design' | 'Comp-Approve'     | 'CS28252FB15'           |'R0402'| '(R0402-0201)'                 | '8.25K'   | '1%'    | '1/16W'  | 'DISCRETE' | 'RESISTOR CHIP 8.25K 1/16W+-1%(0402)'              | 'CHIP0402'     | ''          | ''            | '20110331'
 '8.25K'      | '1%'      | '1/16W'  | '0402LF'  | 'EMPTY'  | 'CS28252FB15'(!)        = 'End of Design' | 'Comp-Approve'     | 'CS28252FB15'           |'R0402'| '(R0402-0201)'                 | '8.25K'   | '1%'    | '1/16W'  | 'IO'       | 'RESISTOR CHIP 8.25K 1/16W+-1%(0402)'              | 'CHIP0402'     | ''          | ''            | '20110331'
 '3.9K'       | '1%'      | '1/16W'  | '0402LF'  | 'CHIP'   | 'CS23902FB14'(!)        = 'End of Design' | 'Comp-Approve'     | 'CS23902FB14'           |'R0402'| '(R0402-0201)'                 | '3.9K'    | '1%'    | '1/16W'  | 'DISCRETE' | 'RES CHIP 3.9K 1/16W+-1%(0402)'                    | 'CHIP0402'     | ''          | ''            | '20110331'
 '3.9K'       | '1%'      | '1/16W'  | '0402LF'  | 'EMPTY'  | 'CS23902FB14'(!)        = 'End of Design' | 'Comp-Approve'     | 'CS23902FB14'           |'R0402'| '(R0402-0201)'                 | '3.9K'    | '1%'    | '1/16W'  | 'IO'       | 'RES CHIP 3.9K 1/16W+-1%(0402)'                    | 'CHIP0402'     | ''          | ''            | '20110331'
 '1.6K'       | '1%'      | '1/16W'  | '0402LF'  | 'CHIP'   | 'CS21602FB00'(!)        = 'End of Design' | 'Comp-Approve'     | 'CS21602FB00'           |'R0402'| '(R0402-0201)'                 | '1.6K'    | '1%'    | '1/16W'  | 'DISCRETE' | 'RES CHIP 1.6K(1/16W.+-1%.0402)'                   | 'CHIP0402'     | ''          | ''            | '20110331'
 '1.6K'       | '1%'      | '1/16W'  | '0402LF'  | 'EMPTY'  | 'CS21602FB00'(!)        = 'End of Design' | 'Comp-Approve'     | 'CS21602FB00'           |'R0402'| '(R0402-0201)'                 | '1.6K'    | '1%'    | '1/16W'  | 'IO'       | 'RES CHIP 1.6K(1/16W.+-1%.0402)'                   | 'CHIP0402'     | ''          | ''            | '20110331'
 '56.2K'      | '1%'      | '1/16W'  | '0402LF'  | 'CHIP'   | 'CS35622FB10'(!)        = 'End of Design' | 'Comp-Approve'     | 'CS35622FB10'           |'R0402'| '(R0402-0201)'                 | '56.2K'   | '1%'    | '1/16W'  | 'DISCRETE' | 'RES CHIP 56.2K 1/16W +-1% (0402)'                 | 'CHIP0402'     | ''          | ''            | '20110407'
 '56.2K'      | '1%'      | '1/16W'  | '0402LF'  | 'EMPTY'  | 'CS35622FB10'(!)        = 'End of Design' | 'Comp-Approve'     | 'CS35622FB10'           |'R0402'| '(R0402-0201)'                 | '56.2K'   | '1%'    | '1/16W'  | 'IO'       | 'RES CHIP 56.2K 1/16W +-1% (0402)'                 | 'CHIP0402'     | ''          | ''            | '20110407'
 '71.5K'      | '1%'      | '1/16W'  | '0402LF'  | 'CHIP'   | 'CS37152FB11'(!)        = 'End of Design' | 'Comp-Approve'     | 'CS37152FB11'           |'R0402'| '(R0402-0201)'                 | '71.5K'   | '1%'    | '1/16W'  | 'DISCRETE' | 'RES CHIP 71.5K 1/16W +-1%(0402)'                  | 'CHIP0402'     | ''          | ''            | '20110411'
 '71.5K'      | '1%'      | '1/16W'  | '0402LF'  | 'EMPTY'  | 'CS37152FB11'(!)        = 'End of Design' | 'Comp-Approve'     | 'CS37152FB11'           |'R0402'| '(R0402-0201)'                 | '71.5K'   | '1%'    | '1/16W'  | 'IO'       | 'RES CHIP 71.5K 1/16W +-1%(0402)'                  | 'CHIP0402'     | ''          | ''            | '20110411'
 '2.0M'       | '1%'      | '1/10W'  | '0603LF'  | 'CHIP'   | 'CS52003F911'(!)        = 'End of Design' | 'Comp-Approve'     | 'CS52003F911'           |'R0603'| '(SMR0603AW)'                  | '2.0M'    | '1%'    | '1/10W'  | 'DISCRETE' | 'RESISTOR CHIP 2M 1/10W +-1%(0603)'                | 'CHIP0603'     | ''          | ''            | '20110411'
 '2.0M'       | '1%'      | '1/10W'  | '0603LF'  | 'EMPTY'  | 'CS52003F911'(!)        = 'End of Design' | 'Comp-Approve'     | 'CS52003F911'           |'R0603'| '(SMR0603AW)'                  | '2.0M'    | '1%'    | '1/10W'  | 'IO'       | 'RESISTOR CHIP 2M 1/10W +-1%(0603)'                | 'CHIP0603'     | ''          | ''            | '20110411'
 '4.7M'       | '1%'      | '1/10W'  | '0603LF'  | 'CHIP'   | 'CS54703F903'(!)        = 'End of Design' | 'Comp-Approve'     | 'CS54703F903'           |'R0603'| '(SMR0603AW)'                  | '4.7M'    | '1%'    | '1/10W'  | 'DISCRETE' | 'RES CHIP 4.7M 1/10W +-1%(0603)'                   | 'CHIP0603'     | ''          | ''            | '20110411'
 '4.7M'       | '1%'      | '1/10W'  | '0603LF'  | 'EMPTY'  | 'CS54703F903'(!)        = 'End of Design' | 'Comp-Approve'     | 'CS54703F903'           |'R0603'| '(SMR0603AW)'                  | '4.7M'    | '1%'    | '1/10W'  | 'IO'       | 'RES CHIP 4.7M 1/10W +-1%(0603)'                   | 'CHIP0603'     | ''          | ''            | '20110411'
 '15.4K'      | '1%'      | '1/16W'  | '0402LF'  | 'CHIP'   | 'CS31542FB14'(!)        = 'End of Design' | 'Comp-Approve'     | 'CS31542FB14'           |'R0402'| '(R0402-0201)'                 | '15.4K'   | '1%'    | '1/16W'  | 'DISCRETE' | 'RES CHIP 15.4K 1/16W +-1%(0402)'                  | 'CHIP0402'     | ''          | ''            | '20110411'
 '15.4K'      | '1%'      | '1/16W'  | '0402LF'  | 'EMPTY'  | 'CS31542FB14'(!)        = 'End of Design' | 'Comp-Approve'     | 'CS31542FB14'           |'R0402'| '(R0402-0201)'                 | '15.4K'   | '1%'    | '1/16W'  | 'IO'       | 'RES CHIP 15.4K 1/16W +-1%(0402)'                  | 'CHIP0402'     | ''          | ''            | '20110411'
 '49.9'       | '1%'      | '1/10W'  | '0603LF'  | 'CHIP'   | 'CS04993F953'(!)        = ''              | ''                 | 'CS04993F953'           |'R0603'| '(SMR0603AW)'                  | '49.9'    | '1%'    | '1/10W'  | 'DISCRETE' | 'RESISTOR CHIP 49.9 1/10W +-1%(1608) '             | 'CHIP0603'     | ''          | ''            | '20110419'
 '49.9'       | '1%'      | '1/10W'  | '0603LF'  | 'EMPTY'  | 'CS04993F953'(!)        = ''              | ''                 | 'CS04993F953'           |'R0603'| '(SMR0603AW)'                  | '49.9'    | '1%'    | '1/10W'  | 'IO'       | 'RESISTOR CHIP 49.9 1/10W +-1%(1608) '             | 'CHIP0603'     | ''          | ''            | '20110419'
 '35.7K'      | '1%'      | '1/16W'  | '0402LF'  | 'CHIP'   | 'CS33572FB13'(!)        = 'End of Design' | 'Comp-Approve'     | 'CS33572FB13'           |'R0402'| '(R0402-0201)'                 | '35.7K'   | '1%'    | '1/16W'  | 'DISCRETE' | 'RES CHIP 35.7K 1/16W +-1%(0402)'                  | 'CHIP0402'     | ''          | ''            | '20110420'
 '35.7K'      | '1%'      | '1/16W'  | '0402LF'  | 'EMPTY'  | 'CS33572FB13'(!)        = 'End of Design' | 'Comp-Approve'     | 'CS33572FB13'           |'R0402'| '(R0402-0201)'                 | '35.7K'   | '1%'    | '1/16W'  | 'IO'       | 'RES CHIP 35.7K 1/16W +-1%(0402)'                  | 'CHIP0402'     | ''          | ''            | '20110420'
 '24.3K'      | '1%'      | '1/16W'  | '0402LF'  | 'CHIP'   | 'CS32432FB19'(!)        = 'End of Design' | 'Comp-Approve'     | 'CS32432FB19'           |'R0402'| '(R0402-0201)'                 | '24.3K'   | '1%'    | '1/16W'  | 'DISCRETE' | 'RES CHIP 24.3K 1/16W +-1%(0402)'                  | 'CHIP0402'     | ''          | ''            | '20110420'
 '24.3K'      | '1%'      | '1/16W'  | '0402LF'  | 'EMPTY'  | 'CS32432FB19'(!)        = 'End of Design' | 'Comp-Approve'     | 'CS32432FB19'           |'R0402'| '(R0402-0201)'                 | '24.3K'   | '1%'    | '1/16W'  | 'IO'       | 'RES CHIP 24.3K 1/16W +-1%(0402)'                  | 'CHIP0402'     | ''          | ''            | '20110420'
 '25.5K'      | '1%'      | '1/16W'  | '0402LF'  | 'CHIP'   | 'CS32552FB11'(!)        = 'End of Design' | 'Comp-Approve'     | 'CS32552FB11'           |'R0402'| '(R0402-0201)'                 | '25.5K'   | '1%'    | '1/16W'  | 'DISCRETE' | 'RES CHIP 25.5K 1/16W +-1%(0402)'                  | 'CHIP0402'     | ''          | ''            | '20110420'
 '25.5K'      | '1%'      | '1/16W'  | '0402LF'  | 'EMPTY'  | 'CS32552FB11'(!)        = 'End of Design' | 'Comp-Approve'     | 'CS32552FB11'           |'R0402'| '(R0402-0201)'                 | '25.5K'   | '1%'    | '1/16W'  | 'IO'       | 'RES CHIP 25.5K 1/16W +-1%(0402)'                  | 'CHIP0402'     | ''          | ''            | '20110420'
 '60.4K'      | '1%'      | '1/16W'  | '0402LF'  | 'CHIP'   | 'CS36042FB10'(!)        = 'End of Design' | 'Comp-Approve'     | 'CS36042FB10'           |'R0402'| '(R0402-0201)'                 | '60.4K'   | '1%'    | '1/16W'  | 'DISCRETE' | 'RES CHIP 60.4K 1/16W +-1%(0402)'                  | 'CHIP0402'     | ''          | ''            | '20110531'
 '60.4K'      | '1%'      | '1/16W'  | '0402LF'  | 'EMPTY'  | 'CS36042FB10'(!)        = 'End of Design' | 'Comp-Approve'     | 'CS36042FB10'           |'R0402'| '(R0402-0201)'                 | '60.4K'   | '1%'    | '1/16W'  | 'IO'       | 'RES CHIP 60.4K 1/16W +-1%(0402)'                  | 'CHIP0402'     | ''          | ''            | '20110531'
 '39.2K'      | '1%'      | '1/16W'  | '0402LF'  | 'CHIP'   | 'CS33922FB15'(!)        = 'End of Design' | 'Comp-Approve'     | 'CS33922FB15'           |'R0402'| '(R0402-0201)'                 | '39.2K'   | '1%'    | '1/16W'  | 'DISCRETE' | 'RES CHIP 39.2K 1/16W +-1%(0402)'                  | 'CHIP0402'     | ''          | ''            | '20110531'
 '39.2K'      | '1%'      | '1/16W'  | '0402LF'  | 'EMPTY'  | 'CS33922FB15'(!)        = 'End of Design' | 'Comp-Approve'     | 'CS33922FB15'           |'R0402'| '(R0402-0201)'                 | '39.2K'   | '1%'    | '1/16W'  | 'IO'       | 'RES CHIP 39.2K 1/16W +-1%(0402)'                  | 'CHIP0402'     | ''          | ''            | '20110531'
 '1.18K'      | '1%'      | '1/16W'  | '0402LF'  | 'CHIP'   | 'CS21182FB08'(!)        = 'End of Design' | 'Comp-Approve'     | 'CS21182FB08'           |'R0402'| '(R0402-0201)'                 | '1.18K'   | '1%'    | '1/16W'  | 'DISCRETE' | 'RES CHIP 1.18K 1/16W +-1%(0402)'                  | 'CHIP0402'     | ''          | ''            | '20110601'
 '1.18K'      | '1%'      | '1/16W'  | '0402LF'  | 'EMPTY'  | 'CS21182FB08'(!)        = 'End of Design' | 'Comp-Approve'     | 'CS21182FB08'           |'R0402'| '(R0402-0201)'                 | '1.18K'   | '1%'    | '1/16W'  | 'IO'       | 'RES CHIP 1.18K 1/16W +-1%(0402)'                  | 'CHIP0402'     | ''          | ''            | '20110601'
 '4.22K'      | '1%'      | '1/16W'  | '0402LF'  | 'CHIP'   | 'CS24222FB11'(!)        = 'End of Design' | 'Comp-Approve'     | 'CS24222FB11'           |'R0402'| '(R0402-0201)'                 | '4.22K'   | '1%'    | '1/16W'  | 'DISCRETE' | 'RES CHIP 4.22K 1/16W +-1%(0402)'                  | 'CHIP0402'     | ''          | ''            | '20110601'
 '4.22K'      | '1%'      | '1/16W'  | '0402LF'  | 'EMPTY'  | 'CS24222FB11'(!)        = 'End of Design' | 'Comp-Approve'     | 'CS24222FB11'           |'R0402'| '(R0402-0201)'                 | '4.22K'   | '1%'    | '1/16W'  | 'IO'       | 'RES CHIP 4.22K 1/16W +-1%(0402)'                  | 'CHIP0402'     | ''          | ''            | '20110601'
 '2'          | '1%'      | '1/10W'  | '0603LF'  | 'CHIP'   | 'CS-2003F900'(!)        = ''              | ''                 | 'CS-2003F900'           |'R0603'| '(SMR0603AW)'                  | '2'       | '1%'    | '1/10W'  | 'DISCRETE' | 'RES CHIP 2 1/10W +-1%(0603)'                      | 'CHIP0603'     | ''          | ''            | '20110624'
 '2'          | '1%'      | '1/10W'  | '0603LF'  | 'EMPTY'  | 'CS-2003F900'(!)        = ''              | ''                 | 'CS-2003F900'           |'R0603'| '(SMR0603AW)'                  | '2'       | '1%'    | '1/10W'  | 'IO'       | 'RES CHIP 2 1/10W +-1%(0603)'                      | 'CHIP0603'     | ''          | ''            | '20110624'
 '29.4K'      | '1%'      | '1/16W'  | '0402LF'  | 'CHIP'   | 'CS32942FB03'(!)        = 'End of Design' | 'Comp-Approve'     | 'CS32942FB03'           |'R0402'| '(R0402-0201)'                 | '29.4K'   | '1%'    | '1/16W'  | 'DISCRETE' | 'RES CHIP 29.4K 1/16W +-1%(0402)'                  | 'CHIP0402'     | ''          | ''            | '20110725'
 '29.4K'      | '1%'      | '1/16W'  | '0402LF'  | 'EMPTY'  | 'CS32942FB03'(!)        = 'End of Design' | 'Comp-Approve'     | 'CS32942FB03'           |'R0402'| '(R0402-0201)'                 | '29.4K'   | '1%'    | '1/16W'  | 'IO'       | 'RES CHIP 29.4K 1/16W +-1%(0402)'                  | 'CHIP0402'     | ''          | ''            | '20110725'
 '22.6K'      | '1%'      | '1/16W'  | '0402LF'  | 'CHIP'   | 'CS32262FB15'(!)        = 'End of Design' | 'Comp-Approve'     | 'CS32262FB15'           |'R0402'| '(R0402-0201)'                 | '22.6K'   | '1%'    | '1/16W'  | 'DISCRETE' | 'RES CHIP 22.6K 1/16W +-1%(0402)'                  | 'CHIP0402'     | ''          | ''            | '20110725'
 '22.6K'      | '1%'      | '1/16W'  | '0402LF'  | 'EMPTY'  | 'CS32262FB15'(!)        = 'End of Design' | 'Comp-Approve'     | 'CS32262FB15'           |'R0402'| '(R0402-0201)'                 | '22.6K'   | '1%'    | '1/16W'  | 'IO'       | 'RES CHIP 22.6K 1/16W +-1%(0402)'                  | 'CHIP0402'     | ''          | ''            | '20110725'
 '383'        | '1%'      | '1/16W'  | '0402LF'  | 'CHIP'   | 'CS13832FB00'(!)        = 'End of Design' | 'Comp-Approve'     | 'CS13832FB00'           |'R0402'| '(R0402-0201)'                 | '383'     | '1%'    | '1/16W'  | 'DISCRETE' | 'RES CHIP 383 1/16W +-1%(0402)'                    | 'CHIP0402'     | ''          | ''            | '20110725'
 '383'        | '1%'      | '1/16W'  | '0402LF'  | 'EMPTY'  | 'CS13832FB00'(!)        = 'End of Design' | 'Comp-Approve'     | 'CS13832FB00'           |'R0402'| '(R0402-0201)'                 | '383'     | '1%'    | '1/16W'  | 'IO'       | 'RES CHIP 383 1/16W +-1%(0402)'                    | 'CHIP0402'     | ''          | ''            | '20110725'
 '2.2'        | '1%'      | '1/16W'  | '0402LF'  | 'CHIP'   | 'CS-2202FB00'(!)        = 'End of Design' | 'Comp-Approve'     | 'CS-2202FB00'           |'R0402'| '(R0402-0201)'                 | '2.2'     | '1%'    | '1/16W'  | 'DISCRETE' | 'RES CHIP 2.2 1/16W +-1% (0402)'                   | 'CHIP0402'     | ''          | ''            | '20110725'
 '2.2'        | '1%'      | '1/16W'  | '0402LF'  | 'EMPTY'  | 'CS-2202FB00'(!)        = 'End of Design' | 'Comp-Approve'     | 'CS-2202FB00'           |'R0402'| '(R0402-0201)'                 | '2.2'     | '1%'    | '1/16W'  | 'IO'       | 'RES CHIP 2.2 1/16W +-1% (0402)'                   | 'CHIP0402'     | ''          | ''            | '20110725'
 '1.13k'      | '1%'      | '1/16W'  | '0402LF'  | 'CHIP'   | 'CS21132FB13'(!)        = ''              | ''                 | 'CS21132FB13'           |'R0402'| '(R0402-0201)'                 | '1.13k'   | '1%'    | '1/16W'  | 'DISCRETE' | 'RES CHIP 1.13K 1/16W +-1%(0402)'                  | 'CHIP0402'     | ''          | ''            | '20110725'
 '1.13k'      | '1%'      | '1/16W'  | '0402LF'  | 'EMPTY'  | 'CS21132FB13'(!)        = ''              | ''                 | 'CS21132FB13'           |'R0402'| '(R0402-0201)'                 | '1.13k'   | '1%'    | '1/16W'  | 'IO'       | 'RES CHIP 1.13K 1/16W +-1%(0402)'                  | 'CHIP0402'     | ''          | ''            | '20110725'
 '38.3K'      | '1%'      | '1/16W'  | '0402LF'  | 'CHIP'   | 'CS33832FB08'(!)        = 'End of Design' | 'Comp-Approve'     | 'CS33832FB08'           |'R0402'| '(R0402-0201)'                 | '38.3K'   | '1%'    | '1/16W'  | 'DISCRETE' | 'RES CHIP 38.3K 1/16W +-1% (0402)'                 | 'CHIP0402'     | ''          | ''            | '20110725'
 '38.3K'      | '1%'      | '1/16W'  | '0402LF'  | 'EMPTY'  | 'CS33832FB08'(!)        = 'End of Design' | 'Comp-Approve'     | 'CS33832FB08'           |'R0402'| '(R0402-0201)'                 | '38.3K'   | '1%'    | '1/16W'  | 'IO'       | 'RES CHIP 38.3K 1/16W +-1% (0402)'                 | 'CHIP0402'     | ''          | ''            | '20110725'
 '4.12K'      | '1%'      | '1/16W'  | '0402LF'  | 'CHIP'   | 'CS24122FB17'(!)        = 'End of Design' | 'Comp-Approve'     | 'CS24122FB17'           |'R0402'| '(R0402-0201)'                 | '4.12K'   | '1%'    | '1/16W'  | 'DISCRETE' | 'RES CHIP 4.12K 1/16W +-1%(0402)'                  | 'CHIP0402'     | ''          | ''            | '20110805'
 '4.12K'      | '1%'      | '1/16W'  | '0402LF'  | 'EMPTY'  | 'CS24122FB17'(!)        = 'End of Design' | 'Comp-Approve'     | 'CS24122FB17'           |'R0402'| '(R0402-0201)'                 | '4.12K'   | '1%'    | '1/16W'  | 'IO'       | 'RES CHIP 4.12K 1/16W +-1%(0402)'                  | 'CHIP0402'     | ''          | ''            | '20110805'
 '1.91K'      | '1%'      | '1/16W'  | '0402LF'  | 'CHIP'   | 'CS21912FB05'(!)        = ''              | ''                 | 'CS21912FB05'           |'R0402'| '(R0402-0201)'                 | '1.91K'   | '1%'    | '1/16W'  | 'DISCRETE' | 'RES CHIP 1.91K 1/16W +-1%(0402)'                  | 'CHIP0402'     | ''          | ''            | '20110810'
 '1.91K'      | '1%'      | '1/16W'  | '0402LF'  | 'EMPTY'  | 'CS21912FB05'(!)        = ''              | ''                 | 'CS21912FB05'           |'R0402'| '(R0402-0201)'                 | '1.91K'   | '1%'    | '1/16W'  | 'IO'       | 'RES CHIP 1.91K 1/16W +-1%(0402)'                  | 'CHIP0402'     | ''          | ''            | '20110810'
 '88.7K'      | '1%'      | '1/16W'  | '0402LF'  | 'CHIP'   | 'CS38872FB18'(!)        = 'End of Design' | 'Comp-Approve'     | 'CS38872FB18'           |'R0402'| '(R0402-0201)'                 | '88.7K'   | '1%'    | '1/16W'  | 'DISCRETE' | 'RES CHIP 88.7K 1/16W +-1%(0402)'                  | 'CHIP0402'     | ''          | ''            | '20110812'
 '88.7K'      | '1%'      | '1/16W'  | '0402LF'  | 'EMPTY'  | 'CS38872FB18'(!)        = 'End of Design' | 'Comp-Approve'     | 'CS38872FB18'           |'R0402'| '(R0402-0201)'                 | '88.7K'   | '1%'    | '1/16W'  | 'IO'       | 'RES CHIP 88.7K 1/16W +-1%(0402)'                  | 'CHIP0402'     | ''          | ''            | '20110812'
 '5.9K'       | '1%'      | '1/16W'  | '0402LF'  | 'CHIP'   | 'CS25902FB10'(!)        = 'End of Design' | 'Comp-Approve'     | 'CS25902FB10'           |'R0402'| '(R0402-0201)'                 | '5.9K'    | '1%'    | '1/16W'  | 'DISCRETE' | 'RES CHIP 5.9K 1/16W +-1%(0402)'                   | 'CHIP0402'     | ''          | ''            | '20110812'
 '5.9K'       | '1%'      | '1/16W'  | '0402LF'  | 'EMPTY'  | 'CS25902FB10'(!)        = 'End of Design' | 'Comp-Approve'     | 'CS25902FB10'           |'R0402'| '(R0402-0201)'                 | '5.9K'    | '1%'    | '1/16W'  | 'IO'       | 'RES CHIP 5.9K 1/16W +-1%(0402)'                   | 'CHIP0402'     | ''          | ''            | '20110812'
 '4.42K'      | '1%'      | '1/16W'  | '0402LF'  | 'CHIP'   | 'CS24422FB00'(!)        = 'End of Design' | 'Comp-Approve'     | 'CS24422FB00'           |'R0402'| '(R0402-0201)'                 | '4.42K'   | '1%'    | '1/16W'  | 'DISCRETE' | 'RES CHIP 4.42K 1/16W +-1%(0402)'                  | 'CHIP0402'     | ''          | ''            | '20110812'
 '4.42K'      | '1%'      | '1/16W'  | '0402LF'  | 'EMPTY'  | 'CS24422FB00'(!)        = 'End of Design' | 'Comp-Approve'     | 'CS24422FB00'           |'R0402'| '(R0402-0201)'                 | '4.42K'   | '1%'    | '1/16W'  | 'IO'       | 'RES CHIP 4.42K 1/16W +-1%(0402)'                  | 'CHIP0402'     | ''          | ''            | '20110812'
 '17.4K'      | '1%'      | '1/16W'  | '0402LF'  | 'CHIP'   | 'CS31742FB20'(!)        = 'End of Design' | 'Comp-Approve'     | 'CS31742FB20'           |'R0402'| '(R0402-0201)'                 | '17.4K'   | '1%'    | '1/16W'  | 'DISCRETE' | 'RES CHIP 17.4K 1/16W +-1% (0402)'                 | 'CHIP0402'     | ''          | ''            | '20110823'
 '17.4K'      | '1%'      | '1/16W'  | '0402LF'  | 'EMPTY'  | 'CS31742FB20'(!)        = 'End of Design' | 'Comp-Approve'     | 'CS31742FB20'           |'R0402'| '(R0402-0201)'                 | '17.4K'   | '1%'    | '1/16W'  | 'IO'       | 'RES CHIP 17.4K 1/16W +-1% (0402)'                 | 'CHIP0402'     | ''          | ''            | '20110823'
 '26.7K'      | '1%'      | '1/16W'  | '0402LF'  | 'CHIP'   | 'CS32672FB14'(!)        = 'End of Design' | 'Comp-Approve'     | 'CS32672FB14'           |'R0402'| '(R0402-0201)'                 | '26.7K'   | '1%'    | '1/16W'  | 'DISCRETE' | 'RES CHIP 26.7K 1/16W +-1%(0402)'                  | 'CHIP0402'     | ''          | ''            | '20110825'
 '26.7K'      | '1%'      | '1/16W'  | '0402LF'  | 'EMPTY'  | 'CS32672FB14'(!)        = 'End of Design' | 'Comp-Approve'     | 'CS32672FB14'           |'R0402'| '(R0402-0201)'                 | '26.7K'   | '1%'    | '1/16W'  | 'IO'       | 'RES CHIP 26.7K 1/16W +-1%(0402)'                  | 'CHIP0402'     | ''          | ''            | '20110825'
 '102K'       | '1%'      | '1/16W'  | '0402LF'  | 'CHIP'   | 'CS41022FB19'(!)        = 'End of Design' | 'Comp-Approve'     | 'CS41022FB19'           |'R0402'| '(R0402-0201)'                 | '102K'    | '1%'    | '1/16W'  | 'DISCRETE' | 'RES CHIP 102K 1/16W +-1%(0402)'                   | 'CHIP0402'     | ''          | ''            | '20110826'
 '102K'       | '1%'      | '1/16W'  | '0402LF'  | 'EMPTY'  | 'CS41022FB19'(!)        = 'End of Design' | 'Comp-Approve'     | 'CS41022FB19'           |'R0402'| '(R0402-0201)'                 | '102K'    | '1%'    | '1/16W'  | 'IO'       | 'RES CHIP 102K 1/16W +-1%(0402)'                   | 'CHIP0402'     | ''          | ''            | '20110826'
 '105K'       | '1%'      | '1/16W'  | '0402LF'  | 'CHIP'   | 'CS41052FB04'(!)        = 'End of Design' | 'Comp-Approve'     | 'CS41052FB04'           |'R0402'| '(R0402-0201)'                 | '105K'    | '1%'    | '1/16W'  | 'DISCRETE' | 'RES CHIP 105K 1/16W +-1%(0402)'                   | 'CHIP0402'     | ''          | ''            | '20110826'
 '105K'       | '1%'      | '1/16W'  | '0402LF'  | 'EMPTY'  | 'CS41052FB04'(!)        = 'End of Design' | 'Comp-Approve'     | 'CS41052FB04'           |'R0402'| '(R0402-0201)'                 | '105K'    | '1%'    | '1/16W'  | 'IO'       | 'RES CHIP 105K 1/16W +-1%(0402)'                   | 'CHIP0402'     | ''          | ''            | '20110826'
 '182K'       | '1%'      | '1/16W'  | '0402LF'  | 'CHIP'   | 'CS41822FB18'(!)        = 'End of Design' | 'Comp-Approve'     | 'CS41822FB18'           |'R0402'| '(R0402-0201)'                 | '182K'    | '1%'    | '1/16W'  | 'DISCRETE' | 'RES CHIP 182K 1/16W +-1%(0402)'                   | 'CHIP0402'     | ''          | ''            | '20110826'
 '182K'       | '1%'      | '1/16W'  | '0402LF'  | 'EMPTY'  | 'CS41822FB18'(!)        = 'End of Design' | 'Comp-Approve'     | 'CS41822FB18'           |'R0402'| '(R0402-0201)'                 | '182K'    | '1%'    | '1/16W'  | 'IO'       | 'RES CHIP 182K 1/16W +-1%(0402)'                   | 'CHIP0402'     | ''          | ''            | '20110826'
 '280K'       | '1%'      | '1/16W'  | '0402LF'  | 'CHIP'   | 'CS42802FB03'(!)        = 'End of Design' | 'Comp-Approve'     | 'CS42802FB03'           |'R0402'| '(R0402-0201)'                 | '182K'    | '1%'    | '1/16W'  | 'DISCRETE' | 'RES CHIP 280K 1/16W +-1%(0402)'                   | 'CHIP0402'     | ''          | ''            | '20110826'
 '280K'       | '1%'      | '1/16W'  | '0402LF'  | 'EMPTY'  | 'CS42802FB03'(!)        = 'End of Design' | 'Comp-Approve'     | 'CS42802FB03'           |'R0402'| '(R0402-0201)'                 | '182K'    | '1%'    | '1/16W'  | 'IO'       | 'RES CHIP 280K 1/16W +-1%(0402)'                   | 'CHIP0402'     | ''          | ''            | '20110826'
 '5.6K'       | '1%'      | '1/16W'  | '0402LF'  | 'CHIP'   | 'CS25602FB19'(!)        = 'End of Design' | 'Comp-Approve'     | 'CS25602FB19'           |'R0402'| '(R0402-0201)'                 | '5.6K'    | '1%'    | '1/16W'  | 'DISCRETE' | 'RES CHIP 5.6K 1/16W +-1%(0402)'                   | 'CHIP0402'     | ''          | ''            | '20110826'
 '5.6K'       | '1%'      | '1/16W'  | '0402LF'  | 'EMPTY'  | 'CS25602FB19'(!)        = 'End of Design' | 'Comp-Approve'     | 'CS25602FB19'           |'R0402'| '(R0402-0201)'                 | '5.6K'    | '1%'    | '1/16W'  | 'IO'       | 'RES CHIP 5.6K 1/16W +-1%(0402)'                   | 'CHIP0402'     | ''          | ''            | '20110826'
 '1K'         | '0.1%'    | '1/16W'  | '0402LF'  | 'CHIP'   | 'CS21002BB00'(!)        = ''              | ''                 | 'CS21002BB00'           |'R0402'| '(R0402-0201)'                 | '1K'      | '0.1%'  | '1/16W'  | 'DISCRETE' | 'RES CHIP 1K 1/16W +-0.1%(0402)'                   | 'CHIP0402'     | ''          | ''            | '20110909'
 '1K'         | '0.1%'    | '1/16W'  | '0402LF'  | 'EMPTY'  | 'CS21002BB00'(!)        = ''              | ''                 | 'CS21002BB00'           |'R0402'| '(R0402-0201)'                 | '1K'      | '0.1%'  | '1/16W'  | 'IO'       | 'RES CHIP 1K 1/16W +-0.1%(0402)'                   | 'CHIP0402'     | ''          | ''            | '20110909'
 '24.9'       | '0.5%'    | '1/16W'  | '0402LF'  | 'CHIP'   | 'CS02492DB00'(!)        = 'End of Design' | 'Comp-Approve'     | 'CS02492DB00'           |'R0402'| '(R0402-0201)'                 | '24.9'    | '0.5%'  | '1/16W'  | 'DISCRETE' | 'RES CHIP 24.9 1/16W +-0.5%(0402)'                 | 'CHIP0402'     | ''          | ''            | '20110909'
 '24.9'       | '0.5%'    | '1/16W'  | '0402LF'  | 'EMPTY'  | 'CS02492DB00'(!)        = 'End of Design' | 'Comp-Approve'     | 'CS02492DB00'           |'R0402'| '(R0402-0201)'                 | '24.9'    | '0.5%'  | '1/16W'  | 'IO'       | 'RES CHIP 24.9 1/16W +-0.5%(0402)'                 | 'CHIP0402'     | ''          | ''            | '20110909'
 '619K'       | '1%'      | '1/16W'  | '0402LF'  | 'CHIP'   | 'CS46192FB18'(!)        = 'End of Design' | 'Comp-Release Qty' | 'CS46192FB18'           |'R0402'| '(R0402-0201)'                 | '619K'    | '1%'    | '1/16W'  | 'DISCRETE' | 'RES CHIP 619K 1/16W +-1%(0402)'                   | 'CHIP0402'     | ''          | ''            | '20111111'
 '619K'       | '1%'      | '1/16W'  | '0402LF'  | 'EMPTY'  | 'CS46192FB18'(!)        = 'End of Design' | 'Comp-Release Qty' | 'CS46192FB18'           |'R0402'| '(R0402-0201)'                 | '619K'    | '1%'    | '1/16W'  | 'IO'       | 'RES CHIP 619K 1/16W +-1%(0402))'                  | 'CHIP0402'     | ''          | ''            | '20111111'
 '10.7K'      | '1%'      | '1/16W'  | '0402LF'  | 'CHIP'   | 'CS31072FB10'(!)        = 'End of Design' | 'Comp-Approve'     | 'CS31072FB10'           |'R0402'| '(R0402-0201)'                 | '10.7K'   | '1%'    | '1/16W'  | 'DISCRETE' | 'RES CHIP 10.7K 1/16W +-1% (0402)'                 | 'CHIP0402'     | ''          | ''            | '20111122'
 '10.7K'      | '1%'      | '1/16W'  | '0402LF'  | 'EMPTY'  | 'CS31072FB10'(!)        = 'End of Design' | 'Comp-Approve'     | 'CS31072FB10'           |'R0402'| '(R0402-0201)'                 | '10.7K'   | '1%'    | '1/16W'  | 'IO'       | 'RES CHIP 10.7K 1/16W +-1% (0402)'                 | 'CHIP0402'     | ''          | ''            | '20111122'
 '51K'        | '1%'      | '1/16W'  | '0402LF'  | 'CHIP'   | 'CS35102FB04'(!)        = 'End of Design' | 'Comp-Approve'     | 'CS35102FB04'           |'R0402'| '(R0402-0201)'                 | '51K'     | '1%'    | '1/16W'  | 'DISCRETE' | 'RES CHIP 51K 1/16W +-1%(0402)'                    | 'CHIP0402'     | ''          | ''            | '20111123'
 '51K'        | '1%'      | '1/16W'  | '0402LF'  | 'EMPTY'  | 'CS35102FB04'(!)        = 'End of Design' | 'Comp-Approve'     | 'CS35102FB04'           |'R0402'| '(R0402-0201)'                 | '51K'     | '1%'    | '1/16W'  | 'IO'       | 'RES CHIP 51K 1/16W +-1%(0402)'                    | 'CHIP0402'     | ''          | ''            | '20111123'
 '3.6K'       | '5%'      | '1/16W'  | '0402LF'  | 'CHIP'   | 'CS23602JB15'(!)        = 'End of Design' | 'Comp-Approve'     | 'CS23602JB15'           |'R0402'| '(R0402-0201)'                 | '3.6K'    | '5%'    | '1/16W'  | 'DISCRETE' | 'RES CHIP 3.6K 1/16W +-5%(0402)'                   | 'CHIP0402'     | ''          | ''            | '20111123'
 '3.6K'       | '5%'      | '1/16W'  | '0402LF'  | 'EMPTY'  | 'CS23602JB15'(!)        = 'End of Design' | 'Comp-Approve'     | 'CS23602JB15'           |'R0402'| '(R0402-0201)'                 | '3.6K'    | '5%'    | '1/16W'  | 'IO'       | 'RES CHIP 3.6K 1/16W +-5%(0402)'                   | 'CHIP0402'     | ''          | ''            | '20111123'
 '7.5'        | '1%'      | '1/16W'  | '0402LF'  | 'CHIP'   | 'CS-7502FB00'(!)        = 'End of Design' | 'Comp-Approve'     | 'CS-7502FB00'           |'R0402'| '(R0402-0201)'                 | '7.5'     | '1%'    | '1/16W'  | 'DISCRETE' | 'RES CHIP 7.5 1/16W +-1%(0402)'                    | 'CHIP0402'     | ''          | ''            | '20111123'
 '7.5'        | '1%'      | '1/16W'  | '0402LF'  | 'EMPTY'  | 'CS-7502FB00'(!)        = 'End of Design' | 'Comp-Approve'     | 'CS-7502FB00'           |'R0402'| '(R0402-0201)'                 | '7.5'     | '1%'    | '1/16W'  | 'IO'       | 'RES CHIP 7.5 1/16W +-1%(0402)'                    | 'CHIP0402'     | ''          | ''            | '20111123'
 '20'         | '5%'      | '2W'     | '2512LF'  | 'CHIP'   | 'CS0200AJR00'(!)        = ''              | ''                 | 'CS0200AJR00'           |'R2512'| '(SMR2512AW)'                  | '20'      | '5%'    | '2W'     | 'DISCRETE' | 'RESISTOR CHIP 20 2W +-5%(2512)'                   | 'CHIP2512'     | ''          | ''            | '20111124'
 '20'         | '5%'      | '2W'     | '2512LF'  | 'EMPTY'  | 'CS0200AJR00'(!)        = ''              | ''                 | 'CS0200AJR00'           |'R2512'| '(SMR2512AW)'                  | '20'      | '5%'    | '2W'     | 'IO'       | 'RESISTOR CHIP 20 2W +-5%(2512)'                   | 'CHIP2512'     | ''          | ''            | '20111124'
 '698'        | '1%'      | '1/16W'  | '0402LF'  | 'CHIP'   | 'CS16982FB00'(!)        = 'End of Design' | 'Comp-Approve'     | 'CS16982FB00'           |'R0402'| '(R0402-0201)'                 | '698'     | '1%'    | '1/16W'  | 'DISCRETE' | 'RES CHIP 698 1/16W +-1%(0402)'                    | 'CHIP0402'     | ''          | ''            | '20111125'
 '698'        | '1%'      | '1/16W'  | '0402LF'  | 'EMPTY'  | 'CS16982FB00'(!)        = 'End of Design' | 'Comp-Approve'     | 'CS16982FB00'           |'R0402'| '(R0402-0201)'                 | '698'     | '1%'    | '1/16W'  | 'IO'       | 'RES CHIP 698 1/16W +-1%(0402)'                    | 'CHIP0402'     | ''          | ''            | '20111125'
 '75K'        | '1%'      | '1/16W'  | '0402LF'  | 'CHIP'   | 'CS37502FB12'(!)        = 'End of Design' | 'Comp-Approve'     | 'CS37502FB12'           |'R0402'| '(R0402-0201)'                 | '75K'     | '1%'    | '1/16W'  | 'DISCRETE' | 'RES CHIP 75K 1/16W +-1%(0402)'                    | 'CHIP0402'     | ''          | ''            | '20111130'
 '75K'        | '1%'      | '1/16W'  | '0402LF'  | 'EMPTY'  | 'CS37502FB12'(!)        = 'End of Design' | 'Comp-Approve'     | 'CS37502FB12'           |'R0402'| '(R0402-0201)'                 | '75K'     | '1%'    | '1/16W'  | 'IO'       | 'RES CHIP 75K 1/16W +-1%(0402)'                    | 'CHIP0402'     | ''          | ''            | '20111130'
 '121K'       | '1%'      | '1/16W'  | '0402LF'  | 'CHIP'   | 'CS41212FB11'(!)        = 'End of Design' | 'Comp-Approve'     | 'CS41212FB11'           |'R0402'| '(R0402-0201)'                 | '121K'    | '1%'    | '1/16W'  | 'DISCRETE' | 'RES CHIP 121K 1/16W +-1%(0402)'                   | 'CHIP0402'     | ''          | ''            | '20111130'
 '121K'       | '1%'      | '1/16W'  | '0402LF'  | 'EMPTY'  | 'CS41212FB11'(!)        = 'End of Design' | 'Comp-Approve'     | 'CS41212FB11'           |'R0402'| '(R0402-0201)'                 | '121K'    | '1%'    | '1/16W'  | 'IO'       | 'RES CHIP 121K 1/16W +-1%(0402)'                   | 'CHIP0402'     | ''          | ''            | '20111130'
 '22.1K'      | '1%'      | '1/16W'  | '0402LF'  | 'CHIP'   | 'CS32212FB12'(!)        = 'End of Design' | 'Comp-Approve'     | 'CS32212FB12'           |'R0402'| '(R0402-0201)'                 | '22.1K'   | '1%'    | '1/16W'  | 'DISCRETE' | 'RES CHIP 22.1K 1/16W +-1%(0402)'                  | 'CHIP0402'     | ''          | ''            | '20111130'
 '22.1K'      | '1%'      | '1/16W'  | '0402LF'  | 'EMPTY'  | 'CS32212FB12'(!)        = 'End of Design' | 'Comp-Approve'     | 'CS32212FB12'           |'R0402'| '(R0402-0201)'                 | '22.1K'   | '1%'    | '1/16W'  | 'IO'       | 'RES CHIP 22.1K 1/16W +-1%(0402)'                  | 'CHIP0402'     | ''          | ''            | '20111130'
 '3K'         | '1%'      | '1/10W'  | '0603LF'  | 'CHIP'   | 'CS23003F926'(!)        = 'End of Design' | 'Comp-Approve'     | 'CS23003F926'           |'R0603'| '(SMR0603AW)'                  | '3K'      | '1%'    | '1/10W'  | 'DISCRETE' | 'RES CHIP 3K 1/10W +-1%(0603)'                     | 'CHIP0603'     | ''          | ''            | '20111202'
 '3K'         | '1%'      | '1/10W'  | '0603LF'  | 'EMPTY'  | 'CS23003F926'(!)        = 'End of Design' | 'Comp-Approve'     | 'CS23003F926'           |'R0603'| '(SMR0603AW)'                  | '3K'      | '1%'    | '1/10W'  | 'IO'       | 'RES CHIP 3K 1/10W +-1%(0603)'                     | 'CHIP0603'     | ''          | ''            | '20111202'
 '470'        | '5%'      | '1/10W'  | '0603LF'  | 'CHIP'   | 'CS14703J941'(!)        = 'End of Design' | 'Comp-Approve'     | 'CS14703J941'           |'R0603'| '(SMR0603AW)'                  | '470'     | '5%'    | '1/10W'  | 'DISCRETE' | 'RESISTOR CHIP 470 1/10W+-5%(0603)'                | 'CHIP0603'     | ''          | ''            | '20111207'
 '470'        | '5%'      | '1/10W'  | '0603LF'  | 'EMPTY'  | 'CS14703J941'(!)        = 'End of Design' | 'Comp-Approve'     | 'CS14703J941'           |'R0603'| '(SMR0603AW)'                  | '470'     | '5%'    | '1/10W'  | 'IO'       | 'RESISTOR CHIP 470 1/10W+-5%(0603)'                | 'CHIP0603'     | ''          | ''            | '20111207'
 '8.2K'       | '1%'      | '1/16W'  | '0402LF'  | 'CHIP'   | 'CS28202FB12'(!)        = 'End of Design' | 'Comp-Approve'     | 'CS28202FB12'           |'R0402'| '(R0402-0201)'                 | '8.2K'    | '1%'    | '1/16W'  | 'DISCRETE' | 'RES CHIP 8.2K 1/16W +-1%(0402)'                   | 'CHIP0402'     | ''          | ''            | '20111208'
 '8.2K'       | '1%'      | '1/16W'  | '0402LF'  | 'EMPTY'  | 'CS28202FB12'(!)        = 'End of Design' | 'Comp-Approve'     | 'CS28202FB12'           |'R0402'| '(R0402-0201)'                 | '8.2K'    | '1%'    | '1/16W'  | 'IO'       | 'RES CHIP 8.2K 1/16W +-1%(0402)'                   | 'CHIP0402'     | ''          | ''            | '20111208'
 '63.4K'      | '1%'      | '1/16W'  | '0402LF'  | 'CHIP'   | 'CS36342FB11'(!)        = 'End of Design' | 'Comp-Approve'     | 'CS36342FB11'           |'R0402'| '(R0402-0201)'                 | '63.4K'   | '1%'    | '1/16W'  | 'DISCRETE' | 'RES CHIP 63.4K 1/16W +-1% (0402)'                 | 'CHIP0402'     | ''          | ''            | '20111208'
 '63.4K'      | '1%'      | '1/16W'  | '0402LF'  | 'EMPTY'  | 'CS36342FB11'(!)        = 'End of Design' | 'Comp-Approve'     | 'CS36342FB11'           |'R0402'| '(R0402-0201)'                 | '63.4K'   | '1%'    | '1/16W'  | 'IO'       | 'RES CHIP 63.4K 1/16W +-1% (0402)'                 | 'CHIP0402'     | ''          | ''            | '20111208'
 '2K'         | '1%'      | '1/10W'  | '0603LF'  | 'CHIP'   | 'CS22003F915'(!)        = ''              | ''                 | 'CS22003F915'           |'R0603'| '(SMR0603AW)'                  | '2K'      | '1%'    | '1/10W'  | 'DISCRETE' | 'RES CHIP 2K 1/10W +-1%(0603)'                     | 'CHIP0603'     | ''          | ''            | '20111208'
 '2K'         | '1%'      | '1/10W'  | '0603LF'  | 'EMPTY'  | 'CS22003F915'(!)        = ''              | ''                 | 'CS22003F915'           |'R0603'| '(SMR0603AW)'                  | '2K'      | '1%'    | '1/10W'  | 'IO'       | 'RES CHIP 2K 1/10W +-1%(0603)'                     | 'CHIP0603'     | ''          | ''            | '20111208'
 '5.11'       | '1%'      | '1/16W'  | '0402LF'  | 'CHIP'   | 'CS-5112FB06'(!)        = 'End of Design' | 'Comp-Approve'     | 'CS-5112FB06'           |'R0402'| '(R0402-0201)'                 | '5.11'    | '1%'    | '1/16W'  | 'DISCRETE' | 'RES CHIP 5.11 1/16W +-1%(0402)'                   | 'CHIP0402'     | ''          | ''            | '20111209'
 '5.11'       | '1%'      | '1/16W'  | '0402LF'  | 'EMPTY'  | 'CS-5112FB06'(!)        = 'End of Design' | 'Comp-Approve'     | 'CS-5112FB06'           |'R0402'| '(R0402-0201)'                 | '5.11'    | '1%'    | '1/16W'  | 'IO'       | 'RES CHIP 5.11 1/16W +-1%(0402)'                   | 'CHIP0402'     | ''          | ''            | '20111209'
 '0.51'       | '1%'      | '1/16W'  | '0402LF'  | 'CHIP'   | 'CS+5102FB00'(!)        = ''              | ''                 | 'CS+5102FB00'           |'R0402'| '(R0402-0201)'                 | '0.51'    | '1%'    | '1/16W'  | 'DISCRETE' | 'RES CHIP 0.51 1/16W +-1%(0402)'                   | 'CHIP0402'     | ''          | ''            | '20111209'
 '0.51'       | '1%'      | '1/16W'  | '0402LF'  | 'EMPTY'  | 'CS+5102FB00'(!)        = ''              | ''                 | 'CS+5102FB00'           |'R0402'| '(R0402-0201)'                 | '0.51'    | '1%'    | '1/16W'  | 'IO'       | 'RES CHIP 0.51 1/16W +-1%(0402)'                   | 'CHIP0402'     | ''          | ''            | '20111209'
 '39K'        | '1%'      | '1/10W'  | '0603LF ' | 'CHIP'   | 'CS33903F912'(!)        = ''              | ''                 | 'CS33903F912'           |'R0603'| '(SMR0603AW)'                  | '39K'     | '1%'    | '1/10W'  | 'DISCRETE' | 'RESISTOR CHIP 39K 1/10W+-1%(0603)'                | 'CHIP0603'     | ''          | ''            | '20111209'
 '39K'        | '1%'      | '1/10W'  | '0603LF ' | 'EMPTY'  | 'CS33903F912'(!)        = ''              | ''                 | 'CS33903F912'           |'R0603'| '(SMR0603AW)'                  | '39K'     | '1%'    | '1/10W'  | 'IO'       | 'RESISTOR CHIP 39K 1/10W+-1%(0603)'                | 'CHIP0603'     | ''          | ''            | '20111209'
 '31.6'       | '1%'      | '1/16W'  | '0402LF'  | 'CHIP'   | 'CS03162FB00'(!)        = ''              | ''                 | 'CS03162FB00'           |'R0402'| '(R0402-0201)'                 | '31.6'    | '1%'    | '1/16W'  | 'DISCRETE' | 'RES CHIP 31.6 1/16W +-1%(0402)'                   | 'CHIP0402'     | ''          | ''            | '20111213'
 '31.6'       | '1%'      | '1/16W'  | '0402LF'  | 'EMPTY'  | 'CS03162FB00'(!)        = ''              | ''                 | 'CS03162FB00'           |'R0402'| '(R0402-0201)'                 | '31.6'    | '1%'    | '1/16W'  | 'IO'       | 'RES CHIP 31.6 1/16W +-1%(0402)'                   | 'CHIP0402'     | ''          | ''            | '20111213'
 '33.2'       | '1%'      | '1/16W'  | '0402LF'  | 'CHIP'   | 'CS03322FB34'(!)        = 'End of Design' | 'Comp-Approve'     | 'CS03322FB34'           |'R0402'| '(R0402-0201)'                 | '33.2'    | '1%'    | '1/16W'  | 'DISCRETE' | 'RES CHIP 33.2 1/16W +-1%(0402)'                   | 'CHIP0402'     | ''          | ''            | '20111213'
 '33.2'       | '1%'      | '1/16W'  | '0402LF'  | 'EMPTY'  | 'CS03322FB34'(!)        = 'End of Design' | 'Comp-Approve'     | 'CS03322FB34'           |'R0402'| '(R0402-0201)'                 | '33.2'    | '1%'    | '1/16W'  | 'IO'       | 'RES CHIP 33.2 1/16W +-1%(0402)'                   | 'CHIP0402'     | ''          | ''            | '20111213'
 '42.2'       | '1%'      | '1/16W'  | '0402LF'  | 'CHIP'   | 'CS04222FB00'(!)        = 'End of Design' | 'End of Life'      | 'CS04222FB00'           |'R0402_EOL'| '(R0402-0201)'                 | '42.2'    | '1%'    | '1/16W'  | 'DISCRETE' | 'RES CHIP 42.2 1/16W +-1%(0402)'                   | 'CHIP0402'     | ''          | ''            | '20111213'
 '42.2'       | '1%'      | '1/16W'  | '0402LF'  | 'EMPTY'  | 'CS04222FB00'(!)        = 'End of Design' | 'End of Life'      | 'CS04222FB00'           |'R0402_EOL'| '(R0402-0201)'                 | '42.2'    | '1%'    | '1/16W'  | 'IO'       | 'RES CHIP 42.2 1/16W +-1%(0402)'                   | 'CHIP0402'     | ''          | ''            | '20111213'
 '51.1'       | '1%'      | '1/16W'  | '0402LF'  | 'CHIP'   | 'CS05112FB11'(!)        = 'End of Design' | 'Comp-Approve'     | 'CS05112FB11'           |'R0402'| '(R0402-0201)'                 | '51.1'    | '1%'    | '1/16W'  | 'DISCRETE' | 'RESISTOR CHIP 51.1,1/16W,+-1%(0402)'              | 'CHIP0402'     | ''          | ''            | '20111213'
 '51.1'       | '1%'      | '1/16W'  | '0402LF'  | 'EMPTY'  | 'CS05112FB11'(!)        = 'End of Design' | 'Comp-Approve'     | 'CS05112FB11'           |'R0402'| '(R0402-0201)'                 | '51.1'    | '1%'    | '1/16W'  | 'IO'       | 'RESISTOR CHIP 51.1,1/16W,+-1%(0402)'              | 'CHIP0402'     | ''          | ''            | '20111213'
 '270'        | '5%'      | '1/16W'  | '0402LF'  | 'CHIP'   | 'CS12702JB14'(!)        = 'End of Design' | 'Comp-Approve'     | 'CS12702JB14'           |'R0402'| '(R0402-0201)'                 | '270'     | '5%'    | '1/16W'  | 'DISCRETE' | 'RES CHIP 270(1/16W,+-5%,0402)'                    | 'CHIP0402'     | ''          | ''            | '20111213'
 '270'        | '5%'      | '1/16W'  | '0402LF'  | 'EMPTY'  | 'CS12702JB14'(!)        = 'End of Design' | 'Comp-Approve'     | 'CS12702JB14'           |'R0402'| '(R0402-0201)'                 | '270'     | '5%'    | '1/16W'  | 'IO'       | 'RES CHIP 270(1/16W,+-5%,0402)'                    | 'CHIP0402'     | ''          | ''            | '20111213'
 '274'        | '1%'      | '1/16W'  | '0402LF'  | 'CHIP'   | 'CS12742FB02'(!)        = 'End of Design' | 'Comp-Approve'     | 'CS12742FB02'           |'R0402'| '(R0402-0201)'                 | '274'     | '1%'    | '1/16W'  | 'DISCRETE' | 'RES CHIP 274 1/16W +-1%(0402)'                    | 'CHIP0402'     | ''          | ''            | '20111213'
 '274'        | '1%'      | '1/16W'  | '0402LF'  | 'EMPTY'  | 'CS12742FB02'(!)        = 'End of Design' | 'Comp-Approve'     | 'CS12742FB02'           |'R0402'| '(R0402-0201)'                 | '274'     | '1%'    | '1/16W'  | 'IO'       | 'RES CHIP 274 1/16W +-1%(0402)'                    | 'CHIP0402'     | ''          | ''            | '20111213'
 '2.43K'      | '1%'      | '1/16W'  | '0402LF'  | 'CHIP'   | 'CS22432FB09'(!)        = 'End of Design' | 'Comp-Approve'     | 'CS22432FB09'           |'R0402'| '(R0402-0201)'                 | '2.43K'   | '1%'    | '1/16W'  | 'DISCRETE' | 'RES CHIP 2.43K 1/16W +-1%(0402)'                  | 'CHIP0402'     | ''          | ''            | '20111213'
 '2.43K'      | '1%'      | '1/16W'  | '0402LF'  | 'EMPTY'  | 'CS22432FB09'(!)        = 'End of Design' | 'Comp-Approve'     | 'CS22432FB09'           |'R0402'| '(R0402-0201)'                 | '2.43K'   | '1%'    | '1/16W'  | 'IO'       | 'RES CHIP 2.43K 1/16W +-1%(0402)'                  | 'CHIP0402'     | ''          | ''            | '20111213'
 '27.4K'      | '1%'      | '1/10W'  | '0603LF'  | 'CHIP'   | 'CS32743F929'(!)        = ''              | ''                 | 'CS32743F929'           |'R0603'| '(SMR0603AW)'                  | '27.4K'   | '1%'    | '1/10W'  | 'DISCRETE' | 'RES CHIP 27.4K 1/10W +-1%(0603)'                  | 'CHIP0603'     | ''          | ''            | '20111213'
 '27.4K'      | '1%'      | '1/10W'  | '0603LF'  | 'EMPTY'  | 'CS32743F929'(!)        = ''              | ''                 | 'CS32743F929'           |'R0603'| '(SMR0603AW)'                  | '27.4K'   | '1%'    | '1/10W'  | 'IO'       | 'RES CHIP 27.4K 1/10W +-1%(0603)'                  | 'CHIP0603'     | ''          | ''            | '20111213'
 '48.7K'      | '1%'      | '1/16W'  | '0402LF'  | 'CHIP'   | 'CS34872FB17'(!)        = 'End of Design' | 'Comp-Approve'     | 'CS34872FB17'           |'R0402'| '(R0402-0201)'                 | '48.7K'   | '1%'    | '1/16W'  | 'DISCRETE' | 'RES CHIP 48.7K 1/16W +-1%(0402)'                  | 'CHIP0402'     | ''          | ''            | '20111213'
 '48.7K'      | '1%'      | '1/16W'  | '0402LF'  | 'EMPTY'  | 'CS34872FB17'(!)        = 'End of Design' | 'Comp-Approve'     | 'CS34872FB17'           |'R0402'| '(R0402-0201)'                 | '48.7K'   | '1%'    | '1/16W'  | 'IO'       | 'RES CHIP 48.7K 1/16W +-1%(0402)'                  | 'CHIP0402'     | ''          | ''            | '20111213'
 '220K'       | '5%'      | '1/16W'  | '0402LF'  | 'CHIP'   | 'CS42202JB11'(!)        = 'End of Design' | 'Comp-Approve'     | 'CS42202JB11'           |'R0402'| '(R0402-0201)'                 | '220K'    | '5%'    | '1/16W'  | 'DISCRETE' | 'RES CHIP 220K 1/16W+-5%(0402)'                    | 'CHIP0402'     | ''          | ''            | '20111213'
 '220K'       | '5%'      | '1/16W'  | '0402LF'  | 'EMPTY'  | 'CS42202JB11'(!)        = 'End of Design' | 'Comp-Approve'     | 'CS42202JB11'           |'R0402'| '(R0402-0201)'                 | '220K'    | '5%'    | '1/16W'  | 'IO'       | 'RES CHIP 220K 1/16W+-5%(0402)'                    | 'CHIP0402'     | ''          | ''            | '20111213'
 '390K'       | '5%'      | '1/16W'  | '0402LF'  | 'CHIP'   | 'CS43902JB10'(!)        = 'End of Design' | 'Comp-Approve'     | 'CS43902JB10'           |'R0402'| '(R0402-0201)'                 | '390K'    | '5%'    | '1/16W'  | 'DISCRETE' | 'RES CHIP 390K(1/16W +-5% 0402)'                   | 'CHIP0402'     | ''          | ''            | '20111213'
 '390K'       | '5%'      | '1/16W'  | '0402LF'  | 'EMPTY'  | 'CS43902JB10'(!)        = 'End of Design' | 'Comp-Approve'     | 'CS43902JB10'           |'R0402'| '(R0402-0201)'                 | '390K'    | '5%'    | '1/16W'  | 'IO'       | 'RES CHIP 390K(1/16W +-5% 0402)'                   | 'CHIP0402'     | ''          | ''            | '20111213'
 '0.01'       | '5%'      | '3/4W'   | '2010LF'  | 'CHIP'   | 'CS+010BFJ28'(!)        = 'End of Design' | 'Comp-Approve'     | 'CS+010BFJ28'           |'R2010'| '(SMR2010AW)'                  | '0.01'    | '5%'    | '3/4W'   | 'DISCRETE' | 'RES CHIP 0.01 3/4W +-1%(2010)'                    | 'CHIP2010'     | ''          | ''            | '20111215'
 '0.01'       | '5%'      | '3/4W'   | '2010LF'  | 'EMPTY'  | 'CS+010BFJ28'(!)        = 'End of Design' | 'Comp-Approve'     | 'CS+010BFJ28'           |'R2010'| '(SMR2010AW)'                  | '0.01'    | '5%'    | '3/4W'   | 'IO'       | 'RES CHIP 0.01 3/4W +-1%(2010)'                    | 'CHIP2010'     | ''          | ''            | '20111215'
 '5.11'       | '1%'      | '1/4W'   | '1206LF'  | 'CHIP'   | 'CS-5116F208'(!)        = ''              | ''                 | 'CS-5116F208'           |'R1206'| '(SMR1206AW)'                  | '5.11'    | '1%'    | '1/4W'   | 'DISCRETE' | 'RES CHIP 5.11 1/4W +-1%(1206)'                    | 'CHIP1206'     | ''          | ''            | '20111219'
 '5.11'       | '1%'      | '1/4W'   | '1206LF'  | 'EMPTY'  | 'CS-5116F208'(!)        = ''              | ''                 | 'CS-5116F208'           |'R1206'| '(SMR1206AW)'                  | '5.11'    | '1%'    | '1/4W'   | 'IO'       | 'RES CHIP 5.11 1/4W +-1%(1206)'                    | 'CHIP1206'     | ''          | ''            | '20111219'
 '20'         | '1%'      | '1/4W'   | '1206LF'  | 'CHIP'   | 'CS02006F200'(!)        = ''              | ''                 | 'CS02006F200'           |'R1206'| '(SMR1206AW)'                  | '20'      | '1%'    | '1/4W'   | 'DISCRETE' | 'RES CHIP 20 1/4 +-1%(1206)'                       | 'CHIP1206'     | ''          | ''            | '20111219'
 '20'         | '1%'      | '1/4W'   | '1206LF'  | 'EMPTY'  | 'CS02006F200'(!)        = ''              | ''                 | 'CS02006F200'           |'R1206'| '(SMR1206AW)'                  | '20'      | '1%'    | '1/4W'   | 'IO'       | 'RES CHIP 20 1/4 +-1%(1206)'                       | 'CHIP1206'     | ''          | ''            | '20111219'
 '121'        | '1%'      | '1/16W'  | '0402LF'  | 'CHIP'   | 'CS11212FB24'(!)        = 'End of Design' | 'Comp-Approve'     | 'CS11212FB24'           |'R0402'| '(R0402-0201)'                 | '121'     | '1%'    | '1/16W'  | 'DISCRETE' | 'RES CHIP 121 1/16W +-1%(0402)'                    | 'CHIP0402'     | ''          | ''            | '20111219'
 '121'        | '1%'      | '1/16W'  | '0402LF'  | 'EMPTY'  | 'CS11212FB24'(!)        = 'End of Design' | 'Comp-Approve'     | 'CS11212FB24'           |'R0402'| '(R0402-0201)'                 | '121'     | '1%'    | '1/16W'  | 'IO'       | 'RES CHIP 121 1/16W +-1%(0402)'                    | 'CHIP0402'     | ''          | ''            | '20111219'
 '11.5K'      | '1%'      | '1/16W'  | '0402LF'  | 'CHIP'   | 'CS31152FB14'(!)        = 'End of Design' | 'Comp-Approve'     | 'CS31152FB14'           |'R0402'| '(R0402-0201)'                 | '11.5K'   | '1%'    | '1/16W'  | 'DISCRETE' | 'RES CHIP 11.5K 1/16W +-1%( 0402)'                 | 'CHIP0402'     | ''          | ''            | '20111219'
 '11.5K'      | '1%'      | '1/16W'  | '0402LF'  | 'EMPTY'  | 'CS31152FB14'(!)        = 'End of Design' | 'Comp-Approve'     | 'CS31152FB14'           |'R0402'| '(R0402-0201)'                 | '11.5K'   | '1%'    | '1/16W'  | 'IO'       | 'RES CHIP 11.5K 1/16W +-1%( 0402)'                 | 'CHIP0402'     | ''          | ''            | '20111219'
 '0.003'      | '1%'      | '1W'     | '2512LF'  | 'CHIP'   | 'CS+0038F128'(!)        = 'End of Design' | 'Comp-Approve'     | 'CS+0038F128'           |'R2512'| '(SMR2512AW)'                  | '0.003'   | '1%'    | '1W'     | 'DISCRETE' | 'RES CHIP 0.003 1W +-1%(2512)'                     | 'CHIP2512'     | ''          | ''            | '20111219'
 '0.003'      | '1%'      | '1W'     | '2512LF'  | 'EMPTY'  | 'CS+0038F128'(!)        = 'End of Design' | 'Comp-Approve'     | 'CS+0038F128'           |'R2512'| '(SMR2512AW)'                  | '0.003'   | '1%'    | '1W'     | 'IO'       | 'RES CHIP 0.003 1W +-1%(2512)'                     | 'CHIP2512'     | ''          | ''            | '20111219'
 '28K'        | '1%'      | '1/16W'  | '0402LF'  | 'CHIP'   | 'CS32802FB10'(!)        = 'End of Design' | 'Comp-Approve'     | 'CS32802FB10'           |'R0402'| '(R0402-0201)'                 | '28K'     | '1%'    | '1/16W'  | 'DISCRETE' | 'RES CHIP 28K 1/16W +-1%(0402)'                    | 'CHIP0402'     | ''          | ''            | '20111219'
 '28K'        | '1%'      | '1/16W'  | '0402LF'  | 'EMPTY'  | 'CS32802FB10'(!)        = 'End of Design' | 'Comp-Approve'     | 'CS32802FB10'           |'R0402'| '(R0402-0201)'                 | '28K'     | '1%'    | '1/16W'  | 'IO'       | 'RES CHIP 28K 1/16W +-1%(0402)'                    | 'CHIP0402'     | ''          | ''            | '20111219'
 '0.01'       | '1%'      | '1W'     | '2512LF'  | 'CHIP'   | 'CS+0108F128'(!)        = 'End of Design' | 'Comp-Release Qty' | 'CS+0108F128'           |'R2512'| '(SMR2512AW)'                  | '0.01'    | '1%'    | '1W'     | 'DISCRETE' | 'RES CHIP 0.01 1W +-1%(2512)'                      | 'CHIP2512'     | ''          | ''            | '20111219'
 '0.01'       | '1%'      | '1W'     | '2512LF'  | 'EMPTY'  | 'CS+0108F128'(!)        = 'End of Design' | 'Comp-Release Qty' | 'CS+0108F128'           |'R2512'| '(SMR2512AW)'                  | '0.01'    | '1%'    | '1W'     | 'IO'       | 'RES CHIP 0.01 1W +-1%(2512)'                      | 'CHIP2512'     | ''          | ''            | '20111219'
 '100K'       | '1%'      | '1/10W'  | '0603LF'  | 'CHIP'   | 'CS41003F932'(!)        = ''              | ''                 | 'CS41003F932'           |'R0603'| '(SMR0603AW)'                  | '100K'    | '1%'    | '1/10W'  | 'DISCRETE' | 'RESISTOR CHIP 100K 1/10W+-1%(0603)'               | 'CHIP0603'     | ''          | ''            | '20111219'
 '100K'       | '1%'      | '1/10W'  | '0603LF'  | 'EMPTY'  | 'CS41003F932'(!)        = ''              | ''                 | 'CS41003F932'           |'R0603'| '(SMR0603AW)'                  | '100K'    | '1%'    | '1/10W'  | 'IO'       | 'RESISTOR CHIP 100K 1/10W+-1%(0603)'               | 'CHIP0603'     | ''          | ''            | '20111219'
 '475'        | '1%'      | '1/10W'  | '0603LF'  | 'CHIP'   | 'CS14753F933'(!)        = ''              | ''                 | 'CS14753F933'           |'R0603'| '(SMR0603AW)'                  | '475'     | '1%'    | '1/10W'  | 'DISCRETE' | 'RESISTOR CHIP 475 1/10W(+-1%.0603)'               | 'CHIP0603'     | ''          | ''            | '20111223'
 '475'        | '1%'      | '1/10W'  | '0603LF'  | 'EMPTY'  | 'CS14753F933'(!)        = ''              | ''                 | 'CS14753F933'           |'R0603'| '(SMR0603AW)'                  | '475'     | '1%'    | '1/10W'  | 'IO'       | 'RESISTOR CHIP 475 1/10W(+-1%.0603)'               | 'CHIP0603'     | ''          | ''            | '20111223'
 '28K'        | '1%'      | '1/10W'  | '0603LF'  | 'CHIP'   | 'CS32803F932'(!)        = ''              | ''                 | 'CS32803F932'           |'R0603'| '(SMR0603AW)'                  | '28K'     | '1%'    | '1/10W'  | 'DISCRETE' | 'RES CHIP 28K 1/10W+-1%(0603)'                     | 'CHIP0603'     | ''          | ''            | '20111223'
 '28K'        | '1%'      | '1/10W'  | '0603LF'  | 'EMPTY'  | 'CS32803F932'(!)        = ''              | ''                 | 'CS32803F932'           |'R0603'| '(SMR0603AW)'                  | '28K'     | '1%'    | '1/10W'  | 'IO'       | 'RES CHIP 28K 1/10W+-1%(0603)'                     | 'CHIP0603'     | ''          | ''            | '20111223'
 '33'         | '1%'      | '1/10W'  | '0603LF'  | 'CHIP'   | 'CS03303F915'(!)        = ''              | ''                 | 'CS03303F915'           |'R0603'| '(SMR0603AW)'                  | '33'      | '1%'    | '1/10W'  | 'DISCRETE' | 'RES CHIP 33 1/10W +-1%(0603)'                     | 'CHIP0603'     | ''          | ''            | '20111223'
 '33'         | '1%'      | '1/10W'  | '0603LF'  | 'EMPTY'  | 'CS03303F915'(!)        = ''              | ''                 | 'CS03303F915'           |'R0603'| '(SMR0603AW)'                  | '33'      | '1%'    | '1/10W'  | 'IO'       | 'RES CHIP 33 1/10W +-1%(0603)'                     | 'CHIP0603'     | ''          | ''            | '20111223'
 '536'        | '1%'      | '1/16W'  | '0402LF'  | 'CHIP'   | 'CS15362FB13'(!)        = 'End of Design' | 'Comp-Approve'     | 'CS15362FB13'           |'R0402'| '(R0402-0201)'                 | '536'     | '1%'    | '1/16W'  | 'DISCRETE' | 'RES CHIP 536 1/16W.+-1%(0402)'                    | 'CHIP0402'     | ''          | ''            | '20111223'
 '536'        | '1%'      | '1/16W'  | '0402LF'  | 'EMPTY'  | 'CS15362FB13'(!)        = 'End of Design' | 'Comp-Approve'     | 'CS15362FB13'           |'R0402'| '(R0402-0201)'                 | '536'     | '1%'    | '1/16W'  | 'IO'       | 'RES CHIP 536 1/16W.+-1%(0402)'                    | 'CHIP0402'     | ''          | ''            | '20111223'
 '27.4K'      | '1%'      | '1/16W'  | '0402LF'  | 'CHIP'   | 'CS32742FB14'(!)        = 'End of Design' | 'Comp-Approve'     | 'CS32742FB14'           |'R0402'| '(R0402-0201)'                 | '27.4K'   | '1%'    | '1/16W'  | 'DISCRETE' | 'RES CHIP 27.4K 1/16W +-1% (0402)'                 | 'CHIP0402'     | ''          | ''            | '20111223'
 '27.4K'      | '1%'      | '1/16W'  | '0402LF'  | 'EMPTY'  | 'CS32742FB14'(!)        = 'End of Design' | 'Comp-Approve'     | 'CS32742FB14'           |'R0402'| '(R0402-0201)'                 | '27.4K'   | '1%'    | '1/16W'  | 'IO'       | 'RES CHIP 27.4K 1/16W +-1% (0402)'                 | 'CHIP0402'     | ''          | ''            | '20111223'
 '73.2K'      | '1%'      | '1/16W'  | '0402LF'  | 'CHIP'   | 'CS37322FB14'(!)        = 'End of Design' | 'Comp-Approve'     | 'CS37322FB14'           |'R0402'| '(R0402-0201)'                 | '73.2K'   | '1%'    | '1/16W'  | 'DISCRETE' | 'RES CHIP 73.2K 1/16W +-1%(0402)'                  | 'CHIP0402'     | ''          | ''            | '20111223'
 '73.2K'      | '1%'      | '1/16W'  | '0402LF'  | 'EMPTY'  | 'CS37322FB14'(!)        = 'End of Design' | 'Comp-Approve'     | 'CS37322FB14'           |'R0402'| '(R0402-0201)'                 | '73.2K'   | '1%'    | '1/16W'  | 'IO'       | 'RES CHIP 73.2K 1/16W +-1%(0402)'                  | 'CHIP0402'     | ''          | ''            | '20111223'
 '1K'         | '1%'      | '1/8W'   | '0805LF'  | 'CHIP'   | 'CS21004FA10'(!)        = ''              | ''                 | 'CS21004FA10'           |'R0805'| '(SMR0805AW)'                  | '1K'      | '1%'    | '1/8W'   | 'DISCRETE' | 'RES CHIP 1K 1/8W+-1%(0805)L-F'                    | 'CHIP0805'     | ''          | ''            | '20111227'
 '1K'         | '1%'      | '1/8W'   | '0805LF'  | 'EMPTY'  | 'CS21004FA10'(!)        = ''              | ''                 | 'CS21004FA10'           |'R0805'| '(SMR0805AW)'                  | '1K'      | '1%'    | '1/8W'   | 'IO'       | 'RES CHIP 1K 1/8W+-1%(0805)L-F'                    | 'CHIP0805'     | ''          | ''            | '20111227'
 '220'        | '1%'      | '1/10W'  | '0603LF'  | 'CHIP'   | 'CS12203F911'(!)        = 'End of Design' | 'Comp-Approve'     | 'CS12203F911'           |'R0603'| '(SMR0603AW)'                  | '220'     | '1%'    | '1/10W'  | 'DISCRETE' | 'RESISTOR CHIP 220 1/10W.+-1%(0603)'               | 'CHIP0603'     | ''          | ''            | '20111227'
 '220'        | '1%'      | '1/10W'  | '0603LF'  | 'EMPTY'  | 'CS12203F911'(!)        = 'End of Design' | 'Comp-Approve'     | 'CS12203F911'           |'R0603'| '(SMR0603AW)'                  | '220'     | '1%'    | '1/10W'  | 'IO'       | 'RESISTOR CHIP 220 1/10W.+-1%(0603)'               | 'CHIP0603'     | ''          | ''            | '20111227'
 '2.49K'      | '1%'      | '1/10W'  | '0603LF'  | 'CHIP'   | 'CS22493F945'(!)        = ''              | ''                 | 'CS22493F945'           |'R0603'| '(SMR0603AW)'                  | '2.49K'   | '1%'    | '1/10W'  | 'DISCRETE' | 'RES CHIP 2.49K 1/10W +-1%(0603)'                  | 'CHIP0603'     | ''          | ''            | '20111227'
 '2.49K'      | '1%'      | '1/10W'  | '0603LF'  | 'EMPTY'  | 'CS22493F945'(!)        = ''              | ''                 | 'CS22493F945'           |'R0603'| '(SMR0603AW)'                  | '2.49K'   | '1%'    | '1/10W'  | 'IO'       | 'RES CHIP 2.49K 1/10W +-1%(0603)'                  | 'CHIP0603'     | ''          | ''            | '20111227'
 '93.1'       | '1%'      | '1/16W'  | '0402LF'  | 'CHIP'   | 'CS09312FB00'(!)        = 'End of Design' | 'Comp-Approve'     | 'CS09312FB00'           |'R0402'| '(R0402-0201)'                 | '93.1'    | '1%'    | '1/16W'  | 'DISCRETE' | 'RES CHIP 93.1 1/16W +-1%(0402)'                   | 'CHIP0402'     | ''          | ''            | '20111230'
 '93.1'       | '1%'      | '1/16W'  | '0402LF'  | 'EMPTY'  | 'CS09312FB00'(!)        = 'End of Design' | 'Comp-Approve'     | 'CS09312FB00'           |'R0402'| '(R0402-0201)'                 | '93.1'    | '1%'    | '1/16W'  | 'IO'       | 'RES CHIP 93.1 1/16W +-1%(0402)'                   | 'CHIP0402'     | ''          | ''            | '20111230'
 '536'        | '1%'      | '1/8W'   | '0805LF'  | 'CHIP'   | 'CS15364FA00'(!)        = ''              | ''                 | 'CS15364FA00'           |'R0805'| '(SMR0805AW)'                  | '536'     | '1%'    | '1/8W'   | 'DISCRETE' | 'RES CHIP 536 1/8W(+-1%,0805)'                     | 'CHIP0805'     | ''          | ''            | '20111230'
 '536'        | '1%'      | '1/8W'   | '0805LF'  | 'EMPTY'  | 'CS15364FA00'(!)        = ''              | ''                 | 'CS15364FA00'           |'R0805'| '(SMR0805AW)'                  | '536'     | '1%'    | '1/8W'   | 'IO'       | 'RES CHIP 536 1/8W(+-1%,0805)'                     | 'CHIP0805'     | ''          | ''            | '20111230'
 '24K'        | '1%'      | '1/16W'  | '0402LF'  | 'CHIP'   | 'CS32402FB15'(!)        = 'End of Design' | 'Comp-Approve'     | 'CS32402FB15'           |'R0402'| '(R0402-0201)'                 | '24K'     | '1%'    | '1/16W'  | 'DISCRETE' | 'RES CHIP 24K 1/16W +-1%(0402)'                    | 'CHIP0402'     | ''          | ''            | '20111230'
 '24K'        | '1%'      | '1/16W'  | '0402LF'  | 'EMPTY'  | 'CS32402FB15'(!)        = 'End of Design' | 'Comp-Approve'     | 'CS32402FB15'           |'R0402'| '(R0402-0201)'                 | '24K'     | '1%'    | '1/16W'  | 'IO'       | 'RES CHIP 24K 1/16W +-1%(0402)'                    | 'CHIP0402'     | ''          | ''            | '20111230'
 '11.8K'      | '1%'      | '1/10W'  | '0603LF'  | 'CHIP'   | 'CS31183F914'(!)        = ''              | ''                 | 'CS31183F914'           |'R0603'| '(SMR0603AW)'                  | '11.8K'   | '1%'    | '1/10W'  | 'DISCRETE' | 'RES CHIP 11.8K 1/10W +-1%(0603)'                  | 'CHIP0603'     | ''          | ''            | '20111230'
 '11.8K'      | '1%'      | '1/10W'  | '0603LF'  | 'EMPTY'  | 'CS31183F914'(!)        = ''              | ''                 | 'CS31183F914'           |'R0603'| '(SMR0603AW)'                  | '11.8K'   | '1%'    | '1/10W'  | 'IO'       | 'RES CHIP 11.8K 1/10W +-1%(0603)'                  | 'CHIP0603'     | ''          | ''            | '20111230'
 '102K'       | '0.50%'   | '1/10W'  | '0603LF'  | 'CHIP'   | 'CS41023D900'(!)        = ''              | ''                 | 'CS41023D900'           |'R0603'| '(SMR0603AW)'                  | '102K'    | '0.50%' | '1/10W'  | 'DISCRETE' | 'RES CHIP 102K 1/10W +-0.5%(0603)'                 | 'CHIP0603'     | ''          | ''            | '20111230'
 '102K'       | '0.50%'   | '1/10W'  | '0603LF'  | 'EMPTY'  | 'CS41023D900'(!)        = ''              | ''                 | 'CS41023D900'           |'R0603'| '(SMR0603AW)'                  | '102K'    | '0.50%' | '1/10W'  | 'IO'       | 'RES CHIP 102K 1/10W +-0.5%(0603)'                 | 'CHIP0603'     | ''          | ''            | '20111230'
 '442'        | '1%'      | '1/10W'  | '0603LF'  | 'CHIP'   | 'CS14423F939'(!)        = ''              | ''                 | 'CS14423F939'           |'R0603'| '(SMR0603AW)'                  | '442'     | '1%'    | '1/10W'  | 'DISCRETE' | 'RES CHIP 442 1/10W +-1%(0603)EP'                  | 'CHIP0603'     | ''          | ''            | '20111230'
 '442'        | '1%'      | '1/10W'  | '0603LF'  | 'EMPTY'  | 'CS14423F939'(!)        = ''              | ''                 | 'CS14423F939'           |'R0603'| '(SMR0603AW)'                  | '442'     | '1%'    | '1/10W'  | 'IO'       | 'RES CHIP 442 1/10W +-1%(0603)EP'                  | 'CHIP0603'     | ''          | ''            | '20111230'
 '90.9K'      | '1%'      | '1/10W'  | '0603LF'  | 'CHIP'   | 'CS39093F917'(!)        = 'End of Design' | 'Comp-Approve'     | 'CS39093F917'           |'R0603'| '(SMR0603AW)'                  | '90.9K'   | '1%'    | '1/10W'  | 'DISCRETE' | 'RES CHIP 90.9K 1/10W+-1%(0603)'                   | 'CHIP0603'     | ''          | ''            | '20120109'
 '90.9K'      | '1%'      | '1/10W'  | '0603LF'  | 'EMPTY'  | 'CS39093F917'(!)        = 'End of Design' | 'Comp-Approve'     | 'CS39093F917'           |'R0603'| '(SMR0603AW)'                  | '90.9K'   | '1%'    | '1/10W'  | 'IO'       | 'RES CHIP 90.9K 1/10W+-1%(0603)'                   | 'CHIP0603'     | ''          | ''            | '20120109'
 '91K'        | '1%'      | '1/16W'  | '0402LF'  | 'CHIP'   | 'CS39102FB05'(!)        = 'End of Design' | 'Comp-Approve'     | 'CS39102FB05'           |'R0402'| '(R0402-0201)'                 | '91K'     | '1%'    | '1/16W'  | 'DISCRETE' | 'RES CHIP 91K 1/16W +-1%(0402)'                    | 'CHIP0402'     | ''          | ''            | '20120109'
 '91K'        | '1%'      | '1/16W'  | '0402LF'  | 'EMPTY'  | 'CS39102FB05'(!)        = 'End of Design' | 'Comp-Approve'     | 'CS39102FB05'           |'R0402'| '(R0402-0201)'                 | '91K'     | '1%'    | '1/16W'  | 'IO'       | 'RES CHIP 91K 1/16W +-1%(0402)'                    | 'CHIP0402'     | ''          | ''            | '20120109'
 '2.1K'       | '1%'      | '1/16W'  | '0402LF'  | 'CHIP'   | 'CS22102FB12'(!)        = 'End of Design' | 'Comp-Approve'     | 'CS22102FB12'           |'R0402'| '(R0402-0201)'                 | '2.1K'    | '1%'    | '1/16W'  | 'DISCRETE' | 'RES CHIP 2.1K 1/16W +-1%(0402)'                   | 'CHIP0402'     | ''          | ''            | '20120110'
 '2.1K'       | '1%'      | '1/16W'  | '0402LF'  | 'EMPTY'  | 'CS22102FB12'(!)        = 'End of Design' | 'Comp-Approve'     | 'CS22102FB12'           |'R0402'| '(R0402-0201)'                 | '2.1K'    | '1%'    | '1/16W'  | 'IO'       | 'RES CHIP 2.1K 1/16W +-1%(0402)'                   | 'CHIP0402'     | ''          | ''            | '20120110'
 '210'        | '1%'      | '1/16W'  | '0402LF'  | 'CHIP'   | 'CS12102FB11'(!)        = 'End of Design' | 'Comp-Approve'     | 'CS12102FB11'           |'R0402'| '(R0402-0201)'                 | '210'     | '1%'    | '1/16W'  | 'DISCRETE' | 'RES CHIP 210 1/16W 1%(0402)'                      | 'CHIP0402'     | ''          | ''            | '20120113'
 '210'        | '1%'      | '1/16W'  | '0402LF'  | 'EMPTY'  | 'CS12102FB11'(!)        = 'End of Design' | 'Comp-Approve'     | 'CS12102FB11'           |'R0402'| '(R0402-0201)'                 | '210'     | '1%'    | '1/16W'  | 'IO'       | 'RES CHIP 210 1/16W 1%(0402)'                      | 'CHIP0402'     | ''          | ''            | '20120113'
 '44.2K'      | '1%'      | '1/16W'  | '0402LF'  | 'CHIP'   | 'CS34422FB00'(!)        = 'End of Design' | 'Comp-Approve'     | 'CS34422FB00'           |'R0402'| '(R0402-0201)'                 | '44.2K'   | '1%'    | '1/16W'  | 'DISCRETE' | 'RES CHIP 44.2K 1/16W +-1%(0402)'                  | 'CHIP0402'     | ''          | ''            | '20120114'
 '44.2K'      | '1%'      | '1/16W'  | '0402LF'  | 'EMPTY'  | 'CS34422FB00'(!)        = 'End of Design' | 'Comp-Approve'     | 'CS34422FB00'           |'R0402'| '(R0402-0201)'                 | '44.2K'   | '1%'    | '1/16W'  | 'IO'       | 'RES CHIP 44.2K 1/16W +-1%(0402)'                  | 'CHIP0402'     | ''          | ''            | '20120114'
 '174K'       | '1%'      | '1/16W'  | '0402LF'  | 'CHIP'   | 'CS41742FB13'(!)        = 'End of Design' | 'Comp-Approve'     | 'CS41742FB13'           |'R0402'| '(R0402-0201)'                 | '174K'    | '1%'    | '1/16W'  | 'DISCRETE' | 'RES CHIP 174K 1/16W +-1%(0402)'                   | 'CHIP0402'     | ''          | ''            | '20120114'
 '174K'       | '1%'      | '1/16W'  | '0402LF'  | 'EMPTY'  | 'CS41742FB13'(!)        = 'End of Design' | 'Comp-Approve'     | 'CS41742FB13'           |'R0402'| '(R0402-0201)'                 | '174K'    | '1%'    | '1/16W'  | 'IO'       | 'RES CHIP 174K 1/16W +-1%(0402)'                   | 'CHIP0402'     | ''          | ''            | '20120114'
 '1'          | '5%'      | '1/16W'  | '0402LF'  | 'CHIP'   | 'CS-1002JB17'(!)        = 'End of Design' | 'Comp-Approve'     | 'CS-1002JB17'           |'R0402'| '(R0402-0201)'                 | '1'       | '5%'    | '1/16W'  | 'DISCRETE' | 'RES CHIP 1 1/16W +-5%(0402)'                      | 'CHIP0402'     | ''          | ''            | '20120114'
 '1'          | '5%'      | '1/16W'  | '0402LF'  | 'EMPTY'  | 'CS-1002JB17'(!)        = 'End of Design' | 'Comp-Approve'     | 'CS-1002JB17'           |'R0402'| '(R0402-0201)'                 | '1'       | '5%'    | '1/16W'  | 'IO'       | 'RES CHIP 1 1/16W +-5%(0402)'                      | 'CHIP0402'     | ''          | ''            | '20120114'
 '56.2'       | '1%'      | '1/4W'   | '1206LF'  | 'CHIP'   | 'CS05626F216'(!)        = ''              | ''                 | 'CS05626F216'           |'R1206'| '(SMR1206AW)'                  | '56.2'    | '1%'    | '1/4W'   | 'DISCRETE' | 'RESISTOR CHIP 56.2 1/4W +-1%(1206)EP'             | 'CHIP1206'     | ''          | ''            | '20120114'
 '56.2'       | '1%'      | '1/4W'   | '1206LF'  | 'EMPTY'  | 'CS05626F216'(!)        = ''              | ''                 | 'CS05626F216'           |'R1206'| '(SMR1206AW)'                  | '56.2'    | '1%'    | '1/4W'   | 'IO'       | 'RESISTOR CHIP 56.2 1/4W +-1%(1206)EP'             | 'CHIP1206'     | ''          | ''            | '20120114'
 '16.9K'      | '1%'      | '1/16W'  | '0402LF'  | 'CHIP'   | 'CS31692FB11'(!)        = 'End of Design' | 'Comp-Approve'     | 'CS31692FB11'           |'R0402'| '(R0402-0201)'                 | '16.9K'   | '1%'    | '1/16W'  | 'DISCRETE' | 'RES CHIP 16.9K 1/16W +-1% (0402)'                 | 'CHIP0402'     | ''          | ''            | '20120119'
 '16.9K'      | '1%'      | '1/16W'  | '0402LF'  | 'EMPTY'  | 'CS31692FB11'(!)        = 'End of Design' | 'Comp-Approve'     | 'CS31692FB11'           |'R0402'| '(R0402-0201)'                 | '16.9K'   | '1%'    | '1/16W'  | 'IO'       | 'RES CHIP 16.9K 1/16W +-1% (0402)'                 | 'CHIP0402'     | ''          | ''            | '20120119'
 '191K'       | '1%'      | '1/16W'  | '0402LF'  | 'CHIP'   | 'CS41912FB17'(!)        = 'End of Design' | 'Comp-Approve'     | 'CS41912FB17'           |'R0402'| '(R0402-0201)'                 | '191K'    | '1%'    | '1/16W'  | 'DISCRETE' | 'RES CHIP 191K 1/16W +-1%(0402)'                   | 'CHIP0402'     | ''          | ''            | '20120119'
 '191K'       | '1%'      | '1/16W'  | '0402LF'  | 'EMPTY'  | 'CS41912FB17'(!)        = 'End of Design' | 'Comp-Approve'     | 'CS41912FB17'           |'R0402'| '(R0402-0201)'                 | '191K'    | '1%'    | '1/16W'  | 'IO'       | 'RES CHIP 191K 1/16W +-1%(0402)'                   | 'CHIP0402'     | ''          | ''            | '20120119'
 '154K'       | '1%'      | '1/16W'  | '0402LF'  | 'CHIP'   | 'CS41542FB16'(!)        = 'End of Design' | 'Comp-Approve'     | 'CS41542FB16'           |'R0402'| '(R0402-0201)'                 | '154K'    | '1%'    | '1/16W'  | 'DISCRETE' | 'RES CHIP 154K 1/16W +1%(0402)'                    | 'CHIP0402'     | ''          | ''            | '20120119'
 '154K'       | '1%'      | '1/16W'  | '0402LF'  | 'EMPTY'  | 'CS41542FB16'(!)        = 'End of Design' | 'Comp-Approve'     | 'CS41542FB16'           |'R0402'| '(R0402-0201)'                 | '154K'    | '1%'    | '1/16W'  | 'IO'       | 'RES CHIP 154K 1/16W +1%(0402)'                    | 'CHIP0402'     | ''          | ''            | '20120119'
 '4.99'       | '1%'      | '1/10W'  | '0603LF'  | 'CHIP'   | 'CS-4993F913'(!)        = ''              | ''                 | 'CS-4993F913'           |'R0603'| '(SMR0603AW)'                  | '4.99'    | '1%'    | '1/10W'  | 'DISCRETE' | 'RES CHIP 4.99 1/10W +-1%(0603)'                   | 'CHIP0603'     | ''          | ''            | '20120119'
 '4.99'       | '1%'      | '1/10W'  | '0603LF'  | 'EMPTY'  | 'CS-4993F913'(!)        = ''              | ''                 | 'CS-4993F913'           |'R0603'| '(SMR0603AW)'                  | '4.99'    | '1%'    | '1/10W'  | 'IO'       | 'RES CHIP 4.99 1/10W +-1%(0603)'                   | 'CHIP0603'     | ''          | ''            | '20120119'
 '249K'       | '1%'      | '1/16W'  | '0402LF'  | 'CHIP'   | 'CS42492FB00'(!)        = 'End of Design' | 'Comp-Approve'     | 'CS42492FB00'           |'R0402'| '(R0402-0201)'                 | '249K'    | '1%'    | '1/16W'  | 'DISCRETE' | 'RES CHIP 249K 1/16W +-1%(0402)'                   | 'CHIP0402'     | ''          | ''            | '20120120'
 '249K'       | '1%'      | '1/16W'  | '0402LF'  | 'EMPTY'  | 'CS42492FB00'(!)        = 'End of Design' | 'Comp-Approve'     | 'CS42492FB00'           |'R0402'| '(R0402-0201)'                 | '249K'    | '1%'    | '1/16W'  | 'IO'       | 'RES CHIP 249K 1/16W +-1%(0402)'                   | 'CHIP0402'     | ''          | ''            | '20120120'
 '19.1K'      | '1%'      | '1/16W'  | '0402LF'  | 'CHIP'   | 'CS31912FB15'(!)        = 'End of Design' | 'Comp-Approve'     | 'CS31912FB15'           |'R0402'| '(R0402-0201)'                 | '19.1K'   | '1%'    | '1/16W'  | 'DISCRETE' | 'RES CHIP 19.1K 1/16W +-1%(0402)'                  | 'CHIP0402'     | ''          | ''            | '20120120'
 '19.1K'      | '1%'      | '1/16W'  | '0402LF'  | 'EMPTY'  | 'CS31912FB15'(!)        = 'End of Design' | 'Comp-Approve'     | 'CS31912FB15'           |'R0402'| '(R0402-0201)'                 | '19.1K'   | '1%'    | '1/16W'  | 'IO'       | 'RES CHIP 19.1K 1/16W +-1%(0402)'                  | 'CHIP0402'     | ''          | ''            | '20120120'
 '16.5K'      | '1%'      | '1/16W'  | '0402LF'  | 'CHIP'   | 'CS31652FB12'(!)        = 'End of Design' | 'Comp-Approve'     | 'CS31652FB12'           |'R0402'| '(R0402-0201)'                 | '16.5K'   | '1%'    | '1/16W'  | 'DISCRETE' | 'RES CHIP 16.5K 1/16W +-1% (0402)'                 | 'CHIP0402'     | ''          | ''            | '20120120'
 '16.5K'      | '1%'      | '1/16W'  | '0402LF'  | 'EMPTY'  | 'CS31652FB12'(!)        = 'End of Design' | 'Comp-Approve'     | 'CS31652FB12'           |'R0402'| '(R0402-0201)'                 | '16.5K'   | '1%'    | '1/16W'  | 'IO'       | 'RES CHIP 16.5K 1/16W +-1% (0402)'                 | 'CHIP0402'     | ''          | ''            | '20120120'
 '26.1K'      | '1%'      | '1/16W'  | '0402LF'  | 'CHIP'   | 'CS32612FB09'(!)        = 'End of Design' | 'Comp-Approve'     | 'CS32612FB09'           |'R0402'| '(R0402-0201)'                 | '26.1K'   | '1%'    | '1/16W'  | 'DISCRETE' | 'RES CHIP 26.1K 1/16W +-1%(0402)'                  | 'CHIP0402'     | ''          | ''            | '20120120'
 '26.1K'      | '1%'      | '1/16W'  | '0402LF'  | 'EMPTY'  | 'CS32612FB09'(!)        = 'End of Design' | 'Comp-Approve'     | 'CS32612FB09'           |'R0402'| '(R0402-0201)'                 | '26.1K'   | '1%'    | '1/16W'  | 'IO'       | 'RES CHIP 26.1K 1/16W +-1%(0402)'                  | 'CHIP0402'     | ''          | ''            | '20120120'
 '249'        | '1%'      | '1/16W'  | '0402LF'  | 'CHIP'   | 'CS12492FB12'(!)        = 'End of Design' | 'Comp-Approve'     | 'CS12492FB12'           |'R0402'| '(R0402-0201)'                 | '249'     | '1%'    | '1/16W'  | 'DISCRETE' | 'RES CHIP 249 1/16W +-1%(0402)'                    | 'CHIP0402'     | ''          | ''            | '20120120'
 '249'        | '1%'      | '1/16W'  | '0402LF'  | 'EMPTY'  | 'CS12492FB12'(!)        = 'End of Design' | 'Comp-Approve'     | 'CS12492FB12'           |'R0402'| '(R0402-0201)'                 | '249'     | '1%'    | '1/16W'  | 'IO'       | 'RES CHIP 249 1/16W +-1%(0402)'                    | 'CHIP0402'     | ''          | ''            | '20120120'
 '205'        | '1%'      | '1/16W'  | '0402LF'  | 'CHIP'   | 'CS12052FB10'(!)        = 'End of Design' | 'Comp-Release Qty' | 'CS12052FB10'           |'R0402'| '(R0402-0201)'                 | '205'     | '1%'    | '1/16W'  | 'DISCRETE' | 'RES CHIP 205(1/16W.+-1%.0402)'                    | 'CHIP0402'     | ''          | ''            | '20120120'
 '205'        | '1%'      | '1/16W'  | '0402LF'  | 'EMPTY'  | 'CS12052FB10'(!)        = 'End of Design' | 'Comp-Release Qty' | 'CS12052FB10'           |'R0402'| '(R0402-0201)'                 | '205'     | '1%'    | '1/16W'  | 'IO'       | 'RES CHIP 205(1/16W.+-1%.0402)'                    | 'CHIP0402'     | ''          | ''            | '20120120'
 '200K'       | '5%'      | '1/16W'  | '0402LF'  | 'CHIP'   | 'CS42002JB14'(!)        = 'End of Design' | 'Comp-Approve'     | 'CS42002JB14'           |'R0402'| '(R0402-0201)'                 | '200K'    | '5%'    | '1/16W'  | 'DISCRETE' | 'RES CHIP 200K 1/16W +-5%(0402)'                   | 'CHIP0402'     | ''          | ''            | '20120131'
 '200K'       | '5%'      | '1/16W'  | '0402LF'  | 'EMPTY'  | 'CS42002JB14'(!)        = 'End of Design' | 'Comp-Approve'     | 'CS42002JB14'           |'R0402'| '(R0402-0201)'                 | '200K'    | '5%'    | '1/16W'  | 'IO'       | 'RES CHIP 200K 1/16W +-5%(0402)'                   | 'CHIP0402'     | ''          | ''            | '20120131'
 '9.09K'      | '1%'      | '1/16W'  | '0402LF'  | 'CHIP'   | 'CS29092FB27'(!)        = 'End of Design' | 'Comp-Approve'     | 'CS29092FB27'           |'R0402'| '(R0402-0201)'                 | '9.09K'   | '1%'    | '1/16W'  | 'DISCRETE' | 'RES CHIP 9.09K 1/16W +-1%(0402)'                  | 'CHIP0402'     | ''          | ''            | '20120207'
 '9.09K'      | '1%'      | '1/16W'  | '0402LF'  | 'EMPTY'  | 'CS29092FB27'(!)        = 'End of Design' | 'Comp-Approve'     | 'CS29092FB27'           |'R0402'| '(R0402-0201)'                 | '9.09K'   | '1%'    | '1/16W'  | 'IO'       | 'RES CHIP 9.09K 1/16W +-1%(0402)'                  | 'CHIP0402'     | ''          | ''            | '20120207'
 '1.21M'      | '1%'      | '1/16W'  | '0402LF'  | 'CHIP'   | 'CS51212FB00'(!)        = ''              | ''                 | 'CS51212FB00'           |'R0402'| '(R0402-0201)'                 | '1.21M'   | '1%'    | '1/16W'  | 'DISCRETE' | 'RES CHIP 1.21M 1/16W +-1%(0402)'                  | 'CHIP0402'     | ''          | ''            | '20120202'
 '1.21M'      | '1%'      | '1/16W'  | '0402LF'  | 'EMPTY'  | 'CS51212FB00'(!)        = ''              | ''                 | 'CS51212FB00'           |'R0402'| '(R0402-0201)'                 | '1.21M '  | '1%'    | '1/16W'  | 'IO'       | 'RES CHIP 1.21M 1/16W +-1%(0402)'                  | 'CHIP0402'     | ''          | ''            | '20120202'
 '301K'       | '1%'      | '1/16W'  | '0402LF'  | 'CHIP'   | 'CS43012FB10'(!)        = 'End of Design' | 'Comp-Approve'     | 'CS43012FB10'           |'R0402'| '(R0402-0201)'                 | '301K  '  | '1%'    | '1/16W'  | 'DISCRETE' | 'RES CHIP 301K 1/16W +-1%( 0402)'                  | 'CHIP0402'     | ''          | ''            | '20120202'
 '301K'       | '1%'      | '1/16W'  | '0402LF'  | 'EMPTY'  | 'CS43012FB10'(!)        = 'End of Design' | 'Comp-Approve'     | 'CS43012FB10'           |'R0402'| '(R0402-0201)'                 | '301K'    | '1%'    | '1/16W'  | 'IO'       | 'RES CHIP 301K 1/16W +-1%( 0402)'                  | 'CHIP0402'     | ''          | ''            | '20120202'
 '43.2'       | '1%'      | '1/16W'  | '0402LF'  | 'CHIP'   | 'CS04322FB11'(!)        = 'End of Design' | 'Comp-Approve'     | 'CS04322FB11'           |'R0402'| '(R0402-0201)'                 | '43.2'    | '1%'    | '1/16W'  | 'DISCRETE' | 'RES CHIP 43.2 1/16W +-1%(0402)'                   | 'CHIP0402'     | ''          | ''            | '20120210'
 '43.2'       | '1%'      | '1/16W'  | '0402LF'  | 'EMPTY'  | 'CS04322FB11'(!)        = 'End of Design' | 'Comp-Approve'     | 'CS04322FB11'           |'R0402'| '(R0402-0201)'                 | '43.2'    | '1%'    | '1/16W'  | 'IO'       | 'RES CHIP 43.2 1/16W +-1%(0402)'                   | 'CHIP0402'     | ''          | ''            | '20120210'
 '14K'        | '1%'      | '1/16W'  | '0402LF'  | 'CHIP'   | 'CS31402FB04'(!)        = ''              | ''                 | 'CS31402FB04'           |'R0402'| '(R0402-0201)'                 | '14K'     | '1%'    | '1/16W'  | 'DISCRETE' | 'RES CHIP 14K +-1% 1/16W(0402)'                    | 'CHIP0402'     | ''          | ''            | '20120210'
 '14K'        | '1%'      | '1/16W'  | '0402LF'  | 'EMPTY'  | 'CS31402FB04'(!)        = ''              | ''                 | 'CS31402FB04'           |'R0402'| '(R0402-0201)'                 | '14K'     | '1%'    | '1/16W'  | 'IO'       | 'RES CHIP 14K +-1% 1/16W(0402)'                    | 'CHIP0402'     | ''          | ''            | '20120210'
 '0.00025'    | '1%'      | '4W'     | '2725LF'  | 'CHIP'   | 'CS0000FFT00'(!)        = 'End of Design' | 'Comp-Approve'     | 'CS0000FFT00'           |'R2725'| '(SMR2725AW)'                  | '0.00025' | '1%'    | '4W'     | 'DISCRETE' | 'RES CHIP 0.00025 4W +-1%(2725)H0.99'              | 'CHIP2725'     | ''          | ''            | '20120216'
 '0.00025'    | '1%'      | '4W'     | '2725LF'  | 'EMPTY'  | 'CS0000FFT00'(!)        = 'End of Design' | 'Comp-Approve'     | 'CS0000FFT00'           |'R2725'| '(SMR2725AW)'                  | '0.00025' | '1%'    | '4W'     | 'IO'       | 'RES CHIP 0.00025 4W +-1%(2725)H0.99'              | 'CHIP2725'     | ''          | ''            | '20120216'
 '300K'       | '1%'      | '1/16W'  | '0402LF'  | 'CHIP'   | 'CS43002FB15'(!)        = 'End of Design' | 'Comp-Approve'     | 'CS43002FB15'           |'R0402'| '(R0402-0201)'                 | '300K'    | '1%'    | '1/16W'  | 'DISCRETE' | 'RES CHIP 300K +-1% 1/16W(0402)'                   | 'CHIP0402'     | ''          | ''            | '20120215'
 '300K'       | '1%'      | '1/16W'  | '0402LF'  | 'EMPTY'  | 'CS43002FB15'(!)        = 'End of Design' | 'Comp-Approve'     | 'CS43002FB15'           |'R0402'| '(R0402-0201)'                 | '300K'    | '1%'    | '1/16W'  | 'IO'       | 'RES CHIP 300K +-1% 1/16W(0402)'                   | 'CHIP0402'     | ''          | ''            | '20120215'
 '169K'       | '1%'      | '1/16W'  | '0402LF'  | 'CHIP'   | 'CS41692FB12'(!)        = 'End of Design' | 'Comp-Approve'     | 'CS41692FB12'           |'R0402'| '(R0402-0201)'                 | '169K'    | '1%'    | '1/16W'  | 'DISCRETE' | 'RES CHIP 169K +-1% 1/16W(0402)'                   | 'CHIP0402'     | ''          | ''            | '20120215'
 '169K'       | '1%'      | '1/16W'  | '0402LF'  | 'EMPTY'  | 'CS41692FB12'(!)        = 'End of Design' | 'Comp-Approve'     | 'CS41692FB12'           |'R0402'| '(R0402-0201)'                 | '169K'    | '1%'    | '1/16W'  | 'IO'       | 'RES CHIP 169K +-1% 1/16W(0402)'                   | 'CHIP0402'     | ''          | ''            | '20120215'
 '3.3'        | '1%'      | '1/10W'  | '0603LF'  | 'CHIP'   | 'CS-3303F918'(!)        = 'End of Design' | 'Comp-Approve'     | 'CS-3303F918'           |'R0603'| '(SMR0603AW)'                  | '3.3'     | '1%'    | '1/10W'  | 'DISCRETE' | 'RES CHIP 3.3 1/10W +-1% (0603) EP'                | 'CHIP0603'     | ''          | ''            | '20120215'
 '3.3'        | '1%'      | '1/10W'  | '0603LF'  | 'EMPTY'  | 'CS-3303F918'(!)        = 'End of Design' | 'Comp-Approve'     | 'CS-3303F918'           |'R0603'| '(SMR0603AW)'                  | '3.3'     | '1%'    | '1/10W'  | 'IO'       | 'RES CHIP 3.3 1/10W +-1% (0603) EP'                | 'CHIP0603'     | ''          | ''            | '20120215'
 '0.009'      | '1%'      | '1W'     | '2512LF'  | 'CHIP'   | 'CS00008FR00'(!)        = ''              | ''                 | 'CS00008FR00'           |'R2512XD'| '(SMR2512AW)'                  | '0.009'   | '1%'    | '1W'     | 'DISCRETE' | 'RES CHIP 0.009 1W +-1%(2512)H0.787'               | 'CHIP2512'     | ''          | ''            | '20120216'
 '0.009'      | '1%'      | '1W'     | '2512LF'  | 'EMPTY'  | 'CS00008FR00'(!)        = ''              | ''                 | 'CS00008FR00'           |'R2512XD'| '(SMR2512AW)'                  | '0.009'   | '1%'    | '1W'     | 'IO'       | 'RES CHIP 0.009 1W +-1%(2512)H0.787'               | 'CHIP2512'     | ''          | ''            | '20120216'
 '90.9'       | '1%'      | '1/16W'  | '0402LF'  | 'CHIP'   | 'CS09092FB15'(!)        = 'End of Design' | 'Comp-Approve'     | 'CS09092FB15'           |'R0402'| '(R0402-0201)'                 | '90.9'    | '1%'    | '1/16W'  | 'DISCRETE' | 'RES CHIP 90.9 1/16W +-1%(0402)'                   | 'CHIP0402'     | ''          | ''            | '20120221'
 '90.9'       | '1%'      | '1/16W'  | '0402LF'  | 'EMPTY'  | 'CS09092FB15'(!)        = 'End of Design' | 'Comp-Approve'     | 'CS09092FB15'           |'R0402'| '(R0402-0201)'                 | '90.9'    | '1%'    | '1/16W'  | 'IO'       | 'RES CHIP 90.9 1/16W +-1%(0402)'                   | 'CHIP0402'     | ''          | ''            | '20120221'
 '0.008'      | '1%'      | '2W'     | '2512LF'  | 'CHIP'   | 'CS+008AFR00'(!)        = ''              | ''                 | 'CS+008AFR00'           |'R2512'| '(SMR2512AW)'                  | '0.008'   | '1%'    | '2W'     | 'DISCRETE' | 'RES CHIP 0.008 2W +-1%(2512)'                     | 'CHIP2512'     | ''          | ''            | '20120222'
 '0.008'      | '1%'      | '2W'     | '2512LF'  | 'EMPTY'  | 'CS+008AFR00'(!)        = ''              | ''                 | 'CS+008AFR00'           |'R2512'| '(SMR2512AW)'                  | '0.008'   | '1%'    | '2W'     | 'IO'       | 'RES CHIP 0.008 2W +-1%(2512)'                     | 'CHIP2512'     | ''          | ''            | '20120222'
 '0.008'      | '1%'      | '2W'     | '2512LF'  | 'CHIP'   | 'CS+008AFR01'(!)        = ''              | ''                 | 'CS+008AFR01'           |'R2512'| '(SMR2512AW)'                  | '0.008'   | '1%'    | '2W'     | 'DISCRETE' | 'RES CHIP 0.008 2W +-1%(2512)HF'                   | 'CHIP2512'     | ''          | ''            | '20120222'
 '0.008'      | '1%'      | '2W'     | '2512LF'  | 'EMPTY'  | 'CS+008AFR01'(!)        = ''              | ''                 | 'CS+008AFR01'           |'R2512'| '(SMR2512AW)'                  | '0.008'   | '1%'    | '2W'     | 'IO'       | 'RES CHIP 0.008 2W +-1%(2512)HF'                   | 'CHIP2512'     | ''          | ''            | '20120222'
 '107K'       | '1%'      | '1/16W'  | '0402LF'  | 'CHIP'   | 'CS41072FB11'(!)        = 'End of Design' | 'Comp-Approve'     | 'CS41072FB11'           |'R0402'| '(R0402-0201)'                 | '107K'    | '1%'    | '1/16W'  | 'DISCRETE' | 'RES CHIP 107K 1/16W +-1%(0402)'                   | 'CHIP0402'     | ''          | ''            | '20120222'
 '107K'       | '1%'      | '1/16W'  | '0402LF'  | 'EMPTY'  | 'CS41072FB11'(!)        = 'End of Design' | 'Comp-Approve'     | 'CS41072FB11'           |'R0402'| '(R0402-0201)'                 | '107K'    | '1%'    | '1/16W'  | 'IO'       | 'RES CHIP 107K 1/16W +-1%(0402)'                   | 'CHIP0402'     | ''          | ''            | '20120222'
 '13'         | '1%'      | '1/16W'  | '0402LF'  | 'CHIP'   | 'CS01302FB05'(!)        = 'End of Design' | 'Comp-Approve'     | 'CS01302FB05'           |'R0402'| '(R0402-0201)'                 | '13'      | '1%'    | '1/16W'  | 'DISCRETE' | 'RES CHIP 13 1/16W +-1%(0402)'                     | 'CHIP0402'     | ''          | ''            | '20120228'
 '13'         | '1%'      | '1/16W'  | '0402LF'  | 'EMPTY'  | 'CS01302FB05'(!)        = 'End of Design' | 'Comp-Approve'     | 'CS01302FB05'           |'R0402'| '(R0402-0201)'                 | '13'      | '1%'    | '1/16W'  | 'IO'       | 'RES CHIP 13 1/16W +-1%(0402)'                     | 'CHIP0402'     | ''          | ''            | '20120228'
 '6.8'        | '1%'      | '1/16W'  | '0402LF'  | 'CHIP'   | 'CS-6802FB00'(!)        = 'End of Design' | 'Comp-Approve'     | 'CS-6802FB00'           |'R0402'| '(R0402-0201)'                 | '6.8'     | '1%'    | '1/16W'  | 'DISCRETE' | 'RES CHIP 6.8 1/16W +-1%(0402)'                    | 'CHIP0402'     | ''          | ''            | '20120228'
 '6.8'        | '1%'      | '1/16W'  | '0402LF'  | 'EMPTY'  | 'CS-6802FB00'(!)        = 'End of Design' | 'Comp-Approve'     | 'CS-6802FB00'           |'R0402'| '(R0402-0201)'                 | '6.8'     | '1%'    | '1/16W'  | 'IO'       | 'RES CHIP 6.8 1/16W +-1%(0402)'                    | 'CHIP0402'     | ''          | ''            | '20120228'
 '3.83K'      | '1%'      | '1/16W'  | '0402LF'  | 'CHIP'   | 'CS23832FB01'(!)        = 'End of Design' | 'Comp-Approve'     | 'CS23832FB01'           |'R0402'| '(R0402-0201)'                 | '3.83K'   | '1%'    | '1/16W'  | 'DISCRETE' | 'RES CHIP 3.83K 1/16W +-1%(0402)'                  | 'CHIP0402'     | ''          | ''            | '20120304'
 '3.83K'      | '1%'      | '1/16W'  | '0402LF'  | 'EMPTY'  | 'CS23832FB01'(!)        = 'End of Design' | 'Comp-Approve'     | 'CS23832FB01'           |'R0402'| '(R0402-0201)'                 | '3.83K'   | '1%'    | '1/16W'  | 'IO'       | 'RES CHIP 3.83K 1/16W +-1%(0402)'                  | 'CHIP0402'     | ''          | ''            | '20120304'
 '95.3K'      | '1%'      | '1/16W'  | '0402LF'  | 'CHIP'   | 'CS39532FB03'(!)        = 'End of Design' | 'Comp-Approve'     | 'CS39532FB03'           |'R0402'| '(R0402-0201)'                 | '95.3K'   | '1%'    | '1/16W'  | 'DISCRETE' | 'RESISTOR CHIP 95.3K,1/16W,+-1%(0402)'             | 'CHIP0402'     | ''          | ''            | '20120304'
 '95.3K'      | '1%'      | '1/16W'  | '0402LF'  | 'EMPTY'  | 'CS39532FB03'(!)        = 'End of Design' | 'Comp-Approve'     | 'CS39532FB03'           |'R0402'| '(R0402-0201)'                 | '95.3K'   | '1%'    | '1/16W'  | 'IO'       | 'RESISTOR CHIP 95.3K,1/16W,+-1%(0402)'             | 'CHIP0402'     | ''          | ''            | '20120304'
 '453K'       | '1%'      | '1/16W'  | '0402LF'  | 'CHIP'   | 'CS44532FB10'(!)        = 'End of Design' | 'Comp-Approve'     | 'CS44532FB10'           |'R0402'| '(R0402-0201)'                 | '453K'    | '1%'    | '1/16W'  | 'DISCRETE' | 'RES CHIP 453K 1/16W +-1%(0402)'                   | 'CHIP0402'     | ''          | ''            | '20120304'
 '453K'       | '1%'      | '1/16W'  | '0402LF'  | 'EMPTY'  | 'CS44532FB10'(!)        = 'End of Design' | 'Comp-Approve'     | 'CS44532FB10'           |'R0402'| '(R0402-0201)'                 | '453K'    | '1%'    | '1/16W'  | 'IO'       | 'RES CHIP 453K 1/16W +-1%(0402)'                   | 'CHIP0402'     | ''          | ''            | '20120304'
 '7.68K'      | '1%'      | '1/16W'  | '0402LF'  | 'CHIP'   | 'CS27682FB11'(!)        = 'End of Design' | 'Comp-Approve'     | 'CS27682FB11'           |'R0402'| '(R0402-0201)'                 | '7.68K'   | '1%'    | '1/16W'  | 'DISCRETE' | 'RES CHIP 7.68K 1/16W +-1%(0402)'                  | 'CHIP0402'     | ''          | ''            | '20120304'
 '7.68K'      | '1%'      | '1/16W'  | '0402LF'  | 'EMPTY'  | 'CS27682FB11'(!)        = 'End of Design' | 'Comp-Approve'     | 'CS27682FB11'           |'R0402'| '(R0402-0201)'                 | '7.68K'   | '1%'    | '1/16W'  | 'IO'       | 'RES CHIP 7.68K 1/16W +-1%(0402)'                  | 'CHIP0402'     | ''          | ''            | '20120304'
 '0.0005'     | '1%'      | '2W'     | '2512LF'  | 'CHIP'   | 'CS0000AFR00'(!)        = ''              | ''                 | 'CS0000AFR00'           |'R2512XD'| '(SMR2512AW)'                  | '0.0005'  | '1%'    | '2W'     | 'DISCRETE' | 'RES CHIP 0.0005 2W +-1%(2512)'                    | 'CHIP2512'     | ''          | ''            | '20120627'
 '0.0005'     | '1%'      | '2W'     | '2512LF'  | 'EMPTY'  | 'CS0000AFR00'(!)        = ''              | ''                 | 'CS0000AFR00'           |'R2512XD'| '(SMR2512AW)'                  | '0.0005'  | '1%'    | '2W'     | 'IO'       | 'RES CHIP 0.0005 2W +-1%(2512)'                    | 'CHIP2512'     | ''          | ''            | '20120627'
 '240'        | '1%'      | '1/10W'  | '0603LF'  | 'CHIP'   | 'CS12403F918'(!)        = ''              | ''                 | 'CS12403F918'           |'R0603'| '(SMR0603AW)'                  | '240'     | '1%'    | '1/10W'  | 'DISCRETE' | 'RES CHIP 240 1/10W +-1%(0603)'                    | 'CHIP0603'     | ''          | ''            | '20120310'
 '240'        | '1%'      | '1/10W'  | '0603LF'  | 'EMPTY'  | 'CS12403F918'(!)        = ''              | ''                 | 'CS12403F918'           |'R0603'| '(SMR0603AW)'                  | '240'     | '1%'    | '1/10W'  | 'IO'       | 'RES CHIP 240 1/10W +-1%(0603)'                    | 'CHIP0603'     | ''          | ''            | '20120310'
 '6.34K'      | '1%'      | '1/16W'  | '0402LF'  | 'CHIP'   | 'CS26342FB27'(!)        = 'End of Design' | 'Comp-Approve'     | 'CS26342FB27'           |'R0402'| '(R0402-0201)'                 | '6.34K'   | '1%'    | '1/16W'  | 'DISCRETE' | 'RES CHIP 6.34K 1/16W +-1%(0402)'                  | 'CHIP0402'     | ''          | ''            | '20120314'
 '6.34K'      | '1%'      | '1/16W'  | '0402LF'  | 'EMPTY'  | 'CS26342FB27'(!)        = 'End of Design' | 'Comp-Approve'     | 'CS26342FB27'           |'R0402'| '(R0402-0201)'                 | '6.34K'   | '1%'    | '1/16W'  | 'IO'       | 'RES CHIP 6.34K 1/16W +-1%(0402)'                  | 'CHIP0402'     | ''          | ''            | '20120314'
 '9.76K'      | '1%'      | '1/16W'  | '0402LF'  | 'CHIP'   | 'CS29762FB00'(!)        = 'End of Design' | 'Comp-Approve'     | 'CS29762FB00'           |'R0402'| '(R0402-0201)'                 | '9.76K'   | '1%'    | '1/16W'  | 'DISCRETE' | 'RES CHIP 9.76K 1/16W +-1%(0402)'                  | 'CHIP0402'     | ''          | ''            | '20120314'
 '9.76K'      | '1%'      | '1/16W'  | '0402LF'  | 'EMPTY'  | 'CS29762FB00'(!)        = 'End of Design' | 'Comp-Approve'     | 'CS29762FB00'           |'R0402'| '(R0402-0201)'                 | '9.76K'   | '1%'    | '1/16W'  | 'IO'       | 'RES CHIP 9.76K 1/16W +-1%(0402)'                  | 'CHIP0402'     | ''          | ''            | '20120314'
 '39K'        | '1%'      | '1/16W'  | '0402LF'  | 'CHIP'   | 'CS33902FB16'(!)        = 'End of Design' | 'Comp-Approve'     | 'CS33902FB16'           |'R0402'| '(R0402-0201)'                 | '39K'     | '1%'    | '1/16W'  | 'DISCRETE' | 'RES CHIP 39K 1/16W +-1%(0402)'                    | 'CHIP0402'     | ''          | ''            | '20120314'
 '39K'        | '1%'      | '1/16W'  | '0402LF'  | 'EMPTY'  | 'CS33902FB16'(!)        = 'End of Design' | 'Comp-Approve'     | 'CS33902FB16'           |'R0402'| '(R0402-0201)'                 | '39K'     | '1%'    | '1/16W'  | 'IO'       | 'RES CHIP 39K 1/16W +-1%(0402)'                    | 'CHIP0402'     | ''          | ''            | '20120314'
 '14K'        | '1%'      | '1/16W'  | '0402LF'  | 'CHIP'   | 'CS31402FB12'(!)        = 'End of Design' | 'Comp-Approve'     | 'CS31402FB12'           |'R0402'| '(R0402-0201)'                 | '14K'     | '1%'    | '1/16W'  | 'DISCRETE' | 'RES CHIP 14K 1/16W +-1% (0402)'                   | 'CHIP0402'     | ''          | ''            | '20120314'
 '14K'        | '1%'      | '1/16W'  | '0402LF'  | 'EMPTY'  | 'CS31402FB12'(!)        = 'End of Design' | 'Comp-Approve'     | 'CS31402FB12'           |'R0402'| '(R0402-0201)'                 | '14K'     | '1%'    | '1/16W'  | 'IO'       | 'RES CHIP 14K 1/16W +-1% (0402)'                   | 'CHIP0402'     | ''          | ''            | '20120314'
 '215K'       | '1%'      | '1/16W'  | '0402LF'  | 'CHIP'   | 'CS42152FB19'(!)        = 'End of Design' | 'Comp-Approve'     | 'CS42152FB19'           |'R0402'| '(R0402-0201)'                 | '215K'    | '1%'    | '1/16W'  | 'DISCRETE' | 'RES CHIP 215K 1/16W +-1%(0402)'                   | 'CHIP0402'     | ''          | ''            | '20120320'
 '215K'       | '1%'      | '1/16W'  | '0402LF'  | 'EMPTY'  | 'CS42152FB19'(!)        = 'End of Design' | 'Comp-Approve'     | 'CS42152FB19'           |'R0402'| '(R0402-0201)'                 | '215K'    | '1%'    | '1/16W'  | 'IO'       | 'RES CHIP 215K 1/16W +-1%(0402)'                   | 'CHIP0402'     | ''          | ''            | '20120320'
 '53.6K'      | '1%'      | '1/16W'  | '0402LF'  | 'CHIP'   | 'CS35362FB17'(!)        = 'End of Design' | 'Comp-Approve'     | 'CS35362FB17'           |'R0402'| '(R0402-0201)'                 | '53.6K'   | '1%'    | '1/16W'  | 'DISCRETE' | 'RES CHIP 53.6K 1/16W +-1%(0402)'                  | 'CHIP0402'     | ''          | ''            | '20120320'
 '53.6K'      | '1%'      | '1/16W'  | '0402LF'  | 'EMPTY'  | 'CS35362FB17'(!)        = 'End of Design' | 'Comp-Approve'     | 'CS35362FB17'           |'R0402'| '(R0402-0201)'                 | '53.6K'   | '1%'    | '1/16W'  | 'IO'       | 'RES CHIP 53.6K 1/16W +-1%(0402)'                  | 'CHIP0402'     | ''          | ''            | '20120320'
 '13K'        | '1%'      | '1/10W'  | '0603LF'  | 'CHIP'   | 'CS31303F931'(!)        = ''              | ''                 | 'CS31303F931'           |'R0603'| '(SMR0603AW)'                  | '13K'     | '1%'    | '1/10W'  | 'DISCRETE' | 'RESISTOR CHIP 13K 1/10W +-1%(0603)'               | 'CHIP0603'     | ''          | ''            | '20120321'
 '13K'        | '1%'      | '1/10W'  | '0603LF'  | 'EMPTY'  | 'CS31303F931'(!)        = ''              | ''                 | 'CS31303F931'           |'R0603'| '(SMR0603AW)'                  | '13K'     | '1%'    | '1/10W'  | 'IO'       | 'RESISTOR CHIP 13K 1/10W +-1%(0603)'               | 'CHIP0603'     | ''          | ''            | '20120321'
 '6.81K'      | '1%'      | '1/16W'  | '0402LF'  | 'CHIP'   | 'CS26812FB13'(!)        = 'End of Design' | 'Comp-Approve'     | 'CS26812FB13'           |'R0402'| '(R0402-0201)'                 | '6.81K'   | '1%'    | '1/16W'  | 'DISCRETE' | 'RES CHIP 6.81K 1/16W +-1% (0402)'                 | 'CHIP0402'     | ''          | ''            | '20120322'
 '6.81K'      | '1%'      | '1/16W'  | '0402LF'  | 'EMPTY'  | 'CS26812FB13'(!)        = 'End of Design' | 'Comp-Approve'     | 'CS26812FB13'           |'R0402'| '(R0402-0201)'                 | '6.81K'   | '1%'    | '1/16W'  | 'IO'       | 'RES CHIP 6.81K 1/16W +-1% (0402)'                 | 'CHIP0402'     | ''          | ''            | '20120322'
 '549'        | '1%'      | '1/8W'   | '0805LF'  | 'CHIP'   | 'CS15494FA00'(!)        = ''              | ''                 | 'CS15494FA00'           |'R0805'| '(SMR0805AW)'                  | '549'     | '1%'    | '1/8W'   | 'DISCRETE' | 'RES CHIP 549 1/8W +-1%(0805)'                     | 'CHIP0805'     | ''          | ''            | '20120325'
 '549'        | '1%'      | '1/8W'   | '0805LF'  | 'EMPTY'  | 'CS15494FA00'(!)        = ''              | ''                 | 'CS15494FA00'           |'R0805'| '(SMR0805AW)'                  | '549'     | '1%'    | '1/8W'   | 'IO'       | 'RES CHIP 549 1/8W +-1%(0805)'                     | 'CHIP0805'     | ''          | ''            | '20120325'
 '91'         | '0.1%'    | '1/10W'  | '0603LF'  | 'CHIP'   | 'CS09103B900'(!)        = ''              | ''                 | 'CS09103B900'           |'R0603'| '(SMR0603AW)'                  | '91'      | '0.1%'  | '1/10W'  | 'DISCRETE' | 'RES CHIP 91 1/10W +-0.1%(0603)'                   | 'CHIP0603'     | ''          | ''            | '20120325'
 '91'         | '0.1%'    | '1/10W'  | '0603LF'  | 'EMPTY'  | 'CS09103B900'(!)        = ''              | ''                 | 'CS09103B900'           |'R0603'| '(SMR0603AW)'                  | '91'      | '0.1%'  | '1/10W'  | 'IO'       | 'RES CHIP 91 1/10W +-0.1%(0603)'                   | 'CHIP0603'     | ''          | ''            | '20120325'
 '115'        | '0.1%'    | '1/10W'  | '0603LF'  | 'CHIP'   | 'CS11153B900'(!)        = ''              | ''                 | 'CS11153B900'           |'R0603'| '(SMR0603AW)'                  | '115'     | '0.1%'  | '1/10W'  | 'DISCRETE' | 'RES CHIP 115 1/10W +-0.1%(0603)'                  | 'CHIP0603'     | ''          | ''            | '20120325'
 '115'        | '0.1%'    | '1/10W'  | '0603LF'  | 'EMPTY'  | 'CS11153B900'(!)        = ''              | ''                 | 'CS11153B900'           |'R0603'| '(SMR0603AW)'                  | '115'     | '0.1%'  | '1/10W'  | 'IO'       | 'RES CHIP 115 1/10W +-0.1%(0603)'                  | 'CHIP0603'     | ''          | ''            | '20120325'
 '768'        | '0.1%'    | '1/10W'  | '0603LF'  | 'CHIP'   | 'CS17683B900'(!)        = ''              | ''                 | 'CS17683B900'           |'R0603'| '(SMR0603AW)'                  | '768'     | '0.1%'  | '1/10W'  | 'DISCRETE' | 'RES CHIP 768 1/10W +-0.1%(0603)'                  | 'CHIP0603'     | ''          | ''            | '20120325'
 '768'        | '0.1%'    | '1/10W'  | '0603LF'  | 'EMPTY'  | 'CS17683B900'(!)        = ''              | ''                 | 'CS17683B900'           |'R0603'| '(SMR0603AW)'                  | '768'     | '0.1%'  | '1/10W'  | 'IO'       | 'RES CHIP 768 1/10W +-0.1%(0603)'                  | 'CHIP0603'     | ''          | ''            | '20120325'
 '180K'       | '1%'      | '1/16W'  | '0402LF'  | 'CHIP'   | 'CS41802FB19'(!)        = 'End of Design' | 'Comp-Approve'     | 'CS41802FB19'           |'R0402'| '(R0402-0201)'                 | '180K'    | '1%'    | '1/16W'  | 'DISCRETE' | 'RES CHIP 180K 1/16W +-1%(0402)'                   | 'CHIP0402'     | ''          | ''            | '20120326'
 '180K'       | '1%'      | '1/16W'  | '0402LF'  | 'EMPTY'  | 'CS41802FB19'(!)        = 'End of Design' | 'Comp-Approve'     | 'CS41802FB19'           |'R0402'| '(R0402-0201)'                 | '180K'    | '1%'    | '1/16W'  | 'IO'       | 'RES CHIP 180K 1/16W +-1%(0402)'                   | 'CHIP0402'     | ''          | ''            | '20120326'
 '174'        | '1%'      | '1/16W'  | '0402LF'  | 'CHIP'   | 'CS11742FB00'(!)        = 'End of Design' | 'Comp-Approve'     | 'CS11742FB00'           |'R0402'| '(R0402-0201)'                 | '174'     | '1%'    | '1/16W'  | 'DISCRETE' | 'RES CHIP 174 1/16W +-1%(0402)'                    | 'CHIP0402'     | ''          | ''            | '20120326'
 '174'        | '1%'      | '1/16W'  | '0402LF'  | 'EMPTY'  | 'CS11742FB00'(!)        = 'End of Design' | 'Comp-Approve'     | 'CS11742FB00'           |'R0402'| '(R0402-0201)'                 | '174'     | '1%'    | '1/16W'  | 'IO'       | 'RES CHIP 174 1/16W +-1%(0402)'                    | 'CHIP0402'     | ''          | ''            | '20120326'
 '0.002'      | '1%'      | '2W'     | '2512LF'  | 'CHIP'   | 'CS+002AFR00'(!)        = ''              | ''                 | 'CS+002AFR00'           |'R2512A'| '(SMR2512AW)'                  | '0.002'   | '1%'    | '2W'     | 'DISCRETE' | 'RES CHIP 0.002 2W +-1%(2512)'                     | 'CHIP2512'     | ''          | ''            | '20120326'
 '0.002'      | '1%'      | '2W'     | '2512LF'  | 'EMPTY'  | 'CS+002AFR00'(!)        = ''              | ''                 | 'CS+002AFR00'           |'R2512A'| '(SMR2512AW)'                  | '0.002'   | '1%'    | '2W'     | 'IO'       | 'RES CHIP 0.002 2W +-1%(2512)'                     | 'CHIP2512'     | ''          | ''            | '20120326'
 '3.48M'      | '1%'      | '1/16W'  | '0402LF'  | 'CHIP'   | 'CS53482FB00'(!)        = ''              | ''                 | 'CS53482FB00'           |'R0402'| '(R0402-0201)'                 | '3.48M'   | '1%'    | '1/16W'  | 'DISCRETE' | 'RES CHIP 3.48M 1/16W +-1%(0402)'                  | 'CHIP0402'     | ''          | ''            | '20120329'
 '3.48M'      | '1%'      | '1/16W'  | '0402LF'  | 'EMPTY'  | 'CS53482FB00'(!)        = ''              | ''                 | 'CS53482FB00'           |'R0402'| '(R0402-0201)'                 | '3.48M'   | '1%'    | '1/16W'  | 'IO'       | 'RES CHIP 3.48M 1/16W +-1%(0402)'                  | 'CHIP0402'     | ''          | ''            | '20120329'
 '3.65M'      | '1%'      | '1/16W'  | '0402LF'  | 'CHIP'   | 'CS53652FB00'(!)        = ''              | ''                 | 'CS53652FB00'           |'R0402'| '(R0402-0201)'                 | '3.65M'   | '1%'    | '1/16W'  | 'DISCRETE' | 'RES CHIP 3.65M 1/16W +-1%(0402)'                  | 'CHIP0402'     | ''          | ''            | '20120329'
 '3.65M'      | '1%'      | '1/16W'  | '0402LF'  | 'EMPTY'  | 'CS53652FB00'(!)        = ''              | ''                 | 'CS53652FB00'           |'R0402'| '(R0402-0201)'                 | '3.65M'   | '1%'    | '1/16W'  | 'IO'       | 'RES CHIP 3.65M 1/16W +-1%(0402)'                  | 'CHIP0402'     | ''          | ''            | '20120329'
 '0.5'        | '10%'     | '15W'    | 'THLF'    | 'CHIP'   | 'TMP_T6M_KOOL_0405_1'(!) = ''              | ''                 | 'TMP_T6M_KOOL_0405_1'   |'R18947D'| '(R18947D)'                    | '0.5'     | '10%'   | '15W'    | 'DISCRETE' | 'RESISTOR CEMENT 0.5 15W +-10%'                    | 'R18947D'      | ''          | ''            | '20120405'
 '0.5'        | '10%'     | '15W'    | 'THLF'    | 'EMPTY'  | 'TMP_T6M_KOOL_0405_1'(!) = ''              | ''                 | 'TMP_T6M_KOOL_0405_1'   |'R18947D'| '(R18947D)'                    | '0.5'     | '10%'   | '15W'    | 'IO'       | 'RESISTOR CEMENT 0.5 15W +-10%'                    | 'R18947D'      | ''          | ''            | '20120405'
 '0.39'       | '10%'     | '15W'    | 'THLF'    | 'CHIP'   | 'TMP_T6M_KOOL_0405_2'(!) = ''              | ''                 | 'TMP_T6M_KOOL_0405_2'   |'R18947D'| '(R18947D)'                    | '0.39'    | '10%'   | '15W'    | 'DISCRETE' | 'RESISTOR CEMENT 0.39 15W +-10%'                   | 'R18947D'      | ''          | ''            | '20120405'
 '0.39'       | '10%'     | '15W'    | 'THLF'    | 'EMPTY'  | 'TMP_T6M_KOOL_0405_2'(!) = ''              | ''                 | 'TMP_T6M_KOOL_0405_2'   |'R18947D'| '(R18947D)'                    | '0.39'    | '10%'   | '15W'    | 'IO'       | 'RESISTOR CEMENT 0.39 15W +-10%'                   | 'R18947D'      | ''          | ''            | '20120405'
 '5.76'       | '10%'     | '50W'    | 'THLF'    | 'CHIP'   | 'TMP_T6M_KOOL_0405_3'(!) = ''              | ''                 | 'TMP_T6M_KOOL_0405_3'   |'R35475D'| '(R35475D)'                    | '5.76'    | '10%'   | '50W'    | 'DISCRETE' | 'RESISTOR CEMENT 5.76 50W +-10%'                   | 'R35475D'      | ''          | ''            | '20120405'
 '5.76'       | '10%'     | '50W'    | 'THLF'    | 'EMPTY'  | 'TMP_T6M_KOOL_0405_3'(!) = ''              | ''                 | 'TMP_T6M_KOOL_0405_3'   |'R35475D'| '(R35475D)'                    | '5.76'    | '10%'   | '50W'    | 'IO'       | 'RESISTOR CEMENT 5.76 50W +-10%'                   | 'R35475D'      | ''          | ''            | '20120405'
 '2.88'       | '10%'     | '60W'    | 'THLF'    | 'CHIP'   | 'TMP_T6M_KOOL_0405_4'(!) = ''              | ''                 | 'TMP_T6M_KOOL_0405_4'   |'R35475D'| '(R35475D)'                    | '2.88'    | '10%'   | '60W'    | 'DISCRETE' | 'RESISTOR CEMENT 2.88 60W +-10%'                   | 'R35475D'      | ''          | ''            | '20120405'
 '2.88'       | '10%'     | '60W'    | 'THLF'    | 'EMPTY'  | 'TMP_T6M_KOOL_0405_4'(!) = ''              | ''                 | 'TMP_T6M_KOOL_0405_4'   |'R35475D'| '(R35475D)'                    | '2.88'    | '10%'   | '60W'    | 'IO'       | 'RESISTOR CEMENT 2.88 60W +-10%'                   | 'R35475D'      | ''          | ''            | '20120405'
 '1.5'        | '5%'      | '25W'    | 'THLF'    | 'CHIP'   | 'TMP_T6M_KOOL_0406_1'(!) = ''              | ''                 | 'TMP_T6M_KOOL_0406_1'   |'R23655D'| '(R23655D)'                    | '1.5'     | '5%'    | '25W'    | 'DISCRETE' | 'RESISTOR CEMENT 1.5 25W +-5%'                     | 'R23655D'      | ''          | ''            | '20120406'
 '1.5'        | '5%'      | '25W'    | 'THLF'    | 'EMPTY'  | 'TMP_T6M_KOOL_0406_1'(!) = ''              | ''                 | 'TMP_T6M_KOOL_0406_1'   |'R23655D'| '(R23655D)'                    | '1.5'     | '5%'    | '25W'    | 'IO'       | 'RESISTOR CEMENT 1.5 25W +-5%'                     | 'R23655D'      | ''          | ''            | '20120406'
 '97.6K'      | '1%'      | '1/16W'  | '0402LF'  | 'CHIP'   | 'CS39762FB12'(!)        = 'End of Design' | 'Comp-Approve'     | 'CS39762FB12'           |'R0402'| '(R0402-0201)'                 | '97.6K'   | '1%'    | '1/16W'  | 'DISCRETE' | 'RES CHIP 97.6K 1/16W +-1%(0402)'                  | 'CHIP0402'     | ''          | ''            | '20120406'
 '97.6K'      | '1%'      | '1/16W'  | '0402LF'  | 'EMPTY'  | 'CS39762FB12'(!)        = 'End of Design' | 'Comp-Approve'     | 'CS39762FB12'           |'R0402'| '(R0402-0201)'                 | '97.6K'   | '1%'    | '1/16W'  | 'IO'       | 'RES CHIP 97.6K 1/16W +-1%(0402)'                  | 'CHIP0402'     | ''          | ''            | '20120406'
 '510'        | '1%'      | '1/16W'  | '0402LF'  | 'CHIP'   | 'CS15102FB19'(!)        = 'End of Design' | 'Comp-Approve'     | 'CS15102FB19'           |'R0402'| '(R0402-0201)'                 | '510'     | '1%'    | '1/16W'  | 'DISCRETE' | 'RES CHIP 510 1/16W +-1%(0402)'                    | 'CHIP0402'     | ''          | ''            | '20120414'
 '510'        | '1%'      | '1/16W'  | '0402LF'  | 'EMPTY'  | 'CS15102FB19'(!)        = 'End of Design' | 'Comp-Approve'     | 'CS15102FB19'           |'R0402'| '(R0402-0201)'                 | '510'     | '1%'    | '1/16W'  | 'IO'       | 'RES CHIP 510 1/16W +-1%(0402)'                    | 'CHIP0402'     | ''          | ''            | '20120414'
 '24.9'       | '0.5%'    | '1/16W'  | '0402LF'  | 'CHIP'   | 'CS02492DB01'(!)        = 'End of Design' | 'Comp-Approve'     | 'CS02492DB01'           |'R0402'| '(R0402-0201)'                 | '24.9'    | '0.5%'  | '1/16W'  | 'DISCRETE' | 'RES CHIP 24.9 1/16W +-0.5%(0402)'                 | 'CHIP0402'     | ''          | ''            | '20120416'
 '24.9'       | '0.5%'    | '1/16W'  | '0402LF'  | 'EMPTY'  | 'CS02492DB01'(!)        = 'End of Design' | 'Comp-Approve'     | 'CS02492DB01'           |'R0402'| '(R0402-0201)'                 | '24.9'    | '0.5%'  | '1/16W'  | 'IO'       | 'RES CHIP 24.9 1/16W +-0.5%(0402)'                 | 'CHIP0402'     | ''          | ''            | '20120416'
 '604'        | '1%'      | '1/8W'   | '0805LF'  | 'CHIP'   | 'CS16044FA00'(!)        = ''              | ''                 | 'CS16044FA00'           |'R0805'| '(SMR0805AW)'                  | '604'     | '1%'    | '1/8W'   | 'DISCRETE' | 'RES CHIP 604 1/8W +-1%(0805)'                     | 'CHIP0805'     | ''          | ''            | '20120424'
 '604'        | '1%'      | '1/8W'   | '0805LF'  | 'EMPTY'  | 'CS16044FA00'(!)        = ''              | ''                 | 'CS16044FA00'           |'R0805'| '(SMR0805AW)'                  | '604'     | '1%'    | '1/8W'   | 'IO'       | 'RES CHIP 604 1/8W +-1%(0805)'                     | 'CHIP0805'     | ''          | ''            | '20120424'
 '115'        | '1%'      | '1/16W'  | '0402LF'  | 'CHIP'   | 'CS11152FB11'(!)        = 'End of Design' | 'Comp-Release Qty' | 'CS11152FB11'           |'R0402'| '(R0402-0201)'                 | '115'     | '1%'    | '1/16W'  | 'DISCRETE' | 'RES CHIP 115 1/16W +-1% (0402)'                   | 'CHIP0402'     | ''          | ''            | '20120426'
 '115'        | '1%'      | '1/16W'  | '0402LF'  | 'EMPTY'  | 'CS11152FB11'(!)        = 'End of Design' | 'Comp-Release Qty' | 'CS11152FB11'           |'R0402'| '(R0402-0201)'                 | '115'     | '1%'    | '1/16W'  | 'IO'       | 'RES CHIP 115 1/16W +-1% (0402)'                   | 'CHIP0402'     | ''          | ''            | '20120426'
 '49.9'       | '1%'      | '1/8W'   | '0805LF'  | 'CHIP'   | 'CS04994FA01'(!)        = ''              | ''                 | 'CS04994FA01'           |'R0805'| '(SMR0805AW)'                  | '49.9'    | '1%'    | '1/8W'   | 'DISCRETE' | 'RES CHIP 49.9 1/8W +-1%(0805)'                    | 'CHIP0805'     | ''          | ''            | '20120427'
 '49.9'       | '1%'      | '1/8W'   | '0805LF'  | 'EMPTY'  | 'CS04994FA01'(!)        = ''              | ''                 | 'CS04994FA01'           |'R0805'| '(SMR0805AW)'                  | '49.9'    | '1%'    | '1/8W'   | 'IO'       | 'RES CHIP 49.9 1/8W +-1%(0805)'                    | 'CHIP0805'     | ''          | ''            | '20120427'
 '13.3K'      | '1%'      | '1/16W'  | '0402LF'  | 'CHIP'   | 'CS21332FB02'(!)        = 'End of Design' | 'Comp-Approve'     | 'CS21332FB02'           |'R0402'| '(R0402-0201)'                 | '13.3K'   | '1%'    | '1/16W'  | 'DISCRETE' | 'RES CHIP 13.3K 1/16W +-1%(0402)'                  | 'CHIP0402'     | ''          | ''            | '20120502'
 '13.3K'      | '1%'      | '1/16W'  | '0402LF'  | 'EMPTY'  | 'CS21332FB02'(!)        = 'End of Design' | 'Comp-Approve'     | 'CS21332FB02'           |'R0402'| '(R0402-0201)'                 | '13.3K'   | '1%'    | '1/16W'  | 'IO'       | 'RES CHIP 13.3K 1/16W +-1%(0402)'                  | 'CHIP0402'     | ''          | ''            | '20120502'
 '332K'       | '1%'      | '1/16W'  | '0402LF'  | 'CHIP'   | 'CS43322FB15'(!)        = 'End of Design' | 'Comp-Approve'     | 'CS43322FB15'           |'R0402'| '(R0402-0201)'                 | '332K'    | '1%'    | '1/16W'  | 'DISCRETE' | 'RES CHIP 332K 1/16W +-1%(0402)'                   | 'CHIP0402'     | ''          | ''            | '20120516'
 '332K'       | '1%'      | '1/16W'  | '0402LF'  | 'EMPTY'  | 'CS43322FB15'(!)        = 'End of Design' | 'Comp-Approve'     | 'CS43322FB15'           |'R0402'| '(R0402-0201)'                 | '332K'    | '1%'    | '1/16W'  | 'IO'       | 'RES CHIP 332K 1/16W +-1%(0402)'                   | 'CHIP0402'     | ''          | ''            | '20120516'
 '95.3K'      | '1%'      | '1/8W'   | '0805LF'  | 'CHIP'   | 'CS39534FA00'(!)        = ''              | ''                 | 'CS39534FA00'           |'R0805'| '(SMR0805AW)'                  | '95.3K '  | '1%'    | '1/8W'   | 'DISCRETE' | 'RES CHIP 95.3K 1/8W +-1%(0805)'                   | 'CHIP0805'     | ''          | ''            | '20120524'
 '95.3K'      | '1%'      | '1/8W'   | '0805LF'  | 'EMPTY'  | 'CS39534FA00'(!)        = ''              | ''                 | 'CS39534FA00'           |'R0805'| '(SMR0805AW)'                  | '95.3K '  | '1%'    | '1/8W'   | 'IO'       | 'RES CHIP 95.3K 1/8W +-1%(0805)'                   | 'CHIP0805'     | ''          | ''            | '20120524'
 '453K'       | '1%'      | '1/8W'   | '0805LF'  | 'CHIP'   | 'CS44534FA00'(!)        = ''              | ''                 | 'CS44534FA00'           |'R0805'| '(SMR0805AW)'                  | '453K'    | '1%'    | '1/8W'   | 'DISCRETE' | 'RES CHIP 453K 1/8W +-1%(0805)'                    | 'CHIP0805'     | ''          | ''            | '20120524'
 '453K'       | '1%'      | '1/8W'   | '0805LF'  | 'EMPTY'  | 'CS44534FA00'(!)        = ''              | ''                 | 'CS44534FA00'           |'R0805'| '(SMR0805AW)'                  | '453K'    | '1%'    | '1/8W'   | 'IO'       | 'RES CHIP 453K 1/8W +-1%(0805)'                    | 'CHIP0805'     | ''          | ''            | '20120524'
 '174K'       | '1%'      | '1/8W'   | '0805LF'  | 'CHIP'   | 'CS41744FA00'(!)        = ''              | ''                 | 'CS41744FA00'           |'R0805'| '(SMR0805AW)'                  | '174K'    | '1%'    | '1/8W'   | 'DISCRETE' | 'RES CHIP 174K 1/8W +-1%(0805)'                    | 'CHIP0805'     | ''          | ''            | '20120524'
 '174K'       | '1%'      | '1/8W'   | '0805LF'  | 'EMPTY'  | 'CS41744FA00'(!)        = ''              | ''                 | 'CS41744FA00'           |'R0805'| '(SMR0805AW)'                  | '174K'    | '1%'    | '1/8W'   | 'IO'       | 'RES CHIP 174K 1/8W +-1%(0805)'                    | 'CHIP0805'     | ''          | ''            | '20120524'
 '10'         | '5%'      | '1/20W'  | '0201LF'  | 'CHIP'   | 'CS01001JE00'(!)        = ''              | ''                 | 'CS01001JE00'           |'R0201'| '(SMR0201AW)'                  | '10'      | '5%'    | '1/20W'  | 'DISCRETE' | 'RES CHIP 10(1/20W,+-5%,0201)HF'                   | 'CHIP0201'     | ''          | ''            | '20120524'
 '10'         | '5%'      | '1/20W'  | '0201LF'  | 'EMPTY'  | 'CS01001JE00'(!)        = ''              | ''                 | 'CS01001JE00'           |'R0201'| '(SMR0201AW)'                  | '10'      | '5%'    | '1/20W'  | 'IO'       | 'RES CHIP 10(1/20W,+-5%,0201)HF'                   | 'CHIP0201'     | ''          | ''            | '20120524'
 '1K'         | '5%'      | '1/20W'  | '0201LF'  | 'CHIP'   | 'CS21001JE00'(!)        = ''              | ''                 | 'CS21001JE00'           |'R0201'| '(SMR0201AW)'                  | '1K'      | '5%'    | '1/20W'  | 'DISCRETE' | 'RES CHIP 1K 1/20W +-5%(0201)HF'                   | 'CHIP0201'     | ''          | ''            | '20120524'
 '1K'         | '5%'      | '1/20W'  | '0201LF'  | 'EMPTY'  | 'CS21001JE00'(!)        = ''              | ''                 | 'CS21001JE00'           |'R0201'| '(SMR0201AW)'                  | '1K'      | '5%'    | '1/20W'  | 'IO'       | 'RES CHIP 1K 1/20W +-5%(0201)HF'                   | 'CHIP0201'     | ''          | ''            | '20120524'
 '27K'        | '5%'      | '1/20W'  | '0201LF'  | 'CHIP'   | 'CS32701JE00'(!)        = ''              | ''                 | 'CS32701JE00'           |'R0201'| '(SMR0201AW)'                  | '27K'     | '5%'    | '1/20W'  | 'DISCRETE' | 'RES CHIP 27K 1/20W +-5%(0201)'                    | 'CHIP0201'     | ''          | ''            | '20120524'
 '27K'        | '5%'      | '1/20W'  | '0201LF'  | 'EMPTY'  | 'CS32701JE00'(!)        = ''              | ''                 | 'CS32701JE00'           |'R0201'| '(SMR0201AW)'                  | '27K'     | '5%'    | '1/20W'  | 'IO'       | 'RES CHIP 27K 1/20W +-5%(0201)'                    | 'CHIP0201'     | ''          | ''            | '20120524'
 '100K'       | '5%'      | '1/20W'  | '0201LF'  | 'CHIP'   | 'CS41001JE00'(!)        = ''              | ''                 | 'CS41001JE00'           |'R0201'| '(SMR0201AW)'                  | '100K'    | '5%'    | '1/20W'  | 'DISCRETE' | 'RES CHIP 100K(1/20W,+-5%,0201)'                   | 'CHIP0201'     | ''          | ''            | '20120524'
 '100K'       | '5%'      | '1/20W'  | '0201LF'  | 'EMPTY'  | 'CS41001JE00'(!)        = ''              | ''                 | 'CS41001JE00'           |'R0201'| '(SMR0201AW)'                  | '100K'    | '5%'    | '1/20W'  | 'IO'       | 'RES CHIP 100K(1/20W,+-5%,0201)'                   | 'CHIP0201'     | ''          | ''            | '20120524'
 '499K'       | '1%'      | '1/8W'   | '0805LF'  | 'CHIP'   | 'CS44994FA00'(!)        = ''              | ''                 | 'CS44994FA00'           |'R0805'| '(SMR0805AW)'                  | '499K'    | '1%'    | '1/8W'   | 'DISCRETE' | 'RES CHIP 499K 1/8W+-1%(0805)'                     | 'CHIP0805'     | ''          | ''            | '20120528'
 '499K'       | '1%'      | '1/8W'   | '0805LF'  | 'EMPTY'  | 'CS44994FA00'(!)        = ''              | ''                 | 'CS44994FA00'           |'R0805'| '(SMR0805AW)'                  | '499K'    | '1%'    | '1/8W'   | 'IO'       | 'RES CHIP 499K 1/8W+-1%(0805)'                     | 'CHIP0805'     | ''          | ''            | '20120528'
 '0'          | '5%'      | '1/20W'  | '0201LF'  | 'CHIP'   | 'CS00001JE02'(!)        = 'End of Design' | 'Comp-Approve'     | 'CS00001JE02'           |'R0201'| '(SMR0201AW)'                  | '0'       | '5%'    | '1/20W'  | 'DISCRETE' | 'RES CHIP 0(1/20W,+-5%,0201)HF'                    | 'CHIP0201'     | ''          | ''            | '20120528'
 '0'          | '5%'      | '1/20W'  | '0201LF'  | 'EMPTY'  | 'CS00001JE02'(!)        = 'End of Design' | 'Comp-Approve'     | 'CS00001JE02'           |'R0201'| '(SMR0201AW)'                  | '0'       | '5%'    | '1/20W'  | 'IO'       | 'RES CHIP 0(1/20W,+-5%,0201)HF'                    | 'CHIP0201'     | ''          | ''            | '20120528'
 '4.7K'       | '5%'      | '1/20W'  | '0201LF'  | 'CHIP'   | 'CS24701JE00'(!)        = ''              | ''                 | 'CS24701JE00'           |'R0201'| '(SMR0201AW)'                  | '4.7K'    | '5%'    | '1/20W'  | 'DISCRETE' | 'RES CHIP 4.7K(1/20W,+-5%,0201)'                   | 'CHIP0201'     | ''          | ''            | '20120528'
 '4.7K'       | '5%'      | '1/20W'  | '0201LF'  | 'EMPTY'  | 'CS24701JE00'(!)        = ''              | ''                 | 'CS24701JE00'           |'R0201'| '(SMR0201AW)'                  | '4.7K'    | '5%'    | '1/20W'  | 'IO'       | 'RES CHIP 4.7K(1/20W,+-5%,0201)'                   | 'CHIP0201'     | ''          | ''            | '20120528'
 '33'         | '1%'      | '1/20W'  | '0201LF'  | 'CHIP'   | 'CS03301FE01'(!)        = ''              | ''                 | 'CS03301FE01'           |'R0201'| '(SMR0201AW)'                  | '33'      | '1%'    | '1/20W'  | 'DISCRETE' | 'RES CHIP 33 1/20W +-1%(0201)'                     | 'CHIP0201'     | ''          | ''            | '20120528'
 '33'         | '1%'      | '1/20W'  | '0201LF'  | 'EMPTY'  | 'CS03301FE01'(!)        = ''              | ''                 | 'CS03301FE01'           |'R0201'| '(SMR0201AW)'                  | '33'      | '1%'    | '1/20W'  | 'IO'       | 'RES CHIP 33 1/20W +-1%(0201)'                     | 'CHIP0201'     | ''          | ''            | '20120528'
 '49.9'       | '1%'      | '1/20W'  | '0201LF'  | 'CHIP'   | 'CS04991FE00'(!)        = ''              | ''                 | 'CS04991FE00'           |'R0201'| '(SMR0201AW)'                  | '49.9'    | '1%'    | '1/20W'  | 'DISCRETE' | 'RES CHIP 49.9 1/20W +-1%(0201)'                   | 'CHIP0201'     | ''          | ''            | '20120528'
 '49.9'       | '1%'      | '1/20W'  | '0201LF'  | 'EMPTY'  | 'CS04991FE00'(!)        = ''              | ''                 | 'CS04991FE00'           |'R0201'| '(SMR0201AW)'                  | '49.9'    | '1%'    | '1/20W'  | 'IO'       | 'RES CHIP 49.9 1/20W +-1%(0201)'                   | 'CHIP0201'     | ''          | ''            | '20120528'
 '6.04K'      | '1%'      | '1/20W'  | '0201LF'  | 'CHIP'   | 'CS26041FE06'(!)        = ''              | ''                 | 'CS26041FE06'           |'R0201'| '(SMR0201AW)'                  | '6.04K'   | '1%'    | '1/20W'  | 'DISCRETE' | 'RES CHIP 6.04K 1/20W +-1%(0201)'                  | 'CHIP0201'     | ''          | ''            | '20120528'
 '6.04K'      | '1%'      | '1/20W'  | '0201LF'  | 'EMPTY'  | 'CS26041FE06'(!)        = ''              | ''                 | 'CS26041FE06'           |'R0201'| '(SMR0201AW)'                  | '6.04K'   | '1%'    | '1/20W'  | 'IO'       | 'RES CHIP 6.04K 1/20W +-1%(0201)'                  | 'CHIP0201'     | ''          | ''            | '20120528'
 '100'        | '1%'      | '1/20W'  | '0201LF'  | 'CHIP'   | 'CS11001FE00'(!)        = ''              | ''                 | 'CS11001FE00'           |'R0201'| '(SMR0201AW)'                  | '100'     | '1%'    | '1/20W'  | 'DISCRETE' | 'RES CHIP 100 1/20W +-1%(0201)'                    | 'CHIP0201'     | ''          | ''            | '20120528'
 '100'        | '1%'      | '1/20W'  | '0201LF'  | 'EMPTY'  | 'CS11001FE00'(!)        = ''              | ''                 | 'CS11001FE00'           |'R0201'| '(SMR0201AW)'                  | '100'     | '1%'    | '1/20W'  | 'IO'       | 'RES CHIP 100 1/20W +-1%(0201)'                    | 'CHIP0201'     | ''          | ''            | '20120528'
 '15K'        | '1%'      | '1/20W'  | '0201LF'  | 'CHIP'   | 'CS31501FE01'(!)        = ''              | ''                 | 'CS31501FE01'           |'R0201'| '(SMR0201AW)'                  | '15K'     | '1%'    | '1/20W'  | 'DISCRETE' | 'RES CHIP 15K 1/20W +-1%(0201)HF'                  | 'CHIP0201'     | ''          | ''            | '20120528'
 '15K'        | '1%'      | '1/20W'  | '0201LF'  | 'EMPTY'  | 'CS31501FE01'(!)        = ''              | ''                 | 'CS31501FE01'           |'R0201'| '(SMR0201AW)'                  | '15K'     | '1%'    | '1/20W'  | 'IO'       | 'RES CHIP 15K 1/20W +-1%(0201)HF'                  | 'CHIP0201'     | ''          | ''            | '20120528'
 '240'        | '1%'      | '1/20W'  | '0201LF'  | 'CHIP'   | 'CS12401FE00'(!)        = ''              | ''                 | 'CS12401FE00'           |'R0201'| '(SMR0201AW)'                  | '240'     | '1%'    | '1/20W'  | 'DISCRETE' | 'RES CHIP 240 1/20W +-1%(0201)'                    | 'CHIP0201'     | ''          | ''            | '20120528'
 '240'        | '1%'      | '1/20W'  | '0201LF'  | 'EMPTY'  | 'CS12401FE00'(!)        = ''              | ''                 | 'CS12401FE00'           |'R0201'| '(SMR0201AW)'                  | '240'     | '1%'    | '1/20W'  | 'IO'       | 'RES CHIP 240 1/20W +-1%(0201)'                    | 'CHIP0201'     | ''          | ''            | '20120528'
 '30.1K'      | '1%'      | '1/10W'  | '0603LF'  | 'CHIP'   | 'CS33013F914'(!)        = ''              | ''                 | 'CS33013F914'           |'R0603'| '(SMR0603AW)'                  | '30.1K'   | '1%'    | '1/10W'  | 'DISCRETE' | 'RESISTOR CHIP 30.1K 1/10W+-1%(0603)'              | 'CHIP0603'     | ''          | ''            | '20120529'
 '30.1K'      | '1%'      | '1/10W'  | '0603LF'  | 'EMPTY'  | 'CS33013F914'(!)        = ''              | ''                 | 'CS33013F914'           |'R0603'| '(SMR0603AW)'                  | '30.1K'   | '1%'    | '1/10W'  | 'IO'       | 'RESISTOR CHIP 30.1K 1/10W+-1%(0603)'              | 'CHIP0603'     | ''          | ''            | '20120529'
 '9.76K'      | '0.10%'   | '1/10W'  | '0603LF'  | 'CHIP'   | 'CS29763B903'(!)        = ''              | ''                 | 'CS29763B903'           |'R0603'| '(SMR0603AW)'                  | '9.76K'   | '0.10%' | '1/10W'  | 'DISCRETE' | 'RES CHIP 9.76K 1/10W +-0.1%(0603)'                | 'CHIP0603'     | ''          | ''            | '20120529'
 '9.76K'      | '0.10%'   | '1/10W'  | '0603LF'  | 'EMPTY'  | 'CS29763B903'(!)        = ''              | ''                 | 'CS29763B903'           |'R0603'| '(SMR0603AW)'                  | '9.76K'   | '0.10%' | '1/10W'  | 'IO'       | 'RES CHIP 9.76K 1/10W +-0.1%(0603)'                | 'CHIP0603'     | ''          | ''            | '20120529'
 '1K'         | '5%'      | '1/8W'   | '0805LF'  | 'CHIP'   | 'CS21004JA38'(!)        = ''              | ''                 | 'CS21004JA38'           |'R0805'| '(SMR0805AW)'                  | '1K'      | '5%'    | '1/8W'   | 'DISCRETE' | 'RES CHIP 1K 1/8W +-5%(0805)L-F'                   | 'CHIP0805'     | ''          | ''            | '20120529'
 '1K'         | '5%'      | '1/8W'   | '0805LF'  | 'EMPTY'  | 'CS21004JA38'(!)        = ''              | ''                 | 'CS21004JA38'           |'R0805'| '(SMR0805AW)'                  | '1K'      | '5%'    | '1/8W'   | 'IO'       | 'RES CHIP 1K 1/8W +-5%(0805)L-F'                   | 'CHIP0805'     | ''          | ''            | '20120529'
 '22K'        | '1%'      | '1/10W'  | '0603LF'  | 'CHIP'   | 'CS32203F914'(!)        = ''              | ''                 | 'CS32203F914'           |'R0603'| '(SMR0603AW)'                  | '22K'     | '1%'    | '1/10W'  | 'DISCRETE' | 'RES CHIP 22K 1/10W +-1%(0603)'                    | 'CHIP0603'     | ''          | ''            | '20120529'
 '22K'        | '1%'      | '1/10W'  | '0603LF'  | 'EMPTY'  | 'CS32203F914'(!)        = ''              | ''                 | 'CS32203F914'           |'R0603'| '(SMR0603AW)'                  | '22K'     | '1%'    | '1/10W'  | 'IO'       | 'RES CHIP 22K 1/10W +-1%(0603)'                    | 'CHIP0603'     | ''          | ''            | '20120529'
 '510K'       | '5%'      | '1/16W'  | '0402LF'  | 'CHIP'   | 'CS45102JB16'(!)        = 'End of Design' | 'Comp-Approve'     | 'CS45102JB16'           |'R0402'| '(R0402-0201)'                 | '510K'    | '5%'    | '1/16W'  | 'DISCRETE' | 'RES CHIP 510K(1/16W,+-5%,0402)'                   | 'CHIP0402'     | ''          | ''            | '20120614'
 '510K'       | '5%'      | '1/16W'  | '0402LF'  | 'EMPTY'  | 'CS45102JB16'(!)        = 'End of Design' | 'Comp-Approve'     | 'CS45102JB16'           |'R0402'| '(R0402-0201)'                 | '510K'    | '5%'    | '1/16W'  | 'IO'       | 'RES CHIP 510K(1/16W,+-5%,0402)'                   | 'CHIP0402'     | ''          | ''            | '20120614'
 '130K'       | '5%'      | '1/16W'  | '0402LF'  | 'CHIP'   | 'CS41302JB12'(!)        = 'End of Design' | 'Comp-Approve'     | 'CS41302JB12'           |'R0402'| '(R0402-0201)'                 | '130K'    | '5%'    | '1/16W'  | 'DISCRETE' | 'RES CHIP 130K 1/16W +-5%(0402)'                   | 'CHIP0402'     | ''          | ''            | '20120614'
 '130K'       | '5%'      | '1/16W'  | '0402LF'  | 'EMPTY'  | 'CS41302JB12'(!)        = 'End of Design' | 'Comp-Approve'     | 'CS41302JB12'           |'R0402'| '(R0402-0201)'                 | '130K'    | '5%'    | '1/16W'  | 'IO'       | 'RES CHIP 130K 1/16W +-5%(0402)'                   | 'CHIP0402'     | ''          | ''            | '20120614'
 '56.2'       | '1%'      | '1/16W'  | '0402LF'  | 'CHIP'   | 'CS05622FB22'(!)        = 'End of Design' | 'Comp-Approve'     | 'CS05622FB22'           |'R0402'| '(R0402-0201)'                 | '56.2'    | '1%'    | '1/16W'  | 'DISCRETE' | 'RESISTOR CHIP 56.2 1/16W +-1% (0402)'             | 'CHIP0402'     | ''          | ''            | '20120614'
 '56.2'       | '1%'      | '1/16W'  | '0402LF'  | 'EMPTY'  | 'CS05622FB22'(!)        = 'End of Design' | 'Comp-Approve'     | 'CS05622FB22'           |'R0402'| '(R0402-0201)'                 | '56.2'    | '1%'    | '1/16W'  | 'IO'       | 'RESISTOR CHIP 56.2 1/16W +-1% (0402)'             | 'CHIP0402'     | ''          | ''            | '20120614'
 '20'         | '5%'      | '1/4W'   | '1206LF'  | 'CHIP'   | 'CS02006J201'(!)        = ''              | ''                 | 'CS02006J201'           |'R1206'| '(SMR1206AW)'                  | '20'      | '5%'    | '1/4W'   | 'DISCRETE' | 'RES CHIP 20 1/4W +-5% (1206)'                     | 'CHIP1206'     | ''          | ''            | '20120614'
 '20'         | '5%'      | '1/4W'   | '1206LF'  | 'EMPTY'  | 'CS02006J201'(!)        = ''              | ''                 | 'CS02006J201'           |'R1206'| '(SMR1206AW)'                  | '20'      | '5%'    | '1/4W'   | 'IO'       | 'RES CHIP 20 1/4W +-5% (1206)'                     | 'CHIP1206'     | ''          | ''            | '20120614'
 '5.1'        | '5%'      | '1/4W'   | '1206LF'  | 'CHIP'   | 'CS-5106J205'(!)        = ''              | ''                 | 'CS-5106J205'           |'R1206'| '(SMR1206AW)'                  | '5.1'     | '5%'    | '1/4W'   | 'DISCRETE' | 'RES CHIP 5.1 1/4W +-5% (1206)'                    | 'CHIP1206'     | ''          | ''            | '20120614'
 '5.1'        | '5%'      | '1/4W'   | '1206LF'  | 'EMPTY'  | 'CS-5106J205'(!)        = ''              | ''                 | 'CS-5106J205'           |'R1206'| '(SMR1206AW)'                  | '5.1'     | '5%'    | '1/4W'   | 'IO'       | 'RES CHIP 5.1 1/4W +-5% (1206)'                    | 'CHIP1206'     | ''          | ''            | '20120614'
 '3.3'        | '5%'      | '1/20W'  | '0201LF'  | 'CHIP'   | 'CS-3301JE00'(!)        = ''              | ''                 | 'CS-3301JE00'           |'R0201'| '(SMR0201AW)'                  | '3.3'     | '5%'    | '1/20W'  | 'DISCRETE' | 'RES CHIP 3.3 1/20W +-5%(0201)'                    | 'CHIP0201'     | ''          | ''            | '20120615'
 '3.3'        | '5%'      | '1/20W'  | '0201LF'  | 'EMPTY'  | 'CS-3301JE00'(!)        = ''              | ''                 | 'CS-3301JE00'           |'R0201'| '(SMR0201AW)'                  | '3.3'     | '5%'    | '1/20W'  | 'IO'       | 'RES CHIP 3.3 1/20W +-5%(0201)'                    | 'CHIP0201'     | ''          | ''            | '20120615'
 '4.99'       | '1%'      | '1/20W'  | '0201LF'  | 'CHIP'   | 'CS-4991FE00'(!)        = ''              | ''                 | 'CS-4991FE00'           |'R0201'| '(SMR0201AW)'                  | '4.99'    | '1%'    | '1/20W'  | 'DISCRETE' | 'RES CHIP 4.99 1/20W +-1%(0201)'                   | 'CHIP0201'     | ''          | ''            | '20120615'
 '4.99'       | '1%'      | '1/20W'  | '0201LF'  | 'EMPTY'  | 'CS-4991FE00'(!)        = ''              | ''                 | 'CS-4991FE00'           |'R0201'| '(SMR0201AW)'                  | '4.99'    | '1%'    | '1/20W'  | 'IO'       | 'RES CHIP 4.99 1/20W +-1%(0201)'                   | 'CHIP0201'     | ''          | ''            | '20120615'
 '301'        | '1%'      | '1/20W'  | '0201LF'  | 'CHIP'   | 'CS13011FE01'(!)        = ''              | ''                 | 'CS13011FE01'           |'R0201'| '(SMR0201AW)'                  | '301'     | '1%'    | '1/20W'  | 'DISCRETE' | 'RES CHIP 301 1/20W +-1%(0201)'                    | 'CHIP0201'     | ''          | ''            | '20120615'
 '301'        | '1%'      | '1/20W'  | '0201LF'  | 'EMPTY'  | 'CS13011FE01'(!)        = ''              | ''                 | 'CS13011FE01'           |'R0201'| '(SMR0201AW)'                  | '301'     | '1%'    | '1/20W'  | 'IO'       | 'RES CHIP 301 1/20W +-1%(0201)'                    | 'CHIP0201'     | ''          | ''            | '20120615'
 '1.6K'       | '5%'      | '1/20W'  | '0201LF'  | 'CHIP'   | 'CS21601JE00'(!)        = ''              | ''                 | 'CS21601JE00'           |'R0201'| '(SMR0201AW)'                  | '1.6K'    | '5%'    | '1/20W'  | 'DISCRETE' | 'RES CHIP 1.6K 1/20W +-5%(0201)'                   | 'CHIP0201'     | ''          | ''            | '20120615'
 '1.6K'       | '5%'      | '1/20W'  | '0201LF'  | 'EMPTY'  | 'CS21601JE00'(!)        = ''              | ''                 | 'CS21601JE00'           |'R0201'| '(SMR0201AW)'                  | '1.6K'    | '5%'    | '1/20W'  | 'IO'       | 'RES CHIP 1.6K 1/20W +-5%(0201)'                   | 'CHIP0201'     | ''          | ''            | '20120615'
 '47K'        | '1%'      | '1/20W'  | '0201LF'  | 'CHIP'   | 'CS34701FE00'(!)        = ''              | ''                 | 'CS34701FE00'           |'R0201'| '(SMR0201AW)'                  | '47K'     | '1%'    | '1/20W'  | 'DISCRETE' | 'RES CHIP 47K 1/20W +-1%(0201)'                    | 'CHIP0201'     | ''          | ''            | '20120618'
 '47K'        | '1%'      | '1/20W'  | '0201LF'  | 'EMPTY'  | 'CS34701FE00'(!)        = ''              | ''                 | 'CS34701FE00'           |'R0201'| '(SMR0201AW)'                  | '47K'     | '1%'    | '1/20W'  | 'IO'       | 'RES CHIP 47K 1/20W +-1%(0201)'                    | 'CHIP0201'     | ''          | ''            | '20120618'
 '4.99K'      | '1%'      | '1/20W'  | '0201LF'  | 'CHIP'   | 'CS24991FE00'(!)        = ''              | ''                 | 'CS24991FE00'           |'R0201'| '(SMR0201AW)'                  | '4.99K'   | '1%'    | '1/20W'  | 'DISCRETE' | 'RES CHIP 4.99K(1/20W,+-1%,0201)'                  | 'CHIP0201'     | ''          | ''            | '20120622'
 '4.99K'      | '1%'      | '1/20W'  | '0201LF'  | 'EMPTY'  | 'CS24991FE00'(!)        = ''              | ''                 | 'CS24991FE00'           |'R0201'| '(SMR0201AW)'                  | '4.99K'   | '1%'    | '1/20W'  | 'IO'       | 'RES CHIP 4.99K(1/20W,+-1%,0201)'                  | 'CHIP0201'     | ''          | ''            | '20120622'
 '5.1K'       | '1%'      | '1/20W'  | '0201LF'  | 'CHIP'   | 'CS25101FE00'(!)        = 'End of Design' | 'Comp-Approve'     | 'CS25101FE00'           |'R0201'| '(SMR0201AW)'                  | '5.1K'    | '1%'    | '1/20W'  | 'DISCRETE' | 'RES CHIP 5.1K 1/20W +-1%(0201)'                   | 'CHIP0201'     | ''          | ''            | '20120622'
 '5.1K'       | '1%'      | '1/20W'  | '0201LF'  | 'EMPTY'  | 'CS25101FE00'(!)        = 'End of Design' | 'Comp-Approve'     | 'CS25101FE00'           |'R0201'| '(SMR0201AW)'                  | '5.1K'    | '1%'    | '1/20W'  | 'IO'       | 'RES CHIP 5.1K 1/20W +-1%(0201)'                   | 'CHIP0201'     | ''          | ''            | '20120622'
 '39.2'       | '1%'      | '1/16W'  | '0402LF'  | 'CHIP'   | 'CS03922FB01'(!)        = ''              | ''                 | 'CS03922FB01'           |'R0402'| '(R0402-0201)'                 | '39.2'    | '1%'    | '1/16W'  | 'DISCRETE' | 'RES CHIP 39.2 1/16W +-1%(0402)'                   | 'CHIP0402'     | ''          | ''            | '20120717'
 '39.2'       | '1%'      | '1/16W'  | '0402LF'  | 'EMPTY'  | 'CS03922FB01'(!)        = ''              | ''                 | 'CS03922FB01'           |'R0402'| '(R0402-0201)'                 | '39.2'    | '1%'    | '1/16W'  | 'IO'       | 'RES CHIP 39.2 1/16W +-1%(0402)'                   | 'CHIP0402'     | ''          | ''            | '20120717'
 '562K'       | '1%'      | '1/16W'  | '0402LF'  | 'CHIP'   | 'CS45622FB11'(!)        = 'End of Design' | 'Comp-Approve'     | 'CS45622FB11'           |'R0402'| '(R0402-0201)'                 | '562K'    | '1%'    | '1/16W'  | 'DISCRETE' | 'RES CHIP 562K 1/16W +-1%(0402)'                   | 'CHIP0402'     | ''          | ''            | '20120717'
 '562K'       | '1%'      | '1/16W'  | '0402LF'  | 'EMPTY'  | 'CS45622FB11'(!)        = 'End of Design' | 'Comp-Approve'     | 'CS45622FB11'           |'R0402'| '(R0402-0201)'                 | '562K'    | '1%'    | '1/16W'  | 'IO'       | 'RES CHIP 562K 1/16W +-1%(0402)'                   | 'CHIP0402'     | ''          | ''            | '20120717'
 '3.09K'      | '1%'      | '1/16W'  | '0402LF'  | 'CHIP'   | 'CS23092FB00'(!)        = 'End of Design' | 'Comp-Approve'     | 'CS23092FB00'           |'R0402'| '(R0402-0201)'                 | '3.09K'   | '1%'    | '1/16W'  | 'DISCRETE' | 'RES CHIP 3.09K 1/16W +-1%(0402)'                  | 'CHIP0402'     | ''          | ''            | '20120717'
 '3.09K'      | '1%'      | '1/16W'  | '0402LF'  | 'EMPTY'  | 'CS23092FB00'(!)        = 'End of Design' | 'Comp-Approve'     | 'CS23092FB00'           |'R0402'| '(R0402-0201)'                 | '3.09K'   | '1%'    | '1/16W'  | 'IO'       | 'RES CHIP 3.09K 1/16W +-1%(0402)'                  | 'CHIP0402'     | ''          | ''            | '20120717'
 '1.8K'       | '5%'      | '1/16W'  | '0402LF'  | 'CHIP'   | 'CS21802JB17'(!)        = 'End of Design' | 'Comp-Approve'     | 'CS21802JB17'           |'R0402'| '(R0402-0201)'                 | '1.8K'    | '5%'    | '1/16W'  | 'DISCRETE' | 'RES CHIP 1.8K 1/16W +-5%(0402)'                   | 'CHIP0402'     | ''          | ''            | '20120717'
 '1.8K'       | '5%'      | '1/16W'  | '0402LF'  | 'EMPTY'  | 'CS21802JB17'(!)        = 'End of Design' | 'Comp-Approve'     | 'CS21802JB17'           |'R0402'| '(R0402-0201)'                 | '1.8K'    | '5%'    | '1/16W'  | 'IO'       | 'RES CHIP 1.8K 1/16W +-5%(0402)'                   | 'CHIP0402'     | ''          | ''            | '20120717'
 '1M'         | '1%'      | '1/10W'  | '0603LF'  | 'CHIP'   | 'CS51003F934'(!)        = ''              | ''                 | 'CS51003F934'           |'R0603'| '(SMR0603AW)'                  | '1M'      | '1%'    | '1/10W'  | 'DISCRETE' | 'RESISTOR CHIP 1M 1/10W+-1%(0603)'                 | 'CHIP0603'     | ''          | ''            | '20120717'
 '1M'         | '1%'      | '1/10W'  | '0603LF'  | 'EMPTY'  | 'CS51003F934'(!)        = ''              | ''                 | 'CS51003F934'           |'R0603'| '(SMR0603AW)'                  | '1M'      | '1%'    | '1/10W'  | 'IO'       | 'RESISTOR CHIP 1M 1/10W+-1%(0603)'                 | 'CHIP0603'     | ''          | ''            | '20120717'
 '910'        | '1%'      | '1/16W'  | '0402LF'  | 'CHIP'   | 'CS19102FB01'(!)        = ''              | ''                 | 'CS19102FB01'           |'R0402'| '(R0402-0201)'                 | '910'     | '1%'    | '1/16W'  | 'DISCRETE' | 'RES CHIP 910(1/16W,1%,0402)'                      | 'CHIP0402'     | ''          | ''            | '20120724'
 '910'        | '1%'      | '1/16W'  | '0402LF'  | 'EMPTY'  | 'CS19102FB01'(!)        = ''              | ''                 | 'CS19102FB01'           |'R0402'| '(R0402-0201)'                 | '910'     | '1%'    | '1/16W'  | 'IO'       | 'RES CHIP 910(1/16W,1%,0402)'                      | 'CHIP0402'     | ''          | ''            | '20120724'
 '4.87K'      | '1%'      | '1/16W'  | '0402LF'  | 'CHIP'   | 'CS24872FB07'(!)        = 'End of Design' | 'Comp-Approve'     | 'CS24872FB07'           |'R0402'| '(R0402-0201)'                 | '4.87K'   | '1%'    | '1/16W'  | 'DISCRETE' | 'RES CHIP 4.87K 1/16W+-1%(0402)'                   | 'CHIP0402'     | ''          | ''            | '20120730'
 '4.87K'      | '1%'      | '1/16W'  | '0402LF'  | 'EMPTY'  | 'CS24872FB07'(!)        = 'End of Design' | 'Comp-Approve'     | 'CS24872FB07'           |'R0402'| '(R0402-0201)'                 | '4.87K'   | '1%'    | '1/16W'  | 'IO'       | 'RES CHIP 4.87K 1/16W+-1%(0402)'                   | 'CHIP0402'     | ''          | ''            | '20120730'
 '590'        | '1%'      | '1/16W'  | '0402LF'  | 'CHIP'   | 'CS15902FB00'(!)        = 'End of Design' | 'Comp-Approve'     | 'CS15902FB00'           |'R0402'| '(R0402-0201)'                 | '590'     | '1%'    | '1/16W'  | 'DISCRETE' | 'RES CHIP 590 1/16W +-1%(0402)'                    | 'CHIP0402'     | ''          | ''            | '20120801'
 '590'        | '1%'      | '1/16W'  | '0402LF'  | 'EMPTY'  | 'CS15902FB00'(!)        = 'End of Design' | 'Comp-Approve'     | 'CS15902FB00'           |'R0402'| '(R0402-0201)'                 | '590'     | '1%'    | '1/16W'  | 'IO'       | 'RES CHIP 590 1/16W +-1%(0402)'                    | 'CHIP0402'     | ''          | ''            | '20120801'
 '147K'       | '1%'      | '1/16W'  | '0402LF'  | 'CHIP'   | 'CS41472FB16'(!)        = 'End of Design' | 'Comp-Approve'     | 'CS41472FB16'           |'R0402'| '(R0402-0201)'                 | '147K'    | '1%'    | '1/16W'  | 'DISCRETE' | 'RES CHIP 147K 1/16W +-1%(0402)'                   | 'CHIP0402'     | ''          | ''            | '20120801'
 '147K'       | '1%'      | '1/16W'  | '0402LF'  | 'EMPTY'  | 'CS41472FB16'(!)        = 'End of Design' | 'Comp-Approve'     | 'CS41472FB16'           |'R0402'| '(R0402-0201)'                 | '147K'    | '1%'    | '1/16W'  | 'IO'       | 'RES CHIP 147K 1/16W +-1%(0402)'                   | 'CHIP0402'     | ''          | ''            | '20120801'
 '510K'       | '5%'      | '1/16W'  | '0402LF'  | 'CHIP'   | 'CS45102JB08'(!)        = ''              | ''                 | 'CS45102JB08'           |'R0402'| '(R0402-0201)'                 | '510K'    | '5%'    | '1/16W'  | 'DISCRETE' | 'RES CHIP 510K(1/16W.+-5%.0402)'                   | 'CHIP0402'     | ''          | ''            | '20120801'
 '510K'       | '5%'      | '1/16W'  | '0402LF'  | 'EMPTY'  | 'CS45102JB08'(!)        = ''              | ''                 | 'CS45102JB08'           |'R0402'| '(R0402-0201)'                 | '510K'    | '5%'    | '1/16W'  | 'IO'       | 'RES CHIP 510K(1/16W.+-5%.0402)'                   | 'CHIP0402'     | ''          | ''            | '20120801'
 '6.8K'       | '1%'      | '1/16W'  | '0402LF'  | 'CHIP'   | 'CS26802FB19'(!)        = 'End of Design' | 'Comp-Approve'     | 'CS26802FB19'           |'R0402'| '(R0402-0201)'                 | '6.8K'    | '1%'    | '1/16W'  | 'DISCRETE' | 'RES CHIP 6.8K 1/16W +-1%(0402)'                   | 'CHIP0402'     | ''          | ''            | '20120801'
 '6.8K'       | '1%'      | '1/16W'  | '0402LF'  | 'EMPTY'  | 'CS26802FB19'(!)        = 'End of Design' | 'Comp-Approve'     | 'CS26802FB19'           |'R0402'| '(R0402-0201)'                 | '6.8K'    | '1%'    | '1/16W'  | 'IO'       | 'RES CHIP 6.8K 1/16W +-1%(0402)'                   | 'CHIP0402'     | ''          | ''            | '20120801'
 '619'        | '1%'      | '1/16W'  | '0402LF'  | 'CHIP'   | 'CS16192FB04'(!)        = ''              | ''                 | 'CS16192FB04'           |'R0402'| '(R0402-0201)'                 | '619'     | '1%'    | '1/16W'  | 'DISCRETE' | ' RES CHIP 619 1/16W +-1%(0402)'                   | 'CHIP0402'     | ''          | ''            | '20120807'
 '619'        | '1%'      | '1/16W'  | '0402LF'  | 'EMPTY'  | 'CS16192FB04'(!)        = ''              | ''                 | 'CS16192FB04'           |'R0402'| '(R0402-0201)'                 | '619'     | '1%'    | '1/16W'  | 'IO'       | ' RES CHIP 619 1/16W +-1%(0402)'                   | 'CHIP0402'     | ''          | ''            | '20120807'
 '11'         | '1%'      | '1/16W'  | '0402LF'  | 'CHIP'   | 'CS01102FB08'(!)        = 'End of Design' | 'Comp-Approve'     | 'CS01102FB08'           |'R0402'| '(R0402-0201)'                 | '11'      | '1%'    | '1/16W'  | 'DISCRETE' | 'RES CHIP 11 1/16W +-1%(0402)'                     | 'CHIP0402'     | ''          | ''            | '20120808'
 '11'         | '1%'      | '1/16W'  | '0402LF'  | 'EMPTY'  | 'CS01102FB08'(!)        = 'End of Design' | 'Comp-Approve'     | 'CS01102FB08'           |'R0402'| '(R0402-0201)'                 | '11'      | '1%'    | '1/16W'  | 'IO'       | 'RES CHIP 11 1/16W +-1%(0402)'                     | 'CHIP0402'     | ''          | ''            | '20120808'
 '191'        | '1%'      | '1/16W'  | '0402LF'  | 'CHIP'   | 'CS11912FB00'(!)        = 'End of Design' | 'Comp-Approve'     | 'CS11912FB00'           |'R0402'| '(R0402-0201)'                 | '191'     | '1%'    | '1/16W'  | 'DISCRETE' | 'RES CHIP 191 1/16W +-1%(0402)'                    | 'CHIP0402'     | ''          | ''            | '20120813'
 '191'        | '1%'      | '1/16W'  | '0402LF'  | 'EMPTY'  | 'CS11912FB00'(!)        = 'End of Design' | 'Comp-Approve'     | 'CS11912FB00'           |'R0402'| '(R0402-0201)'                 | '191'     | '1%'    | '1/16W'  | 'IO'       | 'RES CHIP 191 1/16W +-1%(0402)'                    | 'CHIP0402'     | ''          | ''            | '20120813'
 '27K'        | '1%'      | '1/16W'  | '0402LF'  | 'CHIP'   | 'CS32702FB16'(!)        = 'End of Design' | 'Comp-Approve'     | 'CS32702FB16'           |'R0402'| '(R0402-0201)'                 | '27K'     | '1%'    | '1/16W'  | 'DISCRETE' | 'RES CHIP 27K 1/16W +-1%(0402)'                    | 'CHIP0402'     | ''          | ''            | '20120816'
 '27K'        | '1%'      | '1/16W'  | '0402LF'  | 'EMPTY'  | 'CS32702FB16'(!)        = 'End of Design' | 'Comp-Approve'     | 'CS32702FB16'           |'R0402'| '(R0402-0201)'                 | '27K'     | '1%'    | '1/16W'  | 'IO'       | 'RES CHIP 27K 1/16W +-1%(0402)'                    | 'CHIP0402'     | ''          | ''            | '20120816'
 '255K'       | '1%'      | '1/16W'  | '0402LF'  | 'CHIP'   | 'CS42552FB05'(!)        = 'End of Design' | 'Comp-Approve'     | 'CS42552FB05'           |'R0402'| '(R0402-0201)'                 | '255K'    | '1%'    | '1/16W'  | 'DISCRETE' | 'RES CHIP 255K 1/16W +-1%(0402)'                   | 'CHIP0402'     | ''          | ''            | '20120816'
 '255K'       | '1%'      | '1/16W'  | '0402LF'  | 'EMPTY'  | 'CS42552FB05'(!)        = 'End of Design' | 'Comp-Approve'     | 'CS42552FB05'           |'R0402'| '(R0402-0201)'                 | '255K'    | '1%'    | '1/16W'  | 'IO'       | 'RES CHIP 255K 1/16W +-1%(0402)'                   | 'CHIP0402'     | ''          | ''            | '20120816'
 '226'        | '1%'      | '1/16W'  | '0402LF'  | 'CHIP'   | 'CS12262FB11'(!)        = 'End of Design' | 'Comp-Approve'     | 'CS12262FB11'           |'R0402'| '(R0402-0201)'                 | '226'     | '1%'    | '1/16W'  | 'DISCRETE' | 'RES CHIP 226. 1/16W. +-1% (0402)'                 | 'CHIP0402'     | ''          | ''            | '20120829'
 '226'        | '1%'      | '1/16W'  | '0402LF'  | 'EMPTY'  | 'CS12262FB11'(!)        = 'End of Design' | 'Comp-Approve'     | 'CS12262FB11'           |'R0402'| '(R0402-0201)'                 | '226'     | '1%'    | '1/16W'  | 'IO'       | 'RES CHIP 226. 1/16W. +-1% (0402)'                 | 'CHIP0402'     | ''          | ''            | '20120829'
 '52.3K'      | '1%'      | '1/16W'  | '0402LF'  | 'CHIP'   | 'CS35232FB01'(!)        = ''              | ''                 | 'CS35232FB01'           |'R0402'| '(R0402-0201)'                 | '52.3K'   | '1%'    | '1/16W'  | 'DISCRETE' | 'RES CHIP 52.3K 1/16W +-1% (0402)'                 | 'CHIP0402'     | ''          | ''            | '20120904'
 '52.3K'      | '1%'      | '1/16W'  | '0402LF'  | 'EMPTY'  | 'CS35232FB01'(!)        = ''              | ''                 | 'CS35232FB01'           |'R0402'| '(R0402-0201)'                 | '52.3K'   | '1%'    | '1/16W'  | 'IO'       | 'RES CHIP 52.3K 1/16W +-1% (0402)'                 | 'CHIP0402'     | ''          | ''            | '20120904'
 '274K'       | '1%'      | '1/16W'  | '0402LF'  | 'CHIP'   | 'CS42742FB00'(!)        = 'End of Design' | 'Comp-Approve'     | 'CS42742FB00'           |'R0402'| '(R0402-0201)'                 | '274K'    | '1%'    | '1/16W'  | 'DISCRETE' | 'RES CHP 274K 1/16W +-1%(0402)'                    | 'CHIP0402'     | ''          | ''            | '20120904'
 '274K'       | '1%'      | '1/16W'  | '0402LF'  | 'EMPTY'  | 'CS42742FB00'(!)        = 'End of Design' | 'Comp-Approve'     | 'CS42742FB00'           |'R0402'| '(R0402-0201)'                 | '274K'    | '1%'    | '1/16W'  | 'IO'       | 'RES CHP 274K 1/16W +-1%(0402)'                    | 'CHIP0402'     | ''          | ''            | '20120904'
 '487K'       | '1%'      | '1/16W'  | '0402LF'  | 'CHIP'   | 'CS44872FB19'(!)        = 'End of Design' | 'Comp-Approve'     | 'CS44872FB19'           |'R0402'| '(R0402-0201)'                 | '487K'    | '1%'    | '1/16W'  | 'DISCRETE' | 'RES CHIP 487K 1/16W +-1%( 0402)L-F'               | 'CHIP0402'     | ''          | ''            | '20120904'
 '487K'       | '1%'      | '1/16W'  | '0402LF'  | 'EMPTY'  | 'CS44872FB19'(!)        = 'End of Design' | 'Comp-Approve'     | 'CS44872FB19'           |'R0402'| '(R0402-0201)'                 | '487K'    | '1%'    | '1/16W'  | 'IO'       | 'RES CHIP 487K 1/16W +-1%( 0402)L-F'               | 'CHIP0402'     | ''          | ''            | '20120904'
 '2.87K'      | '1%'      | '1/16W'  | '0402LF'  | 'CHIP'   | 'CS22872FB10'(!)        = 'End of Design' | 'Comp-Approve'     | 'CS22872FB10'           |'R0402'| '(R0402-0201)'                 | '2.87K'   | '1%'    | '1/16W'  | 'DISCRETE' | 'RES CHIP 2.87K 1/16W +-1%(0402)'                  | 'CHIP0402'     | ''          | ''            | '20120904'
 '2.87K'      | '1%'      | '1/16W'  | '0402LF'  | 'EMPTY'  | 'CS22872FB10'(!)        = 'End of Design' | 'Comp-Approve'     | 'CS22872FB10'           |'R0402'| '(R0402-0201)'                 | '2.87K'   | '1%'    | '1/16W'  | 'IO'       | 'RES CHIP 2.87K 1/16W +-1%(0402)'                  | 'CHIP0402'     | ''          | ''            | '20120904'
 '316K'       | '1%'      | '1/16W'  | '0402LF'  | 'CHIP'   | 'CS43162FB00'(!)        = 'End of Design' | 'Comp-Approve'     | 'CS43162FB00'           |'R0402'| '(R0402-0201)'                 | '316K'    | '1%'    | '1/16W'  | 'DISCRETE' | 'RES CHIP 316K 1/16W +-1%(0402)'                   | 'CHIP0402'     | ''          | ''            | '20120906'
 '316K'       | '1%'      | '1/16W'  | '0402LF'  | 'EMPTY'  | 'CS43162FB00'(!)        = 'End of Design' | 'Comp-Approve'     | 'CS43162FB00'           |'R0402'| '(R0402-0201)'                 | '316K'    | '1%'    | '1/16W'  | 'IO'       | 'RES CHIP 316K 1/16W +-1%(0402)'                   | 'CHIP0402'     | ''          | ''            | '20120906'
 '348K'       | '1%'      | '1/16W'  | '0402LF'  | 'CHIP'   | 'CS43482FB16'(!)        = 'End of Design' | 'Comp-Approve'     | 'CS43482FB16'           |'R0402'| '(R0402-0201)'                 | '348K'    | '1%'    | '1/16W'  | 'DISCRETE' | 'RES CHIP 348K 1/16W +-1%( 0402)'                  | 'CHIP0402'     | ''          | ''            | '20120906'
 '348K'       | '1%'      | '1/16W'  | '0402LF'  | 'EMPTY'  | 'CS43482FB16'(!)        = 'End of Design' | 'Comp-Approve'     | 'CS43482FB16'           |'R0402'| '(R0402-0201)'                 | '348K'    | '1%'    | '1/16W'  | 'IO'       | 'RES CHIP 348K 1/16W +-1%( 0402)'                  | 'CHIP0402'     | ''          | ''            | '20120906'
 '360K'       | '1%'      | '1/16W'  | '0402LF'  | 'CHIP'   | 'CS43602FB00'(!)        = 'End of Design' | 'Comp-Approve'     | 'CS43602FB00'           |'R0402'| '(R0402-0201)'                 | '360K'    | '1%'    | '1/16W'  | 'DISCRETE' | 'RES CHIP 360K 1/16W +-1%(0402)'                   | 'CHIP0402'     | ''          | ''            | '20120906'
 '360K'       | '1%'      | '1/16W'  | '0402LF'  | 'EMPTY'  | 'CS43602FB00'(!)        = 'End of Design' | 'Comp-Approve'     | 'CS43602FB00'           |'R0402'| '(R0402-0201)'                 | '360K'    | '1%'    | '1/16W'  | 'IO'       | 'RES CHIP 360K 1/16W +-1%(0402)'                   | 'CHIP0402'     | ''          | ''            | '20120906'
 '499'        | '1%'      | '1/16W'  | '0402LF'  | 'CHIP'   | 'CS14992FB24'(!)        = 'End of Design' | 'Comp-Approve'     | 'CS14992FB24'           |'R0402'| '(R0402-0201)'                 | '499'     | '1%'    | '1/16W'  | 'DISCRETE' | 'RES CHIP 499 1/16W +-1%(0402)'                    | 'CHIP0402'     | ''          | ''            | '20120913'
 '499'        | '1%'      | '1/16W'  | '0402LF'  | 'EMPTY'  | 'CS14992FB24'(!)        = 'End of Design' | 'Comp-Approve'     | 'CS14992FB24'           |'R0402'| '(R0402-0201)'                 | '499'     | '1%'    | '1/16W'  | 'IO'       | 'RES CHIP 499 1/16W +-1%(0402)'                    | 'CHIP0402'     | ''          | ''            | '20120913'
 '1.82K'      | '1%'      | '1/16W'  | '0402LF'  | 'CHIP'   | 'CS21822FB14'(!)        = 'End of Design' | 'Comp-Approve'     | 'CS21822FB14'           |'R0402'| '(R0402-0201)'                 | '1.82K'   | '1%'    | '1/16W'  | 'DISCRETE' | 'RES CHIP 1.82K 1/16W +-1%(0402)'                  | 'CHIP0402'     | ''          | ''            | '20120913'
 '1.82K'      | '1%'      | '1/16W'  | '0402LF'  | 'EMPTY'  | 'CS21822FB14'(!)        = 'End of Design' | 'Comp-Approve'     | 'CS21822FB14'           |'R0402'| '(R0402-0201)'                 | '1.82K'   | '1%'    | '1/16W'  | 'IO'       | 'RES CHIP 1.82K 1/16W +-1%(0402)'                  | 'CHIP0402'     | ''          | ''            | '20120913'
 '3.24K'      | '1%'      | '1/16W'  | '0402LF'  | 'CHIP'   | 'CS23242FB17'(!)        = 'End of Design' | 'Comp-Approve'     | 'CS23242FB17'           |'R0402'| '(R0402-0201)'                 | '3.24K'   | '1%'    | '1/16W'  | 'DISCRETE' | 'RES CHIP 3.24K +-1% 1/16W(0402) EP'               | 'CHIP0402'     | ''          | ''            | '20120913'
 '3.24K'      | '1%'      | '1/16W'  | '0402LF'  | 'EMPTY'  | 'CS23242FB17'(!)        = 'End of Design' | 'Comp-Approve'     | 'CS23242FB17'           |'R0402'| '(R0402-0201)'                 | '3.24K'   | '1%'    | '1/16W'  | 'IO'       | 'RES CHIP 3.24K +-1% 1/16W(0402) EP'               | 'CHIP0402'     | ''          | ''            | '20120913'
 '2.0'        | '1%'      | '1/16W'  | '0402LF'  | 'CHIP'   | 'CS-2002FB00'(!)        = 'End of Design' | 'Comp-Approve'     | 'CS-2002FB00'           |'R0402'| '(R0402-0201)'                 | '2.0'     | '1%'    | '1/16W'  | 'DISCRETE' | 'RES CHIP 2.0 1/16W +1%(0402)'                     | 'CHIP0402'     | ''          | ''            | '20120919'
 '2.0'        | '1%'      | '1/16W'  | '0402LF'  | 'EMPTY'  | 'CS-2002FB00'(!)        = 'End of Design' | 'Comp-Approve'     | 'CS-2002FB00'           |'R0402'| '(R0402-0201)'                 | '2.0'     | '1%'    | '1/16W'  | 'IO'       | 'RES CHIP 2.0 1/16W +1%(0402)'                     | 'CHIP0402'     | ''          | ''            | '20120919'
 '32.4K'      | '1%'      | '1/16W'  | '0402LF'  | 'CHIP'   | 'CS33242FB19'(!)        = 'End of Design' | 'Comp-Approve'     | 'CS33242FB19'           |'R0402'| '(R0402-0201)'                 | '32.4K'   | '1%'    | '1/16W'  | 'DISCRETE' | 'RES CHIP 32.4K 1/16W +-1%(0402)'                  | 'CHIP0402'     | ''          | ''            | '20120925'
 '32.4K'      | '1%'      | '1/16W'  | '0402LF'  | 'EMPTY'  | 'CS33242FB19'(!)        = 'End of Design' | 'Comp-Approve'     | 'CS33242FB19'           |'R0402'| '(R0402-0201)'                 | '32.4K'   | '1%'    | '1/16W'  | 'IO'       | 'RES CHIP 32.4K 1/16W +-1%(0402)'                  | 'CHIP0402'     | ''          | ''            | '20120925'
 '1.4K'       | '1%'      | '1/16W'  | '0402LF'  | 'CHIP'   | 'CS21402FB02'(!)        = 'End of Design' | 'Comp-Approve'     | 'CS21402FB02'           |'R0402'| '(R0402-0201)'                 | '1.4K'    | '1%'    | '1/16W'  | 'DISCRETE' | 'RES CHIP 1.4K 1/16W +-1%(0402)'                   | 'CHIP0402'     | ''          | ''            | '20120925'
 '1.4K'       | '1%'      | '1/16W'  | '0402LF'  | 'EMPTY'  | 'CS21402FB02'(!)        = 'End of Design' | 'Comp-Approve'     | 'CS21402FB02'           |'R0402'| '(R0402-0201)'                 | '1.4K'    | '1%'    | '1/16W'  | 'IO'       | 'RES CHIP 1.4K 1/16W +-1%(0402)'                   | 'CHIP0402'     | ''          | ''            | '20120925'
 '825'        | '1%'      | '1/16W'  | '0402LF'  | 'CHIP'   | 'CS18252FB00'(!)        = 'End of Design' | 'Comp-Approve'     | 'CS18252FB00'           |'R0402'| '(R0402-0201)'                 | '825'     | '1%'    | '1/16W'  | 'DISCRETE' | 'RES CHIP 825 1/16W +-1% (0402)'                   | 'CHIP0402'     | ''          | ''            | '20121003'
 '825'        | '1%'      | '1/16W'  | '0402LF'  | 'EMPTY'  | 'CS18252FB00'(!)        = 'End of Design' | 'Comp-Approve'     | 'CS18252FB00'           |'R0402'| '(R0402-0201)'                 | '825'     | '1%'    | '1/16W'  | 'IO'       | 'RES CHIP 825 1/16W +-1% (0402)'                   | 'CHIP0402'     | ''          | ''            | '20121003'
 '61.9'       | '1%'      | '1/16W'  | '0402LF'  | 'CHIP'   | 'CS06192FB02'(!)        = 'End of Design' | 'Comp-Approve'     | 'CS06192FB02'           |'R0402'| '(R0402-0201)'                 | '61.9'    | '1%'    | '1/16W'  | 'DISCRETE' | 'RES CHIP 61.9 1/16W 1%(0402)'                     | 'CHIP0402'     | ''          | ''            | '20121017'
 '61.9'       | '1%'      | '1/16W'  | '0402LF'  | 'EMPTY'  | 'CS06192FB02'(!)        = 'End of Design' | 'Comp-Approve'     | 'CS06192FB02'           |'R0402'| '(R0402-0201)'                 | '61.9'    | '1%'    | '1/16W'  | 'IO'       | 'RES CHIP 61.9 1/16W 1%(0402)'                     | 'CHIP0402'     | ''          | ''            | '20121017'
 '0'          | '1%'      | '1/2W'   | '1206LF'  | 'CHIP'   | 'CS00007F200'(!)        = ''              | ''                 | 'CS00007F200'           |'R1206'| '(SMR1206AW)'                  | '0'       | '1%'    | '1/2W'   | 'DISCRETE' | 'RES CHIP 0 1/2W +-1%(1206)'                       | 'CHIP1206'     | ''          | ''            | '20121023'
 '0'          | '1%'      | '1/2W'   | '1206LF'  | 'EMPTY'  | 'CS00007F200'(!)        = ''              | ''                 | 'CS00007F200'           |'R1206'| '(SMR1206AW)'                  | '0'       | '1%'    | '1/2W'   | 'IO'       | 'RES CHIP 0 1/2W +-1%(1206)'                       | 'CHIP1206'     | ''          | ''            | '20121023'
 '0.001'      | '1%'      | '1W'     | '3720LF'  | 'CHIP'   | 'CS+0018FL00'(!)        = ''              | ''                 | 'CS+0018FL00'           |'R3720'| '(SMR3720AW)'                  | '0.001'   | '1%'    | '1W'     | 'DISCRETE' | 'RES CHIP 0.001 1W +-1%(3720)'                     | 'CHIP3720'     | ''          | ''            | '20121023'
 '0.001'      | '1%'      | '1W'     | '3720LF'  | 'EMPTY'  | 'CS+0018FL00'(!)        = ''              | ''                 | 'CS+0018FL00'           |'R3720'| '(SMR3720AW)'                  | '0.001'   | '1%'    | '1W'     | 'IO'       | 'RES CHIP 0.001 1W +-1%(3720)'                     | 'CHIP3720'     | ''          | ''            | '20121023'
 '6.8M'       | '5%'      | '1/16W'  | '0402LF'  | 'CHIP'   | 'CS56802JB00'(!)        = ''              | ''                 | 'CS56802JB00'           |'R0402'| '(R0402-0201)'                 | '6.8M'    | '5%'    | '1/16W'  | 'DISCRETE' | 'RESISTOR CHIP 6.8M 1/16W +-5%(0402)'              | 'CHIP0402'     | ''          | ''            | '20121024'
 '6.8M'       | '5%'      | '1/16W'  | '0402LF'  | 'EMPTY'  | 'CS56802JB00'(!)        = ''              | ''                 | 'CS56802JB00'           |'R0402'| '(R0402-0201)'                 | '6.8M'    | '5%'    | '1/16W'  | 'IO'       | 'RESISTOR CHIP 6.8M 1/16W +-5%(0402)'              | 'CHIP0402'     | ''          | ''            | '20121024'
 '0.004'      | '1%'      | '1W'     | '1206LF'  | 'CHIP'   | 'CS+0048F200'(!)        = ''              | ''                 | 'CS+0048F200'           |'R1206XA'| '(SMR1206AW)'                  | '0.004'   | '1%'    | '1W'     | 'DISCRETE' | 'RES CHIP 0.004 1W +-1%(1206)'                     | 'CHIP1206'     | ''          | ''            | '20121029'
 '0.004'      | '1%'      | '1W'     | '1206LF'  | 'EMPTY'  | 'CS+0048F200'(!)        = ''              | ''                 | 'CS+0048F200'           |'R1206XA'| '(SMR1206AW)'                  | '0.004'   | '1%'    | '1W'     | 'IO'       | 'RES CHIP 0.004 1W +-1%(1206)'                     | 'CHIP1206'     | ''          | ''            | '20121029'
 '255'        | '1%'      | '1/16W'  | '0402LF'  | 'CHIP'   | 'CS12552FB18'(!)        = 'End of Design' | 'Comp-Approve'     | 'CS12552FB18'           |'R0402'| '(R0402-0201)'                 | '255'     | '1%'    | '1/16W'  | 'DISCRETE' | 'RES CHIP 255 1/16W +-1%(0402)'                    | 'CHIP0402'     | ''          | ''            | '20121031'
 '255'        | '1%'      | '1/16W'  | '0402LF'  | 'EMPTY'  | 'CS12552FB18'(!)        = 'End of Design' | 'Comp-Approve'     | 'CS12552FB18'           |'R0402'| '(R0402-0201)'                 | '255'     | '1%'    | '1/16W'  | 'IO'       | 'RES CHIP 255 1/16W +-1%(0402)'                    | 'CHIP0402'     | ''          | ''            | '20121031'
 '261K'       | '1%'      | '1/16'   | '0402LF'  | 'CHIP'   | 'CS42612FB00'(!)        = 'End of Design' | 'Comp-Approve'     | 'CS42612FB00'           |'R0402'| '(R0402-0201)'                 | '261K'    | '1%'    | '1/16'   | 'DISCRETE' | 'RES CHIP 261K 1/16 +-1%(0402)'                    | 'CHIP0402'     | ''          | ''            | '20121114'
 '261K'       | '1%'      | '1/16'   | '0402LF'  | 'EMPTY'  | 'CS42612FB00'(!)        = 'End of Design' | 'Comp-Approve'     | 'CS42612FB00'           |'R0402'| '(R0402-0201)'                 | '261K'    | '1%'    | '1/16'   | 'IO'       | 'RES CHIP 261K 1/16 +-1%(0402)'                    | 'CHIP0402'     | ''          | ''            | '20121114'
 '680K'       | '1%'      | '1/16'   | '0402LF'  | 'CHIP'   | 'CS46802FB00'(!)        = 'End of Design' | 'Comp-Approve'     | 'CS46802FB00'           |'R0402'| '(R0402-0201)'                 | '680K'    | '1%'    | '1/16'   | 'DISCRETE' | 'RES CHIP 680K 1/16W +-1%(0402)'                   | 'CHIP0402'     | ''          | ''            | '20121115'
 '680K'       | '1%'      | '1/16'   | '0402LF'  | 'EMPTY'  | 'CS46802FB00'(!)        = 'End of Design' | 'Comp-Approve'     | 'CS46802FB00'           |'R0402'| '(R0402-0201)'                 | '680K'    | '1%'    | '1/16'   | 'IO'       | 'RES CHIP 680K 1/16W +-1%(0402)'                   | 'CHIP0402'     | ''          | ''            | '20121115'
 '649'        | '1%'      | '1/16W'  | '0402LF'  | 'CHIP'   | 'CS16492FB13'(!)        = 'End of Design' | 'Comp-Approve'     | 'CS16492FB13'           |'R0402'| '(R0402-0201)'                 | '649'     | '1%'    | '1/16W'  | 'DISCRETE' | 'RES CHIP 649 1/16W +-1%(0402) -EP'                | 'CHIP0402'     | ''          | ''            | '20121120'
 '649'        | '1%'      | '1/16W'  | '0402LF'  | 'EMPTY'  | 'CS16492FB13'(!)        = 'End of Design' | 'Comp-Approve'     | 'CS16492FB13'           |'R0402'| '(R0402-0201)'                 | '649'     | '1%'    | '1/16W'  | 'IO'       | 'RES CHIP 649 1/16W +-1%(0402) -EP'                | 'CHIP0402'     | ''          | ''            | '20121120'
 '160'        | '1%'      | '1/16W'  | '0402LF'  | 'CHIP'   | 'CS11602FB00'(!)        = 'End of Design' | 'Comp-Approve'     | 'CS11602FB00'           |'R0402'| '(R0402-0201)'                 | '160'     | '1%'    | '1/16W'  | 'DISCRETE' | 'RES CHIP 160 1/16W +-1%(0402)'                    | 'CHIP0402'     | ''          | ''            | '20121122'
 '160'        | '1%'      | '1/16W'  | '0402LF'  | 'EMPTY'  | 'CS11602FB00'(!)        = 'End of Design' | 'Comp-Approve'     | 'CS11602FB00'           |'R0402'| '(R0402-0201)'                 | '160'     | '1%'    | '1/16W'  | 'IO'       | 'RES CHIP 160 1/16W +-1%(0402)'                    | 'CHIP0402'     | ''          | ''            | '20121122'
 '390'        | '1%'      | '1/10W'  | '0603LF'  | 'CHIP'   | 'CS13903F919'(!)        = ''              | ''                 | 'CS13903F919'           |'R0603'| '(SMR0603AW)'                  | '390'     | '1%'    | '1/10W'  | 'DISCRETE' | 'RES CHIP 390 1/10W +-1%(0603)'                    | 'CHIP0603'     | ''          | ''            | '20121128'
 '390'        | '1%'      | '1/10W'  | '0603LF'  | 'EMPTY'  | 'CS13903F919'(!)        = ''              | ''                 | 'CS13903F919'           |'R0603'| '(SMR0603AW)'                  | '390'     | '1%'    | '1/10W'  | 'IO'       | 'RES CHIP 390 1/10W +-1%(0603)'                    | 'CHIP0603'     | ''          | ''            | '20121128'
 '82.5K'      | '1%'      | '1/16W'  | '0402LF'  | 'CHIP'   | 'CS38252FB17'(!)        = 'End of Design' | 'Comp-Approve'     | 'CS38252FB17'           |'R0402'| '(R0402-0201)'                 | '82.5K'   | '1%'    | '1/16W'  | 'DISCRETE' | 'RES CHIP 82.5K 1/16W +-1%(0402)'                  | 'CHIP0402'     | ''          | ''            | '20121128'
 '82.5K'      | '1%'      | '1/16W'  | '0402LF'  | 'EMPTY'  | 'CS38252FB17'(!)        = 'End of Design' | 'Comp-Approve'     | 'CS38252FB17'           |'R0402'| '(R0402-0201)'                 | '82.5K'   | '1%'    | '1/16W'  | 'IO'       | 'RES CHIP 82.5K 1/16W +-1%(0402)'                  | 'CHIP0402'     | ''          | ''            | '20121128'
 '604K'       | '1%'      | '1/16W'  | '0402LF'  | 'CHIP'   | 'CS46042FB11'(!)        = 'End of Design' | 'Comp-Approve'     | 'CS46042FB11'           |'R0402'| '(R0402-0201)'                 | '604K'    | '1%'    | '1/16W'  | 'DISCRETE' | 'RES CHIP 604K 1/16W +-1%(0402)'                   | 'CHIP0402'     | ''          | ''            | '20121128'
 '604K'       | '1%'      | '1/16W'  | '0402LF'  | 'EMPTY'  | 'CS46042FB11'(!)        = 'End of Design' | 'Comp-Approve'     | 'CS46042FB11'           |'R0402'| '(R0402-0201)'                 | '604K'    | '1%'    | '1/16W'  | 'IO'       | 'RES CHIP 604K 1/16W +-1%(0402)'                   | 'CHIP0402'     | ''          | ''            | '20121128'
 '10.5K'      | '1%'      | '1/16W'  | '0402LF'  | 'CHIP'   | 'CS31052FB02'(!)        = 'End of Design' | 'Comp-Approve'     | 'CS31052FB02'           |'R0402'| '(R0402-0201)'                 | '10.5K'   | '1%'    | '1/16W'  | 'DISCRETE' | 'RES CHIP 10.5K 1/16W +-1%( 0402)'                 | 'CHIP0402'     | ''          | ''            | '20121204'
 '10.5K'      | '1%'      | '1/16W'  | '0402LF'  | 'EMPTY'  | 'CS31052FB02'(!)        = 'End of Design' | 'Comp-Approve'     | 'CS31052FB02'           |'R0402'| '(R0402-0201)'                 | '10.5K'   | '1%'    | '1/16W'  | 'IO'       | 'RES CHIP 10.5K 1/16W +-1%( 0402)'                 | 'CHIP0402'     | ''          | ''            | '20121204'
 '34.8K'      | '1%'      | '1/16W'  | '0402LF'  | 'CHIP'   | 'CS33482FB22'(!)        = 'End of Design' | 'Comp-Approve'     | 'CS33482FB22'           |'R0402'| '(R0402-0201)'                 | '34.8K'   | '1%'    | '1/16W'  | 'DISCRETE' | 'RES CHIP 34.8K 1/16W +-1% (0402)EP'               | 'CHIP0402'     | ''          | ''            | '20121204'
 '34.8K'      | '1%'      | '1/16W'  | '0402LF'  | 'EMPTY'  | 'CS33482FB22'(!)        = 'End of Design' | 'Comp-Approve'     | 'CS33482FB22'           |'R0402'| '(R0402-0201)'                 | '34.8K'   | '1%'    | '1/16W'  | 'IO'       | 'RES CHIP 34.8K 1/16W +-1% (0402)EP'               | 'CHIP0402'     | ''          | ''            | '20121204'
 '2.2'        | '5%'      | '1/2W'   | '1210LF'  | 'CHIP'   | 'CS-2207J311'(!)        = ''              | ''                 | 'CS-2207J311'           |'R1210'| '(SMR1210AW)'                  | '2.2'     | '5%'    | '1/2W'   | 'DISCRETE' | 'RES CHIP 2.2 1/2W +-5%(1210)'                     | 'CHIP1210'     | ''          | ''            | '20121210'
 '2.2'        | '5%'      | '1/2W'   | '1210LF'  | 'EMPTY'  | 'CS-2207J311'(!)        = ''              | ''                 | 'CS-2207J311'           |'R1210'| '(SMR1210AW)'                  | '2.2'     | '5%'    | '1/2W'   | 'IO'       | 'RES CHIP 2.2 1/2W +-5%(1210)'                     | 'CHIP1210'     | ''          | ''            | '20121210'
 '62'         | '1%'      | '1/16W'  | '0402LF'  | 'CHIP'   | 'CS06202FB13'(!)        = 'End of Design' | 'Comp-Approve'     | 'CS06202FB13'           |'R0402'| '(R0402-0201)'                 | '62'      | '1%'    | '1/16W'  | 'DISCRETE' | 'RES CHIP 62 1/16W +-1%(0402)'                     | 'CHIP0402'     | ''          | ''            | '20121216'
 '62'         | '1%'      | '1/16W'  | '0402LF'  | 'EMPTY'  | 'CS06202FB13'(!)        = 'End of Design' | 'Comp-Approve'     | 'CS06202FB13'           |'R0402'| '(R0402-0201)'                 | '62'      | '1%'    | '1/16W'  | 'IO'       | 'RES CHIP 62 1/16W +-1%(0402)'                     | 'CHIP0402'     | ''          | ''            | '20121216'
 '62'         | '5%'      | '1/16W'  | '0402LF'  | 'CHIP'   | 'CS06202JB15'(!)        = ''              | ''                 | 'CS06202JB15'           |'R0402'| '(R0402-0201)'                 | '62'      | '5%'    | '1/16W'  | 'DISCRETE' | 'RES CHIP 62 1/16W +-5%(0402)'                     | 'CHIP0402'     | ''          | ''            | '20121216'
 '62'         | '5%'      | '1/16W'  | '0402LF'  | 'EMPTY'  | 'CS06202JB15'(!)        = ''              | ''                 | 'CS06202JB15'           |'R0402'| '(R0402-0201)'                 | '62'      | '5%'    | '1/16W'  | 'IO'       | 'RES CHIP 62 1/16W +-5%(0402)'                     | 'CHIP0402'     | ''          | ''            | '20121216'
 '33.2K'      | '1%'      | '1/16W'  | '0402LF'  | 'CHIP'   | 'CS33322FB13'(!)        = 'End of Design' | 'Comp-Approve'     | 'CS33322FB13'           |'R0402'| '(R0402-0201)'                 | '33.2K'   | '1%'    | '1/16W'  | 'DISCRETE' | 'RES CHIP 33.2K 1/16W +-1% (0402)'                 | 'CHIP0402'     | ''          | ''            | '20121216'
 '33.2K'      | '1%'      | '1/16W'  | '0402LF'  | 'EMPTY'  | 'CS33322FB13'(!)        = 'End of Design' | 'Comp-Approve'     | 'CS33322FB13'           |'R0402'| '(R0402-0201)'                 | '33.2K'   | '1%'    | '1/16W'  | 'IO'       | 'RES CHIP 33.2K 1/16W +-1% (0402)'                 | 'CHIP0402'     | ''          | ''            | '20121216'
 '51'         | '5%'      | '1/8W'   | '0805LF'  | 'CHIP'   | 'CS05104JA12'(!)        = ''              | ''                 | 'CS05104JA12'           |'R0805'| '(SMR0805AW)'                  | '51'      | '5%'    | '1/8W'   | 'DISCRETE' | 'RES CHIP 51 1/8W +-5% (0805)'                     | 'CHIP0805'     | ''          | ''            | '20121216'
 '51'         | '5%'      | '1/8W'   | '0805LF'  | 'EMPTY'  | 'CS05104JA12'(!)        = ''              | ''                 | 'CS05104JA12'           |'R0805'| '(SMR0805AW)'                  | '51'      | '5%'    | '1/8W'   | 'IO'       | 'RES CHIP 51 1/8W +-5% (0805)'                     | 'CHIP0805'     | ''          | ''            | '20121216'
 '0.2'        | '1%'      | '1/10W'  | '0603LF'  | 'CHIP'   | 'CS+0203F900'(!)        = ''              | ''                 | 'CS+0203F900'           |'R0603'| '(SMR0603AW)'                  | '0.2'     | '1%'    | '1/10W'  | 'DISCRETE' | 'RES CHIP 0.2 1/10W +-1%(0603)'                    | 'CHIP0603'     | ''          | ''            | '20121216'
 '0.2'        | '1%'      | '1/10W'  | '0603LF'  | 'EMPTY'  | 'CS+0203F900'(!)        = ''              | ''                 | 'CS+0203F900'           |'R0603'| '(SMR0603AW)'                  | '0.2'     | '1%'    | '1/10W'  | 'IO'       | 'RES CHIP 0.2 1/10W +-1%(0603)'                    | 'CHIP0603'     | ''          | ''            | '20121216'
 '510'        | '5%'      | '1/10W'  | '0603LF'  | 'CHIP'   | 'CS15103J933'(!)        = ''              | ''                 | 'CS15103J933'           |'R0603'| '(SMR0603AW)'                  | '510'     | '5%'    | '1/10W'  | 'DISCRETE' | 'RES CHIP 510 1/10W +-5%(0603)'                    | 'CHIP0603'     | ''          | ''            | '20121218'
 '510'        | '5%'      | '1/10W'  | '0603LF'  | 'EMPTY'  | 'CS15103J933'(!)        = ''              | ''                 | 'CS15103J933'           |'R0603'| '(SMR0603AW)'                  | '510'     | '5%'    | '1/10W'  | 'IO'       | 'RES CHIP 510 1/10W +-5%(0603)'                    | 'CHIP0603'     | ''          | ''            | '20121218'
 '0.01'       | '1%'      | '1W'     | '2010LF'  | 'CHIP'   | 'CS+0108FJ00'(!)        = ''              | ''                 | 'CS+0108FJ00'           |'R2010'| '(SMR2010AW)'                  | '0.01'    | '1%'    | '1W'     | 'DISCRETE' | 'RES CHIP 0.01 1W +-1%(2010)'                      | 'CHIP2010'     | ''          | ''            | '20121221'
 '0.01'       | '1%'      | '1W'     | '2010LF'  | 'EMPTY'  | 'CS+0108FJ00'(!)        = ''              | ''                 | 'CS+0108FJ00'           |'R2010'| '(SMR2010AW)'                  | '0.01'    | '1%'    | '1W'     | 'IO'       | 'RES CHIP 0.01 1W +-1%(2010)'                      | 'CHIP2010'     | ''          | ''            | '20121221'
 '0.015'      | '1%'      | '3/4W'   | '2010LF'  | 'CHIP'   | 'CS+015BFJ21'(!)        = ''              | ''                 | 'CS+015BFJ21'           |'R2010'| '(SMR2010AW)'                  | '0.015'   | '1%'    | '3/4W'   | 'DISCRETE' | 'RES CHIP 0.015 3/4W +-1%(2010)'                   | 'CHIP2010'     | ''          | ''            | '20121221'
 '0.015'      | '1%'      | '3/4W'   | '2010LF'  | 'EMPTY'  | 'CS+015BFJ21'(!)        = ''              | ''                 | 'CS+015BFJ21'           |'R2010'| '(SMR2010AW)'                  | '0.015'   | '1%'    | '3/4W'   | 'IO'       | 'RES CHIP 0.015 3/4W +-1%(2010)'                   | 'CHIP2010'     | ''          | ''            | '20121221'
 '64.9'       | '1%'      | '1/16W'  | '0402LF'  | 'CHIP'   | 'CS06492FB03'(!)        = ''              | ''                 | 'CS06492FB03'           |'R0402'| '(R0402-0201)'                 | '64.9'    | '1%'    | '1/16W'  | 'DISCRETE' | 'RES CHIP 64.9 1/16W +-1%(0402)'                   | 'CHIP0402'     | ''          | ''            | '20121222'
 '64.9'       | '1%'      | '1/16W'  | '0402LF'  | 'EMPTY'  | 'CS06492FB03'(!)        = ''              | ''                 | 'CS06492FB03'           |'R0402'| '(R0402-0201)'                 | '64.9'    | '1%'    | '1/16W'  | 'IO'       | 'RES CHIP 64.9 1/16W +-1%(0402)'                   | 'CHIP0402'     | ''          | ''            | '20121222'
 '665'        | '1%'      | '1/16W'  | '0402LF'  | 'CHIP'   | 'CS16652FB04'(!)        = 'End of Design' | 'Comp-Approve'     | 'CS16652FB04'           |'R0402'| '(R0402-0201)'                 | '665'     | '1%'    | '1/16W'  | 'DISCRETE' | 'RES CHIP 665 1/16W +-1%(0402) L-F'                | 'CHIP0402'     | ''          | ''            | '20121222'
 '665'        | '1%'      | '1/16W'  | '0402LF'  | 'EMPTY'  | 'CS16652FB04'(!)        = 'End of Design' | 'Comp-Approve'     | 'CS16652FB04'           |'R0402'| '(R0402-0201)'                 | '665'     | '1%'    | '1/16W'  | 'IO'       | 'RES CHIP 665 1/16W +-1%(0402) L-F'                | 'CHIP0402'     | ''          | ''            | '20121222'
 '30.1'       | '1%'      | '1/16W'  | '0402LF'  | 'CHIP'   | 'CS03012FB21'(!)        = 'End of Design' | 'Comp-Approve'     | 'CS03012FB21'           |'R0402'| '(R0402-0201)'                 | '30.1'    | '1%'    | '1/16W'  | 'DISCRETE' | 'RES CHIP 30.1 1/16W +-1%(0402)'                   | 'CHIP0402'     | ''          | ''            | '20121224'
 '30.1'       | '1%'      | '1/16W'  | '0402LF'  | 'EMPTY'  | 'CS03012FB21'(!)        = 'End of Design' | 'Comp-Approve'     | 'CS03012FB21'           |'R0402'| '(R0402-0201)'                 | '30.1'    | '1%'    | '1/16W'  | 'IO'       | 'RES CHIP 30.1 1/16W +-1%(0402)'                   | 'CHIP0402'     | ''          | ''            | '20121224'
 '0.002'      | '1%'      | '1W'     | '2512LF'  | 'CHIP'   | 'CS+0028F115'(!)        = ''              | ''                 | 'CS+0028F115'           |'R2512XC'| '(SMR2512AW)'                  | '0.002'   | '1%'    | '1W'     | 'DISCRETE' | 'RES CHIP 0.002 1W +-1%(2512)'                     | 'CHIP2512'     | ''          | ''            | '20121225'
 '0.002'      | '1%'      | '1W'     | '2512LF'  | 'EMPTY'  | 'CS+0028F115'(!)        = ''              | ''                 | 'CS+0028F115'           |'R2512XC'| '(SMR2512AW)'                  | '0.002'   | '1%'    | '1W'     | 'IO'       | 'RES CHIP 0.002 1W +-1%(2512)'                     | 'CHIP2512'     | ''          | ''            | '20121225'
 '4.99'       | '1%'      | '1/16W'  | '0402LF'  | 'CHIP'   | 'CS-4992FB25'(!)        = 'End of Design' | 'Comp-Approve'     | 'CS-4992FB25'           |'R0402'| '(R0402-0201)'                 | '4.99'    | '1%'    | '1/16W'  | 'DISCRETE' | 'RES CHIP 4.99 1/16W +-1% (0402)'                  | 'CHIP0402'     | ''          | ''            | '20121228'
 '4.99'       | '1%'      | '1/16W'  | '0402LF'  | 'EMPTY'  | 'CS-4992FB25'(!)        = 'End of Design' | 'Comp-Approve'     | 'CS-4992FB25'           |'R0402'| '(R0402-0201)'                 | '4.99'    | '1%'    | '1/16W'  | 'IO'       | 'RES CHIP 4.99 1/16W +-1% (0402)'                  | 'CHIP0402'     | ''          | ''            | '20121228'
 '64.9'       | '1%'      | '1/16W'  | '0402LF'  | 'CHIP'   | 'CS06492FB11'(!)        = 'End of Design' | 'Comp-Approve'     | 'CS06492FB11'           |'R0402'| '(R0402-0201)'                 | '64.9'    | '1%'    | '1/16W'  | 'DISCRETE' | 'RES CHIP 64.9 1/16W +-1% (0402)'                  | 'CHIP0402'     | ''          | ''            | '20130105'
 '64.9'       | '1%'      | '1/16W'  | '0402LF'  | 'EMPTY'  | 'CS06492FB11'(!)        = 'End of Design' | 'Comp-Approve'     | 'CS06492FB11'           |'R0402'| '(R0402-0201)'                 | '64.9'    | '1%'    | '1/16W'  | 'IO'       | 'RES CHIP 64.9 1/16W +-1% (0402)'                  | 'CHIP0402'     | ''          | ''            | '20130105'
 '160K'       | '1%'      | '1/16W'  | '0402LF'  | 'CHIP'   | 'CS41602FB00'(!)        = 'End of Design' | 'Comp-Approve'     | 'CS41602FB00'           |'R0402'| '(R0402-0201)'                 | '160K'    | '1%'    | '1/16W'  | 'DISCRETE' | 'RES CHIP 160K (1/16W,+-1%,0402)'                  | 'CHIP0402'     | ''          | ''            | '20130108'
 '160K'       | '1%'      | '1/16W'  | '0402LF'  | 'EMPTY'  | 'CS41602FB00'(!)        = 'End of Design' | 'Comp-Approve'     | 'CS41602FB00'           |'R0402'| '(R0402-0201)'                 | '160K'    | '1%'    | '1/16W'  | 'IO'       | 'RES CHIP 160K (1/16W,+-1%,0402)'                  | 'CHIP0402'     | ''          | ''            | '20130108'
 '35.7'       | '1%'      | '1/16W'  | '0402LF'  | 'CHIP'   | 'CS03572FB01'(!)        = 'End of Design' | 'Comp-Approve'     | 'CS03572FB01'           |'R0402'| '(R0402-0201)'                 | '35.7'    | '1%'    | '1/16W'  | 'DISCRETE' | 'RES CHIP 35.7 1/16W +-1%(0402)'                   | 'CHIP0402'     | ''          | ''            | '20130108'
 '35.7'       | '1%'      | '1/16W'  | '0402LF'  | 'EMPTY'  | 'CS03572FB01'(!)        = 'End of Design' | 'Comp-Approve'     | 'CS03572FB01'           |'R0402'| '(R0402-0201)'                 | '35.7'    | '1%'    | '1/16W'  | 'IO'       | 'RES CHIP 35.7 1/16W +-1%(0402)'                   | 'CHIP0402'     | ''          | ''            | '20130108'
 '140K'       | '1%'      | '1/16W'  | '0402LF'  | 'CHIP'   | 'CS41402FB14'(!)        = 'End of Design' | 'Comp-Approve'     | 'CS41402FB14'           |'R0402'| '(R0402-0201)'                 | '140K'    | '1%'    | '1/16W'  | 'DISCRETE' | 'RES CHIP 140K 1/16W +-1%(0402)'                   | 'CHIP0402'     | ''          | ''            | '20130108'
 '140K'       | '1%'      | '1/16W'  | '0402LF'  | 'EMPTY'  | 'CS41402FB14'(!)        = 'End of Design' | 'Comp-Approve'     | 'CS41402FB14'           |'R0402'| '(R0402-0201)'                 | '140K'    | '1%'    | '1/16W'  | 'IO'       | 'RES CHIP 140K 1/16W +-1%(0402)'                   | 'CHIP0402'     | ''          | ''            | '20130108'
 '69.8K'      | '1%'      | '1/10W'  | '0603LF'  | 'CHIP'   | 'CS36983F917'(!)        = 'End of Design' | 'Comp-Approve'     | 'CS36983F917'           |'R0603'| '(SMR0603AW)'                  | '69.8K'   | '1%'    | '1/10W'  | 'DISCRETE' | 'RESISTOR CHIP 69.8K 1/10W +-1% (0603)'            | 'CHIP0603'     | ''          | ''            | '20130114'
 '69.8K'      | '1%'      | '1/10W'  | '0603LF'  | 'EMPTY'  | 'CS36983F917'(!)        = 'End of Design' | 'Comp-Approve'     | 'CS36983F917'           |'R0603'| '(SMR0603AW)'                  | '69.8K'   | '1%'    | '1/10W'  | 'IO'       | 'RESISTOR CHIP 69.8K 1/10W +-1% (0603)'            | 'CHIP0603'     | ''          | ''            | '20130114'
 '6.65K'      | '1%'      | '1/16W'  | '0402LF'  | 'CHIP'   | 'TMP_QCS26652FB06'(!)   = 'End of Design' | 'Comp-Approve'     | 'CS26652FB06'           |'R0402'| '(R0402-0201)'                 | '6.65K'   | '1%'    | '1/16W'  | 'DISCRETE' | '6.65Kohm 0402'                                    | 'CHIP0402'     | ''          | ''            | ''        
 '6.65K'      | '1%'      | '1/16W'  | '0402LF'  | 'EMPTY'  | 'TMP_QCS26652FB06'(!)   = 'End of Design' | 'Comp-Approve'     | 'CS26652FB06'           |'R0402'| '(R0402-0201)'                 | '6.65K'   | '1%'    | '1/16W'  | 'DISCRETE' | '6.65Kohm 0402'                                    | 'CHIP0402'     | ''          | ''            | ''        
 '5.23K'      | '1%'      | '1/16W'  | '0402LF'  | 'CHIP'   | 'CS25232FB18'(!)        = 'End of Design' | 'Comp-Approve'     | 'CS25232FB18'           |'R0402'| '(R0402-0201)'                 | '5.23K'   | '1%'    | '1/16W'  | 'DISCRETE' | 'RES CHIP 5.23K 1/16W +-1%(0402)'                  | 'CHIP0402'     | ''          | ''            | '20130123'
 '5.23K'      | '1%'      | '1/16W'  | '0402LF'  | 'EMPTY'  | 'CS25232FB18'(!)        = 'End of Design' | 'Comp-Approve'     | 'CS25232FB18'           |'R0402'| '(R0402-0201)'                 | '5.23K'   | '1%'    | '1/16W'  | 'IO'       | 'RES CHIP 5.23K 1/16W +-1%(0402)'                  | 'CHIP0402'     | ''          | ''            | '20130123'
 '120K'       | '1%'      | '1/16W'  | '0402LF'  | 'CHIP'   | 'CS41202FB17'(!)        = 'End of Design' | 'Comp-Approve'     | 'CS41202FB17'           |'R0402'| '(R0402-0201)'                 | '120K'    | '1%'    | '1/16W'  | 'DISCRETE' | 'RES CHIP 120K 1/16W +-1%( 0402)'                  | 'CHIP0402'     | ''          | ''            | '20130218'
 '120K'       | '1%'      | '1/16W'  | '0402LF'  | 'EMPTY'  | 'CS41202FB17'(!)        = 'End of Design' | 'Comp-Approve'     | 'CS41202FB17'           |'R0402'| '(R0402-0201)'                 | '120K'    | '1%'    | '1/16W'  | 'IO'       | 'RES CHIP 120K 1/16W +-1%( 0402)'                  | 'CHIP0402'     | ''          | ''            | '20130218'
 '2.2K'       | '1%'      | '1/10W'  | '0603LF'  | 'CHIP'   | 'CS22203F912'(!)        = 'End of Design' | 'Comp-Approve'     | 'CS22203F912'           |'R0603'| '(SMR0603AW)'                  | '2.2K'    | '1%'    | '1/10W'  | 'DISCRETE' | 'RES CHIP 2.2K 1/10W.+-1%(0603)'                   | 'CHIP0603'     | ''          | ''            | '20130228'
 '2.2K'       | '1%'      | '1/10W'  | '0603LF'  | 'EMPTY'  | 'CS22203F912'(!)        = 'End of Design' | 'Comp-Approve'     | 'CS22203F912'           |'R0603'| '(SMR0603AW)'                  | '2.2K'    | '1%'    | '1/10W'  | 'IO'       | 'RES CHIP 2.2K 1/10W.+-1%(0603)'                   | 'CHIP0603'     | ''          | ''            | '20130228'
 '2.26K'      | '1%'      | '1/10W'  | '0603LF'  | 'CHIP'   | 'CS22263F928'(!)        = 'End of Design' | 'Comp-Approve'     | 'CS22263F928'           |'R0603'| '(SMR0603AW)'                  | '2.26K'   | '1%'    | '1/10W'  | 'DISCRETE' | 'RES CHIP 2.26K 1/10W +-1%(0603)'                  | 'CHIP0603'     | ''          | ''            | '20130228'
 '2.26K'      | '1%'      | '1/10W'  | '0603LF'  | 'EMPTY'  | 'CS22263F928'(!)        = 'End of Design' | 'Comp-Approve'     | 'CS22263F928'           |'R0603'| '(SMR0603AW)'                  | '2.26K'   | '1%'    | '1/10W'  | 'IO'       | 'RES CHIP 2.26K 1/10W +-1%(0603)'                  | 'CHIP0603'     | ''          | ''            | '20130228'
 '1.43K'      | '1%'      | '1/16W'  | '0402LF'  | 'CHIP'   | 'CS21432FB00'(!)        = 'End of Design' | 'Comp-Approve'     | 'CS21432FB00'           |'R0402'| '(R0402-0201)'                 | '1.43K'   | '1%'    | '1/16W'  | 'DISCRETE' | 'RES CHIP 1.43K 1/16W +-1%(0402)'                  | 'CHIP0402'     | ''          | ''            | '20130306'
 '1.43K'      | '1%'      | '1/16W'  | '0402LF'  | 'EMPTY'  | 'CS21432FB00'(!)        = 'End of Design' | 'Comp-Approve'     | 'CS21432FB00'           |'R0402'| '(R0402-0201)'                 | '1.43K'   | '1%'    | '1/16W'  | 'IO'       | 'RES CHIP 1.43K 1/16W +-1%(0402)'                  | 'CHIP0402'     | ''          | ''            | '20130306'
 '60.4'       | '1%'      | '1/16W'  | '0402LF'  | 'CHIP'   | 'CS06042FB14'(!)        = 'End of Design' | 'Comp-Approve'     | 'CS06042FB14'           |'R0402'| '(R0402-0201)'                 | '60.4'    | '1%'    | '1/16W'  | 'DISCRETE' | 'RES CHIP 1.43K 1/16W +-1%(0402)'                  | 'CHIP0402'     | ''          | ''            | '20130319'
 '60.4'       | '1%'      | '1/16W'  | '0402LF'  | 'EMPTY'  | 'CS06042FB14'(!)        = 'End of Design' | 'Comp-Approve'     | 'CS06042FB14'           |'R0402'| '(R0402-0201)'                 | '60.4'    | '1%'    | '1/16W'  | 'IO'       | 'RES CHIP 1.43K 1/16W +-1%(0402)'                  | 'CHIP0402'     | ''          | ''            | '20130319'
 '0.0002'     | '1%'      | '5W'     | '5931LF'  | 'CHIP'   | 'TMP_TU1J_LJ_0322_1'(!) = ''              | ''                 | 'TMP_TU1J_LJ_0322_1'    |'R5931'| '(SMR5931AW)'                  | '0.0002'  | '1%'    | '5W'     | 'DISCRETE' | 'RES CHIP 0.0002 5W +-1%(5931)'                    | 'CHIP5931'     | ''          | ''            | '20130322'
 '0.0002'     | '1%'      | '5W'     | '5931LF'  | 'EMPTY'  | 'TMP_TU1J_LJ_0322_1'(!) = ''              | ''                 | 'TMP_TU1J_LJ_0322_1'    |'R5931'| '(SMR5931AW)'                  | '0.0002'  | '1%'    | '5W'     | 'IO'       | 'RES CHIP 0.0002 5W +-1%(5931)'                    | 'CHIP5931'     | ''          | ''            | '20130322'
 '221'        | '1%'      | '1/16W'  | '0402LF'  | 'CHIP'   | 'CS12212FB19'(!)        = 'End of Design' | 'Comp-Approve'     | 'CS12212FB19'           |'R0402'| '(R0402-0201)'                 | '221'     | '1%'    | '1/16W'  | 'DISCRETE' | 'RES CHIP 221 1/16W +-1%(0402)'                    | 'CHIP0402'     | ''          | ''            | '20130323'
 '221'        | '1%'      | '1/16W'  | '0402LF'  | 'EMPTY'  | 'CS12212FB19'(!)        = 'End of Design' | 'Comp-Approve'     | 'CS12212FB19'           |'R0402'| '(R0402-0201)'                 | '221'     | '1%'    | '1/16W'  | 'IO'       | 'RES CHIP 221 1/16W +-1%(0402)'                    | 'CHIP0402'     | ''          | ''            | '20130323'
 '243'        | '1%'      | '1/16W'  | '0402LF'  | 'CHIP'   | 'CS12432FB15'(!)        = 'End of Design' | 'Comp-Approve'     | 'CS12432FB15'           |'R0402'| '(R0402-0201)'                 | '243'     | '1%'    | '1/16W'  | 'DISCRETE' | 'RES CHIP 243 1/16W +-1% (0402)'                   | 'CHIP0402'     | ''          | ''            | '20130327'
 '243'        | '1%'      | '1/16W'  | '0402LF'  | 'EMPTY'  | 'CS12432FB15'(!)        = 'End of Design' | 'Comp-Approve'     | 'CS12432FB15'           |'R0402'| '(R0402-0201)'                 | '243'     | '1%'    | '1/16W'  | 'IO'       | 'RES CHIP 243 1/16W +-1% (0402)'                   | 'CHIP0402'     | ''          | ''            | '20130327'
 '10'         | '5%'      | '1/8W'   | '0805LF'  | 'CHIP'   | 'CS01004JA42'(!)        = ''              | ''                 | 'CS01004JA42'           |'R0805'| '(SMR0805AW)'                  | '10'      | '5%'    | '1/8W'   | 'DISCRETE' | 'RES CHIP 10 1/8W +-5%(0805)'                      | 'CHIP0805'     | ''          | ''            | '20130401'
 '10'         | '5%'      | '1/8W'   | '0805LF'  | 'EMPTY'  | 'CS01004JA42'(!)        = ''              | ''                 | 'CS01004JA42'           |'R0805'| '(SMR0805AW)'                  | '10'      | '5%'    | '1/8W'   | 'IO'       | 'RES CHIP 10 1/8W +-5%(0805)'                      | 'CHIP0805'     | ''          | ''            | '20130401'
 '1.5K'       | '5%'      | '1/8W'   | '0805LF'  | 'CHIP'   | 'CS21504JA10'(!)        = 'End of Design' | 'End of Life'      | 'CS21504JA10'           |'R0805_EOL'| '(SMR0805AW)'                  | '1.5K'    | '5%'    | '1/8W'   | 'DISCRETE' | 'RES CHIP 1.5K 1/8W +-5%(0805)'                    | 'CHIP0805'     | ''          | ''            | '20130401'
 '1.5K'       | '5%'      | '1/8W'   | '0805LF'  | 'EMPTY'  | 'CS21504JA10'(!)        = 'End of Design' | 'End of Life'      | 'CS21504JA10'           |'R0805_EOL'| '(SMR0805AW)'                  | '1.5K'    | '5%'    | '1/8W'   | 'IO'       | 'RES CHIP 1.5K 1/8W +-5%(0805)'                    | 'CHIP0805'     | ''          | ''            | '20130401'
 '1.5M'       | '1%'      | '1/16W'  | '0402LF'  | 'CHIP'   | 'CS51502FB00'(!)        = 'End of Design' | 'Comp-Approve'     | 'CS51502FB00'           |'R0402'| '(R0402-0201)'                 | '1.5M'    | '1%'    | '1/16W'  | 'DISCRETE' | 'RES CHIP 1.5M 1/16W +-1%(0402)'                   | 'CHIP0402'     | ''          | ''            | '20130411'
 '1.5M'       | '1%'      | '1/16W'  | '0402LF'  | 'EMPTY'  | 'CS51502FB00'(!)        = 'End of Design' | 'Comp-Approve'     | 'CS51502FB00'           |'R0402'| '(R0402-0201)'                 | '1.5M'    | '1%'    | '1/16W'  | 'IO'       | 'RES CHIP 1.5M 1/16W +-1%(0402)'                   | 'CHIP0402'     | ''          | ''            | '20130411'
 '3.0M'       | '1%'      | '1/16W'  | '0402LF'  | 'CHIP'   | 'CS53002FB00'(!)        = 'End of Design' | 'Comp-Release Qty' | 'CS53002FB00'           |'R0402'| '(R0402-0201)'                 | '3.0M'    | '1%'    | '1/16W'  | 'DISCRETE' | 'RES CHIP 3.0M 1/16W +-1%(0402)'                   | 'CHIP0402'     | ''          | ''            | '20130411'
 '3.0M'       | '1%'      | '1/16W'  | '0402LF'  | 'EMPTY'  | 'CS53002FB00'(!)        = 'End of Design' | 'Comp-Release Qty' | 'CS53002FB00'           |'R0402'| '(R0402-0201)'                 | '3.0M'    | '1%'    | '1/16W'  | 'IO'       | 'RES CHIP 3.0M 1/16W +-1%(0402)'                   | 'CHIP0402'     | ''          | ''            | '20130411'
 '2.94K'      | '1%'      | '1/16W'  | '0402LF'  | 'CHIP'   | 'CS22942FB01'(!)        = 'End of Design' | 'Comp-Approve'     | 'CS22942FB01'           |'R0402'| '(R0402-0201)'                 | '2.94K'   | '1%'    | '1/16W'  | 'DISCRETE' | 'RES CHIP 2.94K 1/16W +-1%(0402)'                  | 'CHIP0402'     | ''          | ''            | '20130411'
 '2.94K'      | '1%'      | '1/16W'  | '0402LF'  | 'EMPTY'  | 'CS22942FB01'(!)        = 'End of Design' | 'Comp-Approve'     | 'CS22942FB01'           |'R0402'| '(R0402-0201)'                 | '2.94K'   | '1%'    | '1/16W'  | 'IO'       | 'RES CHIP 2.94K 1/16W +-1%(0402)'                  | 'CHIP0402'     | ''          | ''            | '20130411'
 '44.2'       | '1%'      | '1/16W'  | '0402LF'  | 'CHIP'   | 'CS04422FB14'(!)        = 'End of Design' | 'Comp-Approve'     | 'CS04422FB14'           |'R0402'| '(R0402-0201)'                 | '44.2'    | '1%'    | '1/16W'  | 'DISCRETE' | 'RES CHIP 44.2 1/16W +-1%(0402)'                   | 'CHIP0402'     | ''          | ''            | '20130425'
 '44.2'       | '1%'      | '1/16W'  | '0402LF'  | 'EMPTY'  | 'CS04422FB14'(!)        = 'End of Design' | 'Comp-Approve'     | 'CS04422FB14'           |'R0402'| '(R0402-0201)'                 | '44.2'    | '1%'    | '1/16W'  | 'IO'       | 'RES CHIP 44.2 1/16W +-1%(0402)'                   | 'CHIP0402'     | ''          | ''            | '20130425'
 '3'          | '5%'      | '3/4W'   | '2010LF'  | 'CHIP'   | 'CS0030BJJ00'(!)        = ''              | ''                 | 'CS0030BJJ00'           |'R2010'| '(SMR2010AW)'                  | '3'       | '5%'    | '3/4W'   | 'DISCRETE' | 'RES CHIP 3 3/4W.+-5%(2010)'                       | 'CHIP2010'     | ''          | ''            | '20130429'
 '3'          | '5%'      | '3/4W'   | '2010LF'  | 'EMPTY'  | 'CS0030BJJ00'(!)        = ''              | ''                 | 'CS0030BJJ00'           |'R2010'| '(SMR2010AW)'                  | '3'       | '5%'    | '3/4W'   | 'IO'       | 'RES CHIP 3 3/4W.+-5%(2010)'                       | 'CHIP2010'     | ''          | ''            | '20130429'
 '1'          | '5%'      | '3/4W'   | '2010LF'  | 'CHIP'   | 'CS-100BJJ04'(!)        = ''              | ''                 | 'CS-100BJJ04'           |'R2010'| '(SMR2010AW)'                  | '1'       | '5%'    | '3/4W'   | 'DISCRETE' | 'RES CHIP 1 3/4W +5%(2010)L-F'                     | 'CHIP2010'     | ''          | ''            | '20130429'
 '1'          | '5%'      | '3/4W'   | '2010LF'  | 'EMPTY'  | 'CS-100BJJ04'(!)        = ''              | ''                 | 'CS-100BJJ04'           |'R2010'| '(SMR2010AW)'                  | '1'       | '5%'    | '3/4W'   | 'IO'       | 'RES CHIP 1 3/4W +5%(2010)L-F'                     | 'CHIP2010'     | ''          | ''            | '20130429'
 '432'        | '1%'      | '1/16W'  | '0402LF'  | 'CHIP'   | 'CS14322FB00'(!)        = 'End of Design' | 'Comp-Approve'     | 'CS14322FB00'           |'R0402'| '(R0402-0201)'                 | '432'     | '1%'    | '1/16W'  | 'DISCRETE' | 'RES CHIP 432 1/16W +-1%(0402)'                    | 'CHIP0402'     | ''          | ''            | '20130503'
 '432'        | '1%'      | '1/16W'  | '0402LF'  | 'EMPTY'  | 'CS14322FB00'(!)        = 'End of Design' | 'Comp-Approve'     | 'CS14322FB00'           |'R0402'| '(R0402-0201)'                 | '432'     | '1%'    | '1/16W'  | 'IO'       | 'RES CHIP 432 1/16W +-1%(0402)'                    | 'CHIP0402'     | ''          | ''            | '20130503'
 '348'        | '1%'      | '1/16W'  | '0402LF'  | 'CHIP'   | 'CS13482FB00'(!)        = 'End of Design' | 'Comp-Approve'     | 'CS13482FB00'           |'R0402'| '(R0402-0201)'                 | '348'     | '1%'    | '1/16W'  | 'DISCRETE' | 'RES CHIP 348 1/16W +-1%(0402)'                    | 'CHIP0402'     | ''          | ''            | '20130509'
 '348'        | '1%'      | '1/16W'  | '0402LF'  | 'EMPTY'  | 'CS13482FB00'(!)        = 'End of Design' | 'Comp-Approve'     | 'CS13482FB00'           |'R0402'| '(R0402-0201)'                 | '348'     | '1%'    | '1/16W'  | 'IO'       | 'RES CHIP 348 1/16W +-1%(0402)'                    | 'CHIP0402'     | ''          | ''            | '20130509'
 '2.7K'       | '5%'      | '1/16W'  | '0402LF'  | 'CHIP'   | 'CS22702JB16'(!)        = 'End of Design' | 'Comp-Approve'     | 'CS22702JB16'           |'R0402'| '(R0402-0201)'                 | '2.7K'    | '5%'    | '1/16W'  | 'DISCRETE' | 'RES CHIP 2.7K 1/16W +-5%(0402)'                   | 'CHIP0402'     | ''          | ''            | '20130509'
 '2.7K'       | '5%'      | '1/16W'  | '0402LF'  | 'EMPTY'  | 'CS22702JB16'(!)        = 'End of Design' | 'Comp-Approve'     | 'CS22702JB16'           |'R0402'| '(R0402-0201)'                 | '2.7K'    | '5%'    | '1/16W'  | 'IO'       | 'RES CHIP 2.7K 1/16W +-5%(0402)'                   | 'CHIP0402'     | ''          | ''            | '20130509'
 '3.01'       | '1%'      | '1/4W'   | '1206LF'  | 'CHIP'   | 'CS-3016F200'(!)        = ''              | ''                 | 'CS-3016F200'           |'R1206'| '(SMR1206AW)'                  | '3.01'    | '1%'    | '1/4W'   | 'DISCRETE' | 'RES CHIP 3.01 OHM 1/4W +-1%(1206)'                | 'CHIP1206'     | ''          | ''            | '20130521'
 '3.01'       | '1%'      | '1/4W'   | '1206LF'  | 'EMPTY'  | 'CS-3016F200'(!)        = ''              | ''                 | 'CS-3016F200'           |'R1206'| '(SMR1206AW)'                  | '3.01'    | '1%'    | '1/4W'   | 'IO'       | 'RES CHIP 3.01 OHM 1/4W +-1%(1206)'                | 'CHIP1206'     | ''          | ''            | '20130521'
 '196'        | '1%'      | '1/10W'  | '0603LF'  | 'CHIP'   | 'CS11963F911'(!)        = 'End of Design' | 'Comp-Approve'     | 'CS11963F911'           |'R0603'| '(SMR0603AW)'                  | '196'     | '1%'    | '1/10W'  | 'DISCRETE' | 'RES CHIP 196 1/10W +-1% (0603)'                   | 'CHIP0603'     | ''          | ''            | '20130529'
 '196'        | '1%'      | '1/10W'  | '0603LF'  | 'EMPTY'  | 'CS11963F911'(!)        = 'End of Design' | 'Comp-Approve'     | 'CS11963F911'           |'R0603'| '(SMR0603AW)'                  | '196'     | '1%'    | '1/10W'  | 'IO'       | 'RES CHIP 196 1/10W +-1% (0603)'                   | 'CHIP0603'     | ''          | ''            | '20130529'
 '0.001'      | '1%'      | '4W'     | '2725LF'  | 'CHIP'   | 'CS+001FFT00'(!)        = 'End of Design' | 'P/N Release'      | 'CS+001FFT00'           |'R2725'| '(SMR2725AW)'                  | '0.001'   | '1%'    | '4W'     | 'DISCRETE' | 'RES CHIP 0.001OHM 4W +-1% (2725)'                 | 'CHIP2725'     | ''          | ''            | '20130606'
 '0.001'      | '1%'      | '4W'     | '2725LF'  | 'EMPTY'  | 'CS+001FFT00'(!)        = 'End of Design' | 'P/N Release'      | 'CS+001FFT00'           |'R2725'| '(SMR2725AW)'                  | '0.001'   | '1%'    | '4W'     | 'IO'       | 'RES CHIP 0.001OHM 4W +-1% (2725)'                 | 'CHIP2725'     | ''          | ''            | '20130606'
 '240K'       | '1%'      | '1/16W'  | '0402LF'  | 'CHIP'   | 'CS42402FB17'(!)        = 'End of Design' | 'Comp-Approve'     | 'CS42402FB17'           |'R0402'| '(R0402-0201)'                 | '240K'    | '1%'    | '1/16W'  | 'DISCRETE' | 'RES CHIP 240K 1/16W +-1%(0402)'                   | 'CHIP0402'     | ''          | ''            | '20130611'
 '240K'       | '1%'      | '1/16W'  | '0402LF'  | 'EMPTY'  | 'CS42402FB17'(!)        = 'End of Design' | 'Comp-Approve'     | 'CS42402FB17'           |'R0402'| '(R0402-0201)'                 | '240K'    | '1%'    | '1/16W'  | 'IO'       | 'RES CHIP 240K 1/16W +-1%(0402)'                   | 'CHIP0402'     | ''          | ''            | '20130611'
 '1'          | '1%'      | '1/4W'   | '1206LF'  | 'CHIP'   | 'CS-1006F217'(!)        = ''              | ''                 | 'CS-1006F217'           |'R1206'| '(SMR1206AW)'                  | '1'       | '1%'    | '1/4W'   | 'DISCRETE' | 'RES CHIP 1 1/4W +-1%(1206) L-F'                   | 'CHIP1206'     | ''          | ''            | '20130611'
 '1'          | '1%'      | '1/4W'   | '1206LF'  | 'EMPTY'  | 'CS-1006F217'(!)        = ''              | ''                 | 'CS-1006F217'           |'R1206'| '(SMR1206AW)'                  | '1'       | '1%'    | '1/4W'   | 'IO'       | 'RES CHIP 1 1/4W +-1%(1206) L-F'                   | 'CHIP1206'     | ''          | ''            | '20130611'
 '0.0002'     | '1%'      | '4W'     | '2725LF'  | 'CHIP'   | 'CS0000FFT01'(!)        = ''              | ''                 | 'CS0000FFT01'           |'R2725'| '(SMR2725AW)'                  | '0.0002'  | '1%'    | '4W'     | 'DISCRETE' | 'RES CHIP 0.0002 4W +-1%(2725)H1.131'              | 'CHIP2725'     | ''          | ''            | '20130627'
 '0.0002'     | '1%'      | '4W'     | '2725LF'  | 'EMPTY'  | 'CS0000FFT01'(!)        = ''              | ''                 | 'CS0000FFT01'           |'R2725'| '(SMR2725AW)'                  | '0.0002'  | '1%'    | '4W'     | 'IO'       | 'RES CHIP 0.0002 4W +-1%(2725)H1.131'              | 'CHIP2725'     | ''          | ''            | '20130627'
 '91'         | '1%'      | '1/16W'  | '0402LF'  | 'CHIP'   | 'CS09102FB00'(!)        = 'End of Design' | 'Comp-Approve'     | 'CS09102FB00'           |'R0402'| '(R0402-0201)'                 | '91'      | '1%'    | '1/16W'  | 'DISCRETE' | 'RES CHIP 91 1/16W +-1%(0402)'                     | 'CHIP0402'     | ''          | ''            | '20130702'
 '91'         | '1%'      | '1/16W'  | '0402LF'  | 'EMPTY'  | 'CS09102FB00'(!)        = 'End of Design' | 'Comp-Approve'     | 'CS09102FB00'           |'R0402'| '(R0402-0201)'                 | '91'      | '1%'    | '1/16W'  | 'IO'       | 'RES CHIP 91 1/16W +-1%(0402)'                     | 'CHIP0402'     | ''          | ''            | '20130702'
 '499'        | '1%'      | '1/8W'   | '0805LF'  | 'CHIP'   | 'CS14994FA00'(!)        = ''              | ''                 | 'CS14994FA00'           |'R0805'| '(SMR0805AW)'                  | '499'     | '1%'    | '1/8W'   | 'DISCRETE' | 'RES CHIP 499 1/8W +-1%(0805)'                     | 'CHIP0805'     | ''          | ''            | '20130705'
 '499'        | '1%'      | '1/8W'   | '0805LF'  | 'EMPTY'  | 'CS14994FA00'(!)        = ''              | ''                 | 'CS14994FA00'           |'R0805'| '(SMR0805AW)'                  | '499'     | '1%'    | '1/8W'   | 'IO'       | 'RES CHIP 499 1/8W +-1%(0805)'                     | 'CHIP0805'     | ''          | ''            | '20130705'
 '510'        | '1%'      | '1/8W'   | '0805LF'  | 'CHIP'   | 'CS15104FA00'(!)        = 'End of Design' | 'Comp-Approve'     | 'CS15104FA00'           |'R0805'| '(SMR0805AW)'                  | '510'     | '1%'    | '1/8W'   | 'DISCRETE' | 'RES CHIP 510 1/8W +-1%(0805)'                     | 'CHIP0805'     | ''          | ''            | '20130705'
 '510'        | '1%'      | '1/8W'   | '0805LF'  | 'EMPTY'  | 'CS15104FA00'(!)        = 'End of Design' | 'Comp-Approve'     | 'CS15104FA00'           |'R0805'| '(SMR0805AW)'                  | '510'     | '1%'    | '1/8W'   | 'IO'       | 'RES CHIP 510 1/8W +-1%(0805)'                     | 'CHIP0805'     | ''          | ''            | '20130705'
 '137K'       | '1%'      | '1/16W'  | '0402LF'  | 'CHIP'   | 'CS41372FB12'(!)        = 'End of Design' | 'Comp-Approve'     | 'CS41372FB12'           |'R0402'| '(R0402-0201)'                 | '137K'    | '1%'    | '1/16W'  | 'DISCRETE' | 'RES CHIP 137K 1/16W +-1% (0402)'                  | 'CHIP0402'     | ''          | ''            | '20130729'
 '137K'       | '1%'      | '1/16W'  | '0402LF'  | 'EMPTY'  | 'CS41372FB12'(!)        = 'End of Design' | 'Comp-Approve'     | 'CS41372FB12'           |'R0402'| '(R0402-0201)'                 | '137K'    | '1%'    | '1/16W'  | 'IO'       | 'RES CHIP 137K 1/16W +-1% (0402)'                  | 'CHIP0402'     | ''          | ''            | '20130729'
 '162K'       | '1%'      | '1/16W'  | '0402LF'  | 'CHIP'   | 'CS41622FB11'(!)        = 'End of Design' | 'Comp-Approve'     | 'CS41622FB11'           |'R0402'| '(R0402-0201)'                 | '162K'    | '1%'    | '1/16W'  | 'DISCRETE' | 'RES CHIP 162K 1/16W +-1% (0402)'                  | 'CHIP0402'     | ''          | ''            | '20130729'
 '162K'       | '1%'      | '1/16W'  | '0402LF'  | 'EMPTY'  | 'CS41622FB11'(!)        = 'End of Design' | 'Comp-Approve'     | 'CS41622FB11'           |'R0402'| '(R0402-0201)'                 | '162K'    | '1%'    | '1/16W'  | 'IO'       | 'RES CHIP 162K 1/16W +-1% (0402)'                  | 'CHIP0402'     | ''          | ''            | '20130729'
 '14.3K'      | '1%'      | '1/16W'  | '0402LF'  | 'CHIP'   | 'CS31432FB08'(!)        = 'End of Design' | 'Comp-Approve'     | 'CS31432FB08'           |'R0402'| '(R0402-0201)'                 | '14.3K'   | '1%'    | '1/16W'  | 'DISCRETE' | 'RES CHIP 14.3K 1/16W +-1%(0402)'                  | 'CHIP0402'     | ''          | ''            | '20130729'
 '14.3K'      | '1%'      | '1/16W'  | '0402LF'  | 'EMPTY'  | 'CS31432FB08'(!)        = 'End of Design' | 'Comp-Approve'     | 'CS31432FB08'           |'R0402'| '(R0402-0201)'                 | '14.3K'   | '1%'    | '1/16W'  | 'IO'       | 'RES CHIP 14.3K 1/16W +-1%(0402)'                  | 'CHIP0402'     | ''          | ''            | '20130729'
 '5.11'       | '1%'      | '1/10W'  | '0603LF'  | 'CHIP'   | 'CS-5113F900'(!)        = 'End of Design' | 'Comp-Approve'     | 'CS-5113F900'           |'R0603'| '(SMR0603AW)'                  | '5.11'    | '1%'    | '1/10W'  | 'DISCRETE' | 'RES CHIP 5.11 1/10W +-1%(0603)'                   | 'CHIP0603'     | ''          | ''            | '20130731'
 '5.11'       | '1%'      | '1/10W'  | '0603LF'  | 'EMPTY'  | 'CS-5113F900'(!)        = 'End of Design' | 'Comp-Approve'     | 'CS-5113F900'           |'R0603'| '(SMR0603AW)'                  | '5.11'    | '1%'    | '1/10W'  | 'IO'       | 'RES CHIP 5.11 1/10W +-1%(0603)'                   | 'CHIP0603'     | ''          | ''            | '20130731'
 '232'        | '1%'      | '1/16W'  | '0402LF'  | 'CHIP'   | 'CS12322FB09'(!)        = 'End of Design' | 'Comp-Approve'     | 'CS12322FB09'           |'R0402'| '(R0402-0201)'                 | '232'     | '1%'    | '1/16W'  | 'DISCRETE' | 'RES CHIP 232 1/16W +-1%(0402)'                    | 'CHIP0402'     | ''          | ''            | '20130731'
 '232'        | '1%'      | '1/16W'  | '0402LF'  | 'EMPTY'  | 'CS12322FB09'(!)        = 'End of Design' | 'Comp-Approve'     | 'CS12322FB09'           |'R0402'| '(R0402-0201)'                 | '232'     | '1%'    | '1/16W'  | 'IO'       | 'RES CHIP 232 1/16W +-1%(0402)'                    | 'CHIP0402'     | ''          | ''            | '20130731'
 '511K'       | '1%'      | '1/16W'  | '0402LF'  | 'CHIP'   | 'CS45112FB19'(!)        = 'End of Design' | 'Comp-Approve'     | 'CS45112FB19'           |'R0402'| '(R0402-0201)'                 | '511K'    | '1%'    | '1/16W'  | 'DISCRETE' | 'RES CHIP 511K 1/16W +-1%(0402)'                   | 'CHIP0402'     | ''          | ''            | '20130808'
 '511K'       | '1%'      | '1/16W'  | '0402LF'  | 'EMPTY'  | 'CS45112FB19'(!)        = 'End of Design' | 'Comp-Approve'     | 'CS45112FB19'           |'R0402'| '(R0402-0201)'                 | '511K'    | '1%'    | '1/16W'  | 'IO'       | 'RES CHIP 511K 1/16W +-1%(0402)'                   | 'CHIP0402'     | ''          | ''            | '20130808'
 '140'        | '1%'      | '1/10W'  | '0603LF'  | 'CHIP'   | 'CS11403F915'(!)        = 'End of Design' | 'Comp-Approve'     | 'CS11403F915'           |'R0603'| '(SMR0603AW)'                  | '140'     | '1%'    | '1/10W'  | 'DISCRETE' | 'RESISTOR CHIP 140 1/10W +-1%(0603)'               | 'CHIP0603'     | ''          | ''            | '20130815'
 '140'        | '1%'      | '1/10W'  | '0603LF'  | 'EMPTY'  | 'CS11403F915'(!)        = 'End of Design' | 'Comp-Approve'     | 'CS11403F915'           |'R0603'| '(SMR0603AW)'                  | '140'     | '1%'    | '1/10W'  | 'IO'       | 'RESISTOR CHIP 140 1/10W +-1%(0603)'               | 'CHIP0603'     | ''          | ''            | '20130815'
 '4.75K'      | '0.1%'    | '1/16W'  | '0402LF'  | 'CHIP'   | 'CS24752BB00'(!)        = ''              | ''                 | 'CS24752BB00'           |'R0402'| '(R0402-0201)'                 | '4.75K'   | '0.1%'  | '1/16W'  | 'DISCRETE' | 'RES CHIP 4.75K 1/16W +-0.1%(0402)'                | 'CHIP0402'     | ''          | ''            | '20130826'
 '4.75K'      | '0.1%'    | '1/16W'  | '0402LF'  | 'EMPTY'  | 'CS24752BB00'(!)        = ''              | ''                 | 'CS24752BB00'           |'R0402'| '(R0402-0201)'                 | '4.75K'   | '0.1%'  | '1/16W'  | 'IO'       | 'RES CHIP 4.75K 1/16W +-0.1%(0402)'                | 'CHIP0402'     | ''          | ''            | '20130826'
 '137'        | '1%'      | '1/16W'  | '0402LF'  | 'CHIP'   | 'CS11372FB25'(!)        = 'End of Design' | 'Comp-Approve'     | 'CS11372FB25'           |'R0402'| '(R0402-0201)'                 | '137'     | '1%'    | '1/16W'  | 'DISCRETE' | 'RES CHIP 137 1/16W +-1%(0402)'                    | 'CHIP0402'     | ''          | ''            | '20131007'
 '137'        | '1%'      | '1/16W'  | '0402LF'  | 'EMPTY'  | 'CS11372FB25'(!)        = 'End of Design' | 'Comp-Approve'     | 'CS11372FB25'           |'R0402'| '(R0402-0201)'                 | '137'     | '1%'    | '1/16W'  | 'IO'       | 'RES CHIP 137 1/16W +-1%(0402)'                    | 'CHIP0402'     | ''          | ''            | '20131007'
 '1'          | '1%'      | '1/10W'  | '0603LF'  | 'CHIP'   | 'CS-1003F920'(!)        = ''              | ''                 | 'CS-1003F920'           |'R0603'| '(SMR0603AW)'                  | '1'       | '1%'    | '1/10W'  | 'DISCRETE' | 'RES CHIP 1 1/10W +-1%(0603)'                      | 'CHIP0603'     | ''          | ''            | '20131007'
 '1'          | '1%'      | '1/10W'  | '0603LF'  | 'EMPTY'  | 'CS-1003F920'(!)        = ''              | ''                 | 'CS-1003F920'           |'R0603'| '(SMR0603AW)'                  | '1'       | '1%'    | '1/10W'  | 'IO'       | 'RES CHIP 1 1/10W +-1%(0603)'                      | 'CHIP0603'     | ''          | ''            | '20131007'
 '137'        | '1%'      | '1/10W'  | '0603LF'  | 'CHIP'   | 'CS11373F921'(!)        = ''              | ''                 | 'CS11373F921'           |'R0603'| '(SMR0603AW)'                  | '137'     | '1%'    | '1/10W'  | 'DISCRETE' | 'RES CHIP 137 1/10W +-1%(0603)'                    | 'CHIP0603'     | ''          | ''            | '20131007'
 '137'        | '1%'      | '1/10W'  | '0603LF'  | 'EMPTY'  | 'CS11373F921'(!)        = ''              | ''                 | 'CS11373F921'           |'R0603'| '(SMR0603AW)'                  | '137'     | '1%'    | '1/10W'  | 'IO'       | 'RES CHIP 137 1/10W +-1%(0603)'                    | 'CHIP0603'     | ''          | ''            | '20131007'
 '442'        | '1%'      | '1/16W'  | '0402LF'  | 'CHIP'   | 'CS14422FB16'(!)        = 'End of Design' | 'Comp-Approve'     | 'CS14422FB16'           |'R0402'| '(R0402-0201)'                 | '442'     | '1%'    | '1/16W'  | 'DISCRETE' | 'RES CHIP 442 1/16W +-1% (0402)'                   | 'CHIP0402'     | ''          | ''            | '20131022'
 '442'        | '1%'      | '1/16W'  | '0402LF'  | 'EMPTY'  | 'CS14422FB16'(!)        = 'End of Design' | 'Comp-Approve'     | 'CS14422FB16'           |'R0402'| '(R0402-0201)'                 | '442'     | '1%'    | '1/16W'  | 'IO'       | 'RES CHIP 442 1/16W +-1% (0402)'                   | 'CHIP0402'     | ''          | ''            | '20131022'
 '0.005'      | '1%'      | '1W'     | '2010LF'  | 'CHIP'   | 'CS+0058FJ03'(!)        = ''              | ''                 | 'CS+0058FJ03'           |'R2010'| '(SMR2010AW)'                  | '0.005'   | '1%'    | '1W'     | 'DISCRETE' | 'RES CHIP 0.005 1W +-1%(2010)'                     | 'CHIP2010'     | ''          | ''            | '20131031'
 '0.005'      | '1%'      | '1W'     | '2010LF'  | 'EMPTY'  | 'CS+0058FJ03'(!)        = ''              | ''                 | 'CS+0058FJ03'           |'R2010'| '(SMR2010AW)'                  | '0.005'   | '1%'    | '1W'     | 'IO'       | 'RES CHIP 0.005 1W +-1%(2010)'                     | 'CHIP2010'     | ''          | ''            | '20131031'
 '1.3K'       | '1%'      | '1/16W'  | '0402LF'  | 'CHIP'   | 'CS21302FB17'(!)        = 'End of Design' | 'Comp-Approve'     | 'CS21302FB17'           |'R0402'| '(R0402-0201)'                 | '1.3K'    | '1%'    | '1/16W'  | 'DISCRETE' | 'RES CHIP 1.3K 1/16W +-1%(0402) L-F'               | 'CHIP0402'     | ''          | ''            | '20131122'
 '1.3K'       | '1%'      | '1/16W'  | '0402LF'  | 'EMPTY'  | 'CS21302FB17'(!)        = 'End of Design' | 'Comp-Approve'     | 'CS21302FB17'           |'R0402'| '(R0402-0201)'                 | '1.3K'    | '1%'    | '1/16W'  | 'IO'       | 'RES CHIP 1.3K 1/16W +-1%(0402) L-F'               | 'CHIP0402'     | ''          | ''            | '20131122'
 '2.4K'       | '1%'      | '1/16W'  | '0402LF'  | 'CHIP'   | 'CS22402FB00'(!)        = 'End of Design' | 'Comp-Approve'     | 'CS22402FB00'           |'R0402'| '(R0402-0201)'                 | '2.4K'    | '1%'    | '1/16W'  | 'DISCRETE' | 'RES CHIP 2.4K 1/16W+-1%(0402)'                    | 'CHIP0402'     | ''          | ''            | '20131202'
 '2.4K'       | '1%'      | '1/16W'  | '0402LF'  | 'EMPTY'  | 'CS22402FB00'(!)        = 'End of Design' | 'Comp-Approve'     | 'CS22402FB00'           |'R0402'| '(R0402-0201)'                 | '2.4K'    | '1%'    | '1/16W'  | 'IO'       | 'RES CHIP 2.4K 1/16W+-1%(0402)'                    | 'CHIP0402'     | ''          | ''            | '20131202'
 '1.33K'      | '1%'      | '1/16W'  | '0402LF'  | 'CHIP'   | 'CS21332FB11'(!)        = 'End of Design' | 'Comp-Approve'     | 'CS21332FB11'           |'R0402'| '(R0402-0201)'                 | '1.33K'   | '1%'    | '1/16W'  | 'DISCRETE' | 'RES CHIP 1.33K 1/16W +-1%( 0402)EP'               | 'CHIP0402'     | ''          | ''            | '20131203'
 '1.33K'      | '1%'      | '1/16W'  | '0402LF'  | 'EMPTY'  | 'CS21332FB11'(!)        = 'End of Design' | 'Comp-Approve'     | 'CS21332FB11'           |'R0402'| '(R0402-0201)'                 | '1.33K'   | '1%'    | '1/16W'  | 'IO'       | 'RES CHIP 1.33K 1/16W +-1%( 0402)EP'               | 'CHIP0402'     | ''          | ''            | '20131203'
 '1.78K'      | '1%'      | '1/16W'  | '0402LF'  | 'CHIP'   | 'CS21782FB18'(!)        = 'End of Design' | 'Comp-Approve'     | 'CS21782FB18'           |'R0402'| '(R0402-0201)'                 | '1.78K'   | '1%'    | '1/16W'  | 'DISCRETE' | 'RES CHIP 1.78K 1/16W +-1% (0402)'                 | 'CHIP0402'     | ''          | ''            | '20131205'
 '1.78K'      | '1%'      | '1/16W'  | '0402LF'  | 'EMPTY'  | 'CS21782FB18'(!)        = 'End of Design' | 'Comp-Approve'     | 'CS21782FB18'           |'R0402'| '(R0402-0201)'                 | '1.78K'   | '1%'    | '1/16W'  | 'IO'       | 'RES CHIP 1.78K 1/16W +-1% (0402)'                 | 'CHIP0402'     | ''          | ''            | '20131205'
 '8.45K'      | '1%'      | '1/16W'  | '0402LF'  | 'CHIP'   | 'CS28452FB12'(!)        = 'End of Design' | 'Comp-Approve'     | 'CS28452FB12'           |'R0402'| '(R0402-0201)'                 | '8.45K'   | '1%'    | '1/16W'  | 'DISCRETE' | 'RES CHIP 8.45K 1/16W +-1%( 0402)'                 | 'CHIP0402'     | ''          | ''            | '20131211'
 '8.45K'      | '1%'      | '1/16W'  | '0402LF'  | 'EMPTY'  | 'CS28452FB12'(!)        = 'End of Design' | 'Comp-Approve'     | 'CS28452FB12'           |'R0402'| '(R0402-0201)'                 | '8.45K'   | '1%'    | '1/16W'  | 'IO'       | 'RES CHIP 8.45K 1/16W +-1%( 0402)'                 | 'CHIP0402'     | ''          | ''            | '20131211'
 '1.58K'      | '1%'      | '1/16W'  | '0402LF'  | 'CHIP'   | 'CS21582FB00'(!)        = 'End of Design' | 'Comp-Approve'     | 'CS21582FB00'           |'R0402'| '(R0402-0201)'                 | '1.58K'   | '1%'    | '1/16W'  | 'DISCRETE' | 'RES CHIP 1.58K 1/16W +-1%(0402)'                  | 'CHIP0402'     | ''          | ''            | '20140116'
 '1.58K'      | '1%'      | '1/16W'  | '0402LF'  | 'EMPTY'  | 'CS21582FB00'(!)        = 'End of Design' | 'Comp-Approve'     | 'CS21582FB00'           |'R0402'| '(R0402-0201)'                 | '1.58K'   | '1%'    | '1/16W'  | 'IO'       | 'RES CHIP 1.58K 1/16W +-1%(0402)'                  | 'CHIP0402'     | ''          | ''            | '20140116'
 '18'         | '1%'      | '1/16W'  | '0402LF'  | 'CHIP'   | 'CS01802FB11'(!)        = 'End of Design' | 'Comp-Release Qty' | 'CS01802FB11'           |'R0402'| '(R0402-0201)'                 | '18'      | '1%'    | '1/16W'  | 'DISCRETE' | 'RES CHIP 18 1/16W +-1% (0402)'                    | 'CHIP0402'     | ''          | ''            | '20140128'
 '18'         | '1%'      | '1/16W'  | '0402LF'  | 'EMPTY'  | 'CS01802FB11'(!)        = 'End of Design' | 'Comp-Release Qty' | 'CS01802FB11'           |'R0402'| '(R0402-0201)'                 | '18'      | '1%'    | '1/16W'  | 'IO'       | 'RES CHIP 18 1/16W +-1% (0402)'                    | 'CHIP0402'     | ''          | ''            | '20140128'
 '1.2K'       | '1%'      | '1/8W'   | '0805LF'  | 'CHIP'   | 'CS21204FA17'(!)        = 'End of Design' | 'Comp-Approve'     | 'CS21204FA17'           |'R0805'| '(SMR0805AW)'                  | '1.2K'    | '1%'    | '1/8W'   | 'DISCRETE' | 'RES CHIP 1.2K 1/8W +-1%(0805)'                    | 'CHIP0805'     | ''          | ''            | '20140310'
 '1.2K'       | '1%'      | '1/8W'   | '0805LF'  | 'EMPTY'  | 'CS21204FA17'(!)        = 'End of Design' | 'Comp-Approve'     | 'CS21204FA17'           |'R0805'| '(SMR0805AW)'                  | '1.2K'    | '1%'    | '1/8W'   | 'IO'       | 'RES CHIP 1.2K 1/8W +-1%(0805)'                    | 'CHIP0805'     | ''          | ''            | '20140310'
 '68'         | '5%'      | '1/4W'   | '0805LF'  | 'CHIP'   | 'CS06806JA00'(!)        = ''              | ''                 | 'CS06806JA00'           |'R0805'| '(SMR0805AW)'                  | '68'      | '5%'    | '1/4W'   | 'DISCRETE' | 'RES CHIP 68 1/4W +-5%(0805)'                      | 'CHIP0805'     | ''          | ''            | '20140415'
 '68'         | '5%'      | '1/4W'   | '0805LF'  | 'EMPTY'  | 'CS06806JA00'(!)        = ''              | ''                 | 'CS06806JA00'           |'R0805'| '(SMR0805AW)'                  | '68'      | '5%'    | '1/4W'   | 'IO'       | 'RES CHIP 68 1/4W +-5%(0805)'                      | 'CHIP0805'     | ''          | ''            | '20140415'
 '33'         | '5%'      | '1/2W'   | '1206LF'  | 'CHIP'   | 'CS03307J200'(!)        = ''              | ''                 | 'CS03307J200'           |'R1206'| '(SMR1206AW)'                  | '33'      | '5%'    | '1/2W'   | 'DISCRETE' | 'RES CHIP 33 1/2W +-5%(1206)'                      | 'CHIP1206'     | ''          | ''            | '20140415'
 '33'         | '5%'      | '1/2W'   | '1206LF'  | 'EMPTY'  | 'CS03307J200'(!)        = ''              | ''                 | 'CS03307J200'           |'R1206'| '(SMR1206AW)'                  | '33'      | '5%'    | '1/2W'   | 'IO'       | 'RES CHIP 33 1/2W +-5%(1206)'                      | 'CHIP1206'     | ''          | ''            | '20140415'
 '1K'         | '1%'      | '1/20W'  | '0201LF'  | 'CHIP'   | 'CS21001FE04'(!)        = ''              | ''                 | 'CS21001FE04'           |'R0201'| '(SMR0201AW)'                  | '1K'      | '1%'    | '1/20W'  | 'DISCRETE' | 'RES CHIP 1K 1/20W +-1%(0201)'                     | 'CHIP0201'     | ''          | ''            | '20140424'
 '1K'         | '1%'      | '1/20W'  | '0201LF'  | 'EMPTY'  | 'CS21001FE04'(!)        = ''              | ''                 | 'CS21001FE04'           |'R0201'| '(SMR0201AW)'                  | '1K'      | '1%'    | '1/20W'  | 'IO'       | 'RES CHIP 1K 1/20W +-1%(0201)'                     | 'CHIP0201'     | ''          | ''            | '20140424'
 '150K'       | '1%'      | '1/10W'  | '0603LF'  | 'CHIP'   | 'CS41503F914'(!)        = 'End of Design' | 'Comp-Approve'     | 'CS41503F914'           |'R0603'| '(SMR0603AW)'                  | '150K'    | '1%'    | '1/10W'  | 'DISCRETE' | 'RES CHIP 150K 1/10W +-1%(0603)'                   | 'CHIP0603'     | ''          | ''            | '20140429'
 '150K'       | '1%'      | '1/10W'  | '0603LF'  | 'EMPTY'  | 'CS41503F914'(!)        = 'End of Design' | 'Comp-Approve'     | 'CS41503F914'           |'R0603'| '(SMR0603AW)'                  | '150K'    | '1%'    | '1/10W'  | 'IO'       | 'RES CHIP 150K 1/10W +-1%(0603)'                   | 'CHIP0603'     | ''          | ''            | '20140429'
 '0.015'      | '1%'      | '1W'     | '2512LF'  | 'CHIP'   | 'CS+0158FR00'(!)        = 'End of Design' | 'Comp-Approve'     | 'CS+0158FR00'           |'R2512'| '(SMR2512AW)'                  | '0.015'   | '1%'    | '1W'     | 'DISCRETE' | 'RES CHIP 0.015 1W +-1%(2512)'                     | 'CHIP2512'     | ''          | ''            | '20140505'
 '0.015'      | '1%'      | '1W'     | '2512LF'  | 'EMPTY'  | 'CS+0158FR00'(!)        = 'End of Design' | 'Comp-Approve'     | 'CS+0158FR00'           |'R2512'| '(SMR2512AW)'                  | '0.015'   | '1%'    | '1W'     | 'IO'       | 'RES CHIP 0.015 1W +-1%(2512)'                     | 'CHIP2512'     | ''          | ''            | '20140505'
 '2.2K'       | '1%'      | '1/10W'  | '0603LF'  | 'CHIP'   | 'CS22203F904'(!)        = ''              | ''                 | 'CS22203F904'           |'R0603'| '(SMR0603AW)'                  | '2.2K'    | '1%'    | '1/10W'  | 'DISCRETE' | 'RES CHIP 2.2K 1/10W.+-1%(0603)'                   | 'CHIP0603'     | ''          | ''            | '20140505'
 '2.2K'       | '1%'      | '1/10W'  | '0603LF'  | 'EMPTY'  | 'CS22203F904'(!)        = ''              | ''                 | 'CS22203F904'           |'R0603'| '(SMR0603AW)'                  | '2.2K'    | '1%'    | '1/10W'  | 'IO'       | 'RES CHIP 2.2K 1/10W.+-1%(0603)'                   | 'CHIP0603'     | ''          | ''            | '20140505'
 '200K'       | '1%'      | '1/8W'   | '0805LF'  | 'CHIP'   | 'CS42004FA00'(!)        = ''              | ''                 | 'CS42004FA00'           |'R0805'| '(SMR0805AW)'                  | '200K'    | '1%'    | '1/8W'   | 'DISCRETE' | 'RES CHIP 200K 1/8W +-1%(0805)'                    | 'CHIP0805'     | ''          | ''            | '20140527'
 '200K'       | '1%'      | '1/8W'   | '0805LF'  | 'EMPTY'  | 'CS42004FA00'(!)        = ''              | ''                 | 'CS42004FA00'           |'R0805'| '(SMR0805AW)'                  | '200K'    | '1%'    | '1/8W'   | 'IO'       | 'RES CHIP 200K 1/8W +-1%(0805)'                    | 'CHIP0805'     | ''          | ''            | '20140527'
 '23.2K'      | '1%'      | '1/10W'  | '0603LF'  | 'CHIP'   | 'CS32323F917'(!)        = ''              | ''                 | 'CS32323F917'           |'R0603'| '(SMR0603AW)'                  | '23.2K'   | '1%'    | '1/10W'  | 'DISCRETE' | 'RES CHIP 23.2K 1/10W +-1%(0603)'                  | 'CHIP0603'     | ''          | ''            | '20140529'
 '23.2K'      | '1%'      | '1/10W'  | '0603LF'  | 'EMPTY'  | 'CS32323F917'(!)        = ''              | ''                 | 'CS32323F917'           |'R0603'| '(SMR0603AW)'                  | '23.2K'   | '1%'    | '1/10W'  | 'IO'       | 'RES CHIP 23.2K 1/10W +-1%(0603)'                  | 'CHIP0603'     | ''          | ''            | '20140529'
 '470'        | '1%'      | '1/16W'  | '0402LF'  | 'CHIP'   | 'CS14702FB18'(!)        = 'End of Design' | 'Comp-Approve'     | 'CS14702FB18'           |'R0402'| '(R0402-0201)'                 | '470'     | '1%'    | '1/16W'  | 'DISCRETE' | 'RES CHIP 470 1/16W +-1%(0402)'                    | 'CHIP0402'     | ''          | ''            | '20140605'
 '470'        | '1%'      | '1/16W'  | '0402LF'  | 'EMPTY'  | 'CS14702FB18'(!)        = 'End of Design' | 'Comp-Approve'     | 'CS14702FB18'           |'R0402'| '(R0402-0201)'                 | '470'     | '1%'    | '1/16W'  | 'IO'       | 'RES CHIP 470 1/16W +-1%(0402)'                    | 'CHIP0402'     | ''          | ''            | '20140605'
 '12K'        | '0.5%'    | '1/16W'  | '0402LF'  | 'CHIP'   | 'CS31202DB00'(!)        = ''              | ''                 | 'CS31202DB00'           |'R0402'| '(R0402-0201)'                 | '12K'     | '0.5%'  | '1/16W'  | 'DISCRETE' | 'RES CHIP 12K 1/16W +-0.5%(0402)'                  | 'CHIP0402'     | ''          | ''            | '20140613'
 '12K'        | '0.5%'    | '1/16W'  | '0402LF'  | 'EMPTY'  | 'CS31202DB00'(!)        = ''              | ''                 | 'CS31202DB00'           |'R0402'| '(R0402-0201)'                 | '12K'     | '0.5%'  | '1/16W'  | 'IO'       | 'RES CHIP 12K 1/16W +-0.5%(0402)'                  | 'CHIP0402'     | ''          | ''            | '20140613'
 '2.8K'       | '1%'      | '1/16W'  | '0402LF'  | 'CHIP'   | 'CS22802FB02'(!)        = ''              | 'End of Life'      | 'CS22802FB02'           |'R0402_EOL'| '(R0402-0201)'                 | '2.8K'    | '1%'    | '1/16W'  | 'DISCRETE' | 'RES CHIP 2.8K 1/16W +-1%(0402)'                   | 'CHIP0402'     | ''          | ''            | '20140616'
 '2.8K'       | '1%'      | '1/16W'  | '0402LF'  | 'EMPTY'  | 'CS22802FB02'(!)        = ''              | 'End of Life'      | 'CS22802FB02'           |'R0402_EOL'| '(R0402-0201)'                 | '2.8K'    | '1%'    | '1/16W'  | 'IO'       | 'RES CHIP 2.8K 1/16W +-1%(0402)'                   | 'CHIP0402'     | ''          | ''            | '20140616'
 '1.69K'      | '1%'      | '1/16W'  | '0402LF'  | 'CHIP'   | 'CS21692FB01'(!)        = 'End of Design' | 'Comp-Approve'     | 'CS21692FB01'           |'R0402'| '(R0402-0201)'                 | '1.69K'   | '1%'    | '1/16W'  | 'DISCRETE' | 'RES CHIP 1.69K 1/16W +-1%(0402)'                  | 'CHIP0402'     | ''          | ''            | '20140616'
 '1.69K'      | '1%'      | '1/16W'  | '0402LF'  | 'EMPTY'  | 'CS21692FB01'(!)        = 'End of Design' | 'Comp-Approve'     | 'CS21692FB01'           |'R0402'| '(R0402-0201)'                 | '1.69K'   | '1%'    | '1/16W'  | 'IO'       | 'RES CHIP 1.69K 1/16W +-1%(0402)'                  | 'CHIP0402'     | ''          | ''            | '20140616'
 '40.2'       | '1%'      | '1/16W'  | '0402LF'  | 'CHIP'   | 'CS04022FB28'(!)        = 'End of Design' | 'Comp-Approve'     | 'CS04022FB28'           |'R0402'| '(R0402-0201)'                 | '40.2'    | '1%'    | '1/16W'  | 'DISCRETE' | 'RES CHIP 40.2 1/16W +-1%(0402)'                   | 'CHIP0402'     | ''          | ''            | '20140630'
 '40.2'       | '1%'      | '1/16W'  | '0402LF'  | 'EMPTY'  | 'CS04022FB28'(!)        = 'End of Design' | 'Comp-Approve'     | 'CS04022FB28'           |'R0402'| '(R0402-0201)'                 | '40.2'    | '1%'    | '1/16W'  | 'IO'       | 'RES CHIP 40.2 1/16W +-1%(0402)'                   | 'CHIP0402'     | ''          | ''            | '20140630'
 '1.8K'       | '1%'      | '1/16W'  | '0402LF'  | 'CHIP'   | 'CS21802FB10'(!)        = 'End of Design' | 'Comp-Approve'     | 'CS21802FB10'           |'R0402'| '(R0402-0201)'                 | '1.8K'    | '1%'    | '1/16W'  | 'DISCRETE' | 'RES CHIP 1.8K 1/16W +-1%(0402)'                   | 'CHIP0402'     | ''          | ''            | '20140630'
 '1.8K'       | '1%'      | '1/16W'  | '0402LF'  | 'EMPTY'  | 'CS21802FB10'(!)        = 'End of Design' | 'Comp-Approve'     | 'CS21802FB10'           |'R0402'| '(R0402-0201)'                 | '1.8K'    | '1%'    | '1/16W'  | 'IO'       | 'RES CHIP 1.8K 1/16W +-1%(0402)'                   | 'CHIP0402'     | ''          | ''            | '20140630'
 '1.74K'      | '1%'      | '1/10W'  | '0603LF'  | 'CHIP'   | 'CS21743F916'(!)        = ''              | ''                 | 'CS21743F916'           |'R0603'| '(SMR0603AW)'                  | '1.74K'   | '1%'    | '1/10W'  | 'DISCRETE' | 'RESISTER CHIP 1.74K 1/10W +-1%(0603)L-F'          | 'CHIP0603'     | ''          | ''            | '20140724'
 '1.74K'      | '1%'      | '1/10W'  | '0603LF'  | 'EMPTY'  | 'CS21743F916'(!)        = ''              | ''                 | 'CS21743F916'           |'R0603'| '(SMR0603AW)'                  | '1.74K'   | '1%'    | '1/10W'  | 'IO'       | 'RESISTER CHIP 1.74K 1/10W +-1%(0603)L-F'          | 'CHIP0603'     | ''          | ''            | '20140724'
 '113K'       | '1%'      | '1/16W'  | '0402LF'  | 'CHIP'   | 'CS41132FB17'(!)        = 'End of Design' | 'Comp-Approve'     | 'CS41132FB17'           |'R0402'| '(R0402-0201)'                 | '113K'    | '1%'    | '1/16W'  | 'DISCRETE' | 'RES CHIP 113K 1/16W +-1%(0402)'                   | 'CHIP0402'     | ''          | ''            | '20140729'
 '113K'       | '1%'      | '1/16W'  | '0402LF'  | 'EMPTY'  | 'CS41132FB17'(!)        = 'End of Design' | 'Comp-Approve'     | 'CS41132FB17'           |'R0402'| '(R0402-0201)'                 | '113K'    | '1%'    | '1/16W'  | 'IO'       | 'RES CHIP 113K 1/16W +-1%(0402)'                   | 'CHIP0402'     | ''          | ''            | '20140729'
 '82'         | '1%'      | '1/16W'  | '0402LF'  | 'CHIP'   | 'CS08202FB01'(!)        = 'End of Design' | 'Comp-Approve'     | 'CS08202FB01'           |'R0402'| '(R0402-0201)'                 | '82'      | '1%'    | '1/16W'  | 'DISCRETE' | 'RES CHIP 82(1/16W,+-1%,0402)EP'                   | 'CHIP0402'     | ''          | ''            | '20140729'
 '82'         | '1%'      | '1/16W'  | '0402LF'  | 'EMPTY'  | 'CS08202FB01'(!)        = 'End of Design' | 'Comp-Approve'     | 'CS08202FB01'           |'R0402'| '(R0402-0201)'                 | '82'      | '1%'    | '1/16W'  | 'IO'       | 'RES CHIP 82(1/16W,+-1%,0402)EP'                   | 'CHIP0402'     | ''          | ''            | '20140729'
 '42.2K'      | '1%'      | '1/8W'   | '0805LF'  | 'CHIP'   | 'CS34224FA00'(!)        = ''              | ''                 | 'CS34224FA00'           |'R0805'| '(SMR0805AW)'                  | '42.2K'   | '1%'    | '1/8W'   | 'DISCRETE' | 'RES CHIP 42.2K 1/8W +-1%(0805)'                   | 'CHIP0805'     | ''          | ''            | '20140806'
 '42.2K'      | '1%'      | '1/8W'   | '0805LF'  | 'EMPTY'  | 'CS34224FA00'(!)        = ''              | ''                 | 'CS34224FA00'           |'R0805'| '(SMR0805AW)'                  | '42.2K'   | '1%'    | '1/8W'   | 'IO'       | 'RES CHIP 42.2K 1/8W +-1%(0805)'                   | 'CHIP0805'     | ''          | ''            | '20140806'
 '0.3'        | '1%'      | '1/2W'   | '1206LF'  | 'CHIP'   | 'CS+3007F200'(!)        = ''              | ''                 | 'CS+3007F200'           |'R1206'| '(SMR1206AW)'                  | '0.3'     | '1%'    | '1/2W'   | 'DISCRETE' | 'RES CHIP 0.3 1/2W +-1%(1206)'                     | 'CHIP1206'     | ''          | ''            | '20140806'
 '0.3'        | '1%'      | '1/2W'   | '1206LF'  | 'EMPTY'  | 'CS+3007F200'(!)        = ''              | ''                 | 'CS+3007F200'           |'R1206'| '(SMR1206AW)'                  | '0.3'     | '1%'    | '1/2W'   | 'IO'       | 'RES CHIP 0.3 1/2W +-1%(1206)'                     | 'CHIP1206'     | ''          | ''            | '20140806'
 '1.21'       | '1%'      | '1/16W'  | '0402LF'  | 'CHIP'   | 'CS-1212FB00'(!)        = ''              | ''                 | 'CS-1212FB00'           |'R0402'| '(R0402-0201)'                 | '1.21'    | '1%'    | '1/16W'  | 'DISCRETE' | 'RES CHIP 1.21 1/16W +-1%(0402)'                   | 'CHIP0402'     | ''          | ''            | '20140807'
 '1.21'       | '1%'      | '1/16W'  | '0402LF'  | 'EMPTY'  | 'CS-1212FB00'(!)        = ''              | ''                 | 'CS-1212FB00'           |'R0402'| '(R0402-0201)'                 | '1.21'    | '1%'    | '1/16W'  | 'IO'       | 'RES CHIP 1.21 1/16W +-1%(0402)'                   | 'CHIP0402'     | ''          | ''            | '20140807'
 '0.004'      | '1%'      | '3W'     | '2512LF'  | 'CHIP'   | 'CS+004DFR00'(!)        = ''              | ''                 | 'CS+004DFR00'           |'R2512XF'| '(SMR2512AW)'                  | '0.004'   | '1%'    | '3W'     | 'DISCRETE' | 'RES CHIP 0.004 3W +-1%(2512)'                     | 'CHIP2512'     | ''          | ''            | '20140808'
 '0.004'      | '1%'      | '3W'     | '2512LF'  | 'EMPTY'  | 'CS+004DFR00'(!)        = ''              | ''                 | 'CS+004DFR00'           |'R2512XF'| '(SMR2512AW)'                  | '0.004'   | '1%'    | '3W'     | 'IO'       | 'RES CHIP 0.004 3W +-1%(2512)'                     | 'CHIP2512'     | ''          | ''            | '20140808'
 '68.1'       | '1%'      | '1/16W'  | '0402LF'  | 'CHIP'   | 'CS06812FB00'(!)        = 'End of Design' | 'Comp-Approve'     | 'CS06812FB00'           |'R0402'| '(R0402-0201)'                 | '68.1'    | '1%'    | '1/16W'  | 'DISCRETE' | 'RES CHIP 68.1 1/16W +-1% (0402)'                  | 'CHIP0402'     | ''          | ''            | '20140808'
 '68.1'       | '1%'      | '1/16W'  | '0402LF'  | 'EMPTY'  | 'CS06812FB00'(!)        = 'End of Design' | 'Comp-Approve'     | 'CS06812FB00'           |'R0402'| '(R0402-0201)'                 | '68.1'    | '1%'    | '1/16W'  | 'IO'       | 'RES CHIP 68.1 1/16W +-1% (0402)'                  | 'CHIP0402'     | ''          | ''            | '20140808'
 '332'        | '1%'      | '1/16W'  | '0402LF'  | 'CHIP'   | 'CS13322FB10'(!)        = 'End of Design' | 'Comp-Approve'     | 'CS13322FB10'           |'R0402'| '(R0402-0201)'                 | '332'     | '1%'    | '1/16W'  | 'DISCRETE' | 'RES CHIP 332 1/16W +-1%(0402)'                    | 'CHIP0402'     | ''          | ''            | '20140808'
 '332'        | '1%'      | '1/16W'  | '0402LF'  | 'EMPTY'  | 'CS13322FB10'(!)        = 'End of Design' | 'Comp-Approve'     | 'CS13322FB10'           |'R0402'| '(R0402-0201)'                 | '332'     | '1%'    | '1/16W'  | 'IO'       | 'RES CHIP 332 1/16W +-1%(0402)'                    | 'CHIP0402'     | ''          | ''            | '20140808'
 '5.62K'      | '1%'      | '1/16W'  | '0402LF'  | 'CHIP'   | 'CS25622FB18'(!)        = 'End of Design' | 'Comp-Approve'     | 'CS25622FB18'           |'R0402'| '(R0402-0201)'                 | '5.62K'   | '1%'    | '1/16W'  | 'DISCRETE' | 'RES CHIP 5.62K 1/16W +-1%( 0402)'                 | 'CHIP0402'     | ''          | ''            | '20140808'
 '5.62K'      | '1%'      | '1/16W'  | '0402LF'  | 'EMPTY'  | 'CS25622FB18'(!)        = 'End of Design' | 'Comp-Approve'     | 'CS25622FB18'           |'R0402'| '(R0402-0201)'                 | '5.62K'   | '1%'    | '1/16W'  | 'IO'       | 'RES CHIP 5.62K 1/16W +-1%( 0402)'                 | 'CHIP0402'     | ''          | ''            | '20140808'
 '205K'       | '1%'      | '1/8W'   | '0805LF'  | 'CHIP'   | 'CS42054FA00'(!)        = ''              | ''                 | 'CS42054FA00'           |'R0805'| '(SMR0805AW)'                  | '205K'    | '1%'    | '1/8W'   | 'DISCRETE' | 'RES CHIP 205K 1/8W +-1%(0805)'                    | 'CHIP0805'     | ''          | ''            | '20140808'
 '205K'       | '1%'      | '1/8W'   | '0805LF'  | 'EMPTY'  | 'CS42054FA00'(!)        = ''              | ''                 | 'CS42054FA00'           |'R0805'| '(SMR0805AW)'                  | '205K'    | '1%'    | '1/8W'   | 'IO'       | 'RES CHIP 205K 1/8W +-1%(0805)'                    | 'CHIP0805'     | ''          | ''            | '20140808'
 '150K'       | '1%'      | '1/8W'   | '0805LF'  | 'CHIP'   | 'CS41504FA00'(!)        = ''              | ''                 | 'CS41504FA00'           |'R0805'| '(SMR0805AW)'                  | '150K'    | '1%'    | '1/8W'   | 'DISCRETE' | 'RES CHIP 150K 1/8W +-1%(0805)'                    | 'CHIP0805'     | ''          | ''            | '20140808'
 '150K'       | '1%'      | '1/8W'   | '0805LF'  | 'EMPTY'  | 'CS41504FA00'(!)        = ''              | ''                 | 'CS41504FA00'           |'R0805'| '(SMR0805AW)'                  | '150K'    | '1%'    | '1/8W'   | 'IO'       | 'RES CHIP 150K 1/8W +-1%(0805)'                    | 'CHIP0805'     | ''          | ''            | '20140808'
 '221K'       | '1%'      | '1/16W'  | '0402LF'  | 'CHIP'   | 'CS42212FB22'(!)        = 'End of Design' | 'Comp-Approve'     | 'CS42212FB22'           |'R0402'| '(R0402-0201)'                 | '221K'    | '1%'    | '1/16W'  | 'DISCRETE' | 'RES CHIP 221K 1/16W +-1% (0402)'                  | 'CHIP0402'     | ''          | ''            | '20140812'
 '221K'       | '1%'      | '1/16W'  | '0402LF'  | 'EMPTY'  | 'CS42212FB22'(!)        = 'End of Design' | 'Comp-Approve'     | 'CS42212FB22'           |'R0402'| '(R0402-0201)'                 | '221K'    | '1%'    | '1/16W'  | 'IO'       | 'RES CHIP 221K 1/16W +-1% (0402)'                  | 'CHIP0402'     | ''          | ''            | '20140812'
 '10K'        | '0.10%'   | '1/16W'  | '0402LF'  | 'CHIP'   | 'CS31002BB00'(!)        = ''              | ''                 | 'CS31002BB00'           |'R0402'| '(R0402-0201)'                 | '10K'     | '0.10%' | '1/16W'  | 'DISCRETE' | 'RES CHIP 10K 1/16W +-0.1%(0402)'                  | 'CHIP0402'     | ''          | ''            | '20140812'
 '10K'        | '0.10%'   | '1/16W'  | '0402LF'  | 'EMPTY'  | 'CS31002BB00'(!)        = ''              | ''                 | 'CS31002BB00'           |'R0402'| '(R0402-0201)'                 | '10K'     | '0.10%' | '1/16W'  | 'IO'       | 'RES CHIP 10K 1/16W +-0.1%(0402)'                  | 'CHIP0402'     | ''          | ''            | '20140812'
 '470'        | '5%'      | '1/8W'   | '0805LF'  | 'CHIP'   | 'CS14704JA13'(!)        = ''              | ''                 | 'CS14704JA13'           |'R0805'| '(SMR0805AW)'                  | '470'     | '5%'    | '1/8W'   | 'DISCRETE' | 'RES CHIP 470 1/8W +-5%(0805)'                     | 'CHIP0805'     | ''          | ''            | '20140812'
 '470'        | '5%'      | '1/8W'   | '0805LF'  | 'EMPTY'  | 'CS14704JA13'(!)        = ''              | ''                 | 'CS14704JA13'           |'R0805'| '(SMR0805AW)'                  | '470'     | '5%'    | '1/8W'   | 'IO'       | 'RES CHIP 470 1/8W +-5%(0805)'                     | 'CHIP0805'     | ''          | ''            | '20140812'
 '26.7K'      | '0.1%'    | '1/16W'  | '0402LF'  | 'CHIP'   | 'CS32672BB00'(!)        = ''              | ''                 | 'CS32672BB00'           |'R0402'| '(R0402-0201)'                 | '26.7K'   | '0.1%'  | '1/16W'  | 'DISCRETE' | 'RES CHIP 26.7K 1/16W +-0.1%(0402)'                | 'CHIP0402'     | ''          | ''            | '20140813'
 '26.7K'      | '0.1%'    | '1/16W'  | '0402LF'  | 'EMPTY'  | 'CS32672BB00'(!)        = ''              | ''                 | 'CS32672BB00'           |'R0402'| '(R0402-0201)'                 | '26.7K'   | '0.1%'  | '1/16W'  | 'IO'       | 'RES CHIP 26.7K 1/16W +-0.1%(0402)'                | 'CHIP0402'     | ''          | ''            | '20140813'
 '4.64K'      | '0.5%'    | '1/16W'  | '0402LF'  | 'CHIP'   | 'CS24642DB00'(!)        = ''              | ''                 | 'CS24642DB00'           |'R0402'| '(R0402-0201)'                 | '4.64K'   | '0.5%'  | '1/16W'  | 'DISCRETE' | 'RES CHIP 4.64K 1/16W +-0.5%(0402)'                | 'CHIP0402'     | ''          | ''            | '20140813'
 '4.64K'      | '0.5%'    | '1/16W'  | '0402LF'  | 'EMPTY'  | 'CS24642DB00'(!)        = ''              | ''                 | 'CS24642DB00'           |'R0402'| '(R0402-0201)'                 | '4.64K'   | '0.5%'  | '1/16W'  | 'IO'       | 'RES CHIP 4.64K 1/16W +-0.5%(0402)'                | 'CHIP0402'     | ''          | ''            | '20140813'
 '1.78K'      | '0.1%'    | '1/16W'  | '0402LF'  | 'CHIP'   | 'CS21782BB00'(!)        = ''              | ''                 | 'CS21782BB00'           |'R0402'| '(R0402-0201)'                 | '1.78K'   | '0.1%'  | '1/16W'  | 'DISCRETE' | 'RES CHIP 1.78K 1/16W +-0.1%(0402)'                | 'CHIP0402'     | ''          | ''            | '20140813'
 '1.78K'      | '0.1%'    | '1/16W'  | '0402LF'  | 'EMPTY'  | 'CS21782BB00'(!)        = ''              | ''                 | 'CS21782BB00'           |'R0402'| '(R0402-0201)'                 | '1.78K'   | '0.1%'  | '1/16W'  | 'IO'       | 'RES CHIP 1.78K 1/16W +-0.1%(0402)'                | 'CHIP0402'     | ''          | ''            | '20140813'
 '2.37K'      | '0.1%'    | '1/16W'  | '0402LF'  | 'CHIP'   | 'CS22372BB00'(!)        = ''              | ''                 | 'CS22372BB00'           |'R0402'| '(R0402-0201)'                 | '2.37K'   | '0.1%'  | '1/16W'  | 'DISCRETE' | 'RES CHIP 2.37K 1/16W +-0.1%(0402)'                | 'CHIP0402'     | ''          | ''            | '20140813'
 '2.37K'      | '0.1%'    | '1/16W'  | '0402LF'  | 'EMPTY'  | 'CS22372BB00'(!)        = ''              | ''                 | 'CS22372BB00'           |'R0402'| '(R0402-0201)'                 | '2.37K'   | '0.1%'  | '1/16W'  | 'IO'       | 'RES CHIP 2.37K 1/16W +-0.1%(0402)'                | 'CHIP0402'     | ''          | ''            | '20140813'
 '11.3K'      | '0.1%'    | '1/16W'  | '0402LF'  | 'CHIP'   | 'CS31132BB00'(!)        = ''              | ''                 | 'CS31132BB00'           |'R0402'| '(R0402-0201)'                 | '11.3K'   | '0.1%'  | '1/16W'  | 'DISCRETE' | 'RES CHIP 11.3K 1/16W +-0.1%(0402)'                | 'CHIP0402'     | ''          | ''            | '20140813'
 '11.3K'      | '0.1%'    | '1/16W'  | '0402LF'  | 'EMPTY'  | 'CS31132BB00'(!)        = ''              | ''                 | 'CS31132BB00'           |'R0402'| '(R0402-0201)'                 | '11.3K'   | '0.1%'  | '1/16W'  | 'IO'       | 'RES CHIP 11.3K 1/16W +-0.1%(0402)'                | 'CHIP0402'     | ''          | ''            | '20140813'
 '18.2K'      | '0.1%'    | '1/16W'  | '0402LF'  | 'CHIP'   | 'CS31822BB00'(!)        = ''              | ''                 | 'CS31822BB00'           |'R0402'| '(R0402-0201)'                 | '18.2K'   | '0.1%'  | '1/16W'  | 'DISCRETE' | 'RES CHIP 18.2K 1/16W +-0.1%(0402)'                | 'CHIP0402'     | ''          | ''            | '20140813'
 '18.2K'      | '0.1%'    | '1/16W'  | '0402LF'  | 'EMPTY'  | 'CS31822BB00'(!)        = ''              | ''                 | 'CS31822BB00'           |'R0402'| '(R0402-0201)'                 | '18.2K'   | '0.1%'  | '1/16W'  | 'IO'       | 'RES CHIP 18.2K 1/16W +-0.1%(0402)'                | 'CHIP0402'     | ''          | ''            | '20140813'
 '4.99K'      | '1%'      | '1/8W'   | '0805LF'  | 'CHIP'   | 'CS24994FA00'(!)        = ''              | ''                 | 'CS24994FA00'           |'R0805'| '(SMR0805AW)'                  | '4.99K'   | '1%'    | '1/8W'   | 'DISCRETE' | 'RES CHIP 4.99K 1/8W +-1%(0805)'                   | 'CHIP0805'     | ''          | ''            | '20140813'
 '4.99K'      | '1%'      | '1/8W'   | '0805LF'  | 'EMPTY'  | 'CS24994FA00'(!)        = ''              | ''                 | 'CS24994FA00'           |'R0805'| '(SMR0805AW)'                  | '4.99K'   | '1%'    | '1/8W'   | 'IO'       | 'RES CHIP 4.99K 1/8W +-1%(0805)'                   | 'CHIP0805'     | ''          | ''            | '20140813'
 '3.65K'      | '1%'      | '1/10W'  | '0603LF'  | 'CHIP'   | 'CS23653F912'(!)        = ''              | ''                 | 'CS23653F912'           |'R0603'| '(SMR0603AW)'                  | '3.65K'   | '1%'    | '1/10W'  | 'DISCRETE' | 'RES CHIP 3.65K 1/10W(+-1%.0603)'                  | 'CHIP0603'     | ''          | ''            | '20140813'
 '3.65K'      | '1%'      | '1/10W'  | '0603LF'  | 'EMPTY'  | 'CS23653F912'(!)        = ''              | ''                 | 'CS23653F912'           |'R0603'| '(SMR0603AW)'                  | '3.65K'   | '1%'    | '1/10W'  | 'IO'       | 'RES CHIP 3.65K 1/10W(+-1%.0603)'                  | 'CHIP0603'     | ''          | ''            | '20140813'
 '2.21K'      | '1%'      | '1/10W'  | '0603LF'  | 'CHIP'   | 'CS22213F925'(!)        = ''              | ''                 | 'CS22213F925'           |'R0603'| '(SMR0603AW)'                  | '2.21K'   | '1%'    | '1/10W'  | 'DISCRETE' | 'RESISTOR CHIP 2.21K 1/10W +-1%(0603)'             | 'CHIP0603'     | ''          | ''            | '20140813'
 '2.21K'      | '1%'      | '1/10W'  | '0603LF'  | 'EMPTY'  | 'CS22213F925'(!)        = ''              | ''                 | 'CS22213F925'           |'R0603'| '(SMR0603AW)'                  | '2.21K'   | '1%'    | '1/10W'  | 'IO'       | 'RESISTOR CHIP 2.21K 1/10W +-1%(0603)'             | 'CHIP0603'     | ''          | ''            | '20140813'
 '0.003'      | '1%'      | '1W'     | '3720LF'  | 'CHIP'   | 'CS+0038FL00'(!)        = ''              | ''                 | 'CS+0038FL00'           |'R3720XA'| '(SMR3720AW)'                  | '0.003'   | '1%'    | '1W'     | 'DISCRETE' | 'RES CHIP 0.003 1W +-1% (3720)'                    | 'CHIP3720'     | ''          | ''            | '20140814'
 '0.003'      | '1%'      | '1W'     | '3720LF'  | 'EMPTY'  | 'CS+0038FL00'(!)        = ''              | ''                 | 'CS+0038FL00'           |'R3720XA'| '(SMR3720AW)'                  | '0.003'   | '1%'    | '1W'     | 'IO'       | 'RES CHIP 0.003 1W +-1% (3720)'                    | 'CHIP3720'     | ''          | ''            | '20140814'
 '43.2K'      | '1%'      | '1/16W'  | '0402LF'  | 'CHIP'   | 'CS34322FB16'(!)        = ''              | 'End of Life'      | 'CS34322FB16'           |'R0402_EOL'| '(R0402-0201)'                 | '43.2K'   | '1%'    | '1/16W'  | 'DISCRETE' | 'RES CHIP 43.2K 1/16W +-1%(0402)'                  | 'CHIP0402'     | ''          | ''            | '20140817'
 '43.2K'      | '1%'      | '1/16W'  | '0402LF'  | 'EMPTY'  | 'CS34322FB16'(!)        = ''              | 'End of Life'      | 'CS34322FB16'           |'R0402_EOL'| '(R0402-0201)'                 | '43.2K'   | '1%'    | '1/16W'  | 'IO'       | 'RES CHIP 43.2K 1/16W +-1%(0402)'                  | 'CHIP0402'     | ''          | ''            | '20140817'
 '147'        | '0.5%'    | '1/16W'  | '0402LF'  | 'CHIP'   | 'CS11472DB00'(!)        = ''              | ''                 | 'CS11472DB00'           |'R0402'| '(R0402-0201)'                 | '147'     | '0.5%'  | '1/16W'  | 'DISCRETE' | 'RES CHIP 147 1/16W +-0.5%(0402)'                  | 'CHIP0402'     | ''          | ''            | '20140817'
 '147'        | '0.5%'    | '1/16W'  | '0402LF'  | 'EMPTY'  | 'CS11472DB00'(!)        = ''              | ''                 | 'CS11472DB00'           |'R0402'| '(R0402-0201)'                 | '147'     | '0.5%'  | '1/16W'  | 'IO'       | 'RES CHIP 147 1/16W +-0.5%(0402)'                  | 'CHIP0402'     | ''          | ''            | '20140817'
 '2.61K'      | '0.5%'    | '1/16W'  | '0402LF'  | 'CHIP'   | 'CS22612DB00'(!)        = ''              | ''                 | 'CS22612DB00'           |'R0402'| '(R0402-0201)'                 | '2.61K'   | '0.5%'  | '1/16W'  | 'DISCRETE' | 'RES CHIP 2.61K 1/16W +-0.5%(0402)'                | 'CHIP0402'     | ''          | ''            | '20140817'
 '2.61K'      | '0.5%'    | '1/16W'  | '0402LF'  | 'EMPTY'  | 'CS22612DB00'(!)        = ''              | ''                 | 'CS22612DB00'           |'R0402'| '(R0402-0201)'                 | '2.61K'   | '0.5%'  | '1/16W'  | 'IO'       | 'RES CHIP 2.61K 1/16W +-0.5%(0402)'                | 'CHIP0402'     | ''          | ''            | '20140817'
 '2.74'       | '1%'      | '1/16W'  | '0402LF'  | 'CHIP'   | 'CS-2742FB00'(!)        = ''              | ''                 | 'CS-2742FB00'           |'R0402'| '(R0402-0201)'                 | '2.74'    | '1%'    | '1/16W'  | 'DISCRETE' | 'RES CHIP 2.74 1/16W +-1%(0402)'                   | 'CHIP0402'     | ''          | ''            | '20140817'
 '2.74'       | '1%'      | '1/16W'  | '0402LF'  | 'EMPTY'  | 'CS-2742FB00'(!)        = ''              | ''                 | 'CS-2742FB00'           |'R0402'| '(R0402-0201)'                 | '2.74'    | '1%'    | '1/16W'  | 'IO'       | 'RES CHIP 2.74 1/16W +-1%(0402)'                   | 'CHIP0402'     | ''          | ''            | '20140817'
 '10K'        | '1%'      | '1W'     | '2010LF'  | 'CHIP'   | 'CS31008FJ00'(!)        = ''              | ''                 | 'CS31008FJ00'           |'R2010XB'| '(SMR2010AW)'                  | '10K'     | '1%'    | '1W'     | 'DISCRETE' | 'RES CHIP 10K 1W +-1%(2010)'                       | 'CHIP2010'     | ''          | ''            | '20140817'
 '10K'        | '1%'      | '1W'     | '2010LF'  | 'EMPTY'  | 'CS31008FJ00'(!)        = ''              | ''                 | 'CS31008FJ00'           |'R2010XB'| '(SMR2010AW)'                  | '10K'     | '1%'    | '1W'     | 'IO'       | 'RES CHIP 10K 1W +-1%(2010)'                       | 'CHIP2010'     | ''          | ''            | '20140817'
 '158'        | '1%'      | '1/16W'  | '0402LF'  | 'CHIP'   | 'CS11582FB00'(!)        = ''              | ''                 | 'CS11582FB00'           |'R0402'| '(R0402-0201)'                 | '158'     | '1%'    | '1/16W'  | 'DISCRETE' | 'RES CHIP 158 1/16W +-1%(0402)'                    | 'CHIP0402'     | ''          | ''            | '20140817'
 '158'        | '1%'      | '1/16W'  | '0402LF'  | 'EMPTY'  | 'CS11582FB00'(!)        = ''              | ''                 | 'CS11582FB00'           |'R0402'| '(R0402-0201)'                 | '158'     | '1%'    | '1/16W'  | 'IO'       | 'RES CHIP 158 1/16W +-1%(0402)'                    | 'CHIP0402'     | ''          | ''            | '20140817'
 '0.007'      | '1%'      | '1W'     | '3720LF'  | 'CHIP'   | 'CS+0078FL00'(!)        = 'End of Design' | 'Comp-Approve'     | 'CS+0078FL00'           |'R3720XA'| '(SMR3720AW)'                  | '0.007'   | '1%'    | '1W'     | 'DISCRETE' | 'RES CHIP 0.007 1W +-1%(3720)'                     | 'CHIP3720'     | ''          | ''            | '20140817'
 '0.007'      | '1%'      | '1W'     | '3720LF'  | 'EMPTY'  | 'CS+0078FL00'(!)        = 'End of Design' | 'Comp-Approve'     | 'CS+0078FL00'           |'R3720XA'| '(SMR3720AW)'                  | '0.007'   | '1%'    | '1W'     | 'IO'       | 'RES CHIP 0.007 1W +-1%(3720)'                     | 'CHIP3720'     | ''          | ''            | '20140817'
 '2.49K'      | '1%'      | '1/2W'   | '1206LF'  | 'CHIP'   | 'CS22497F200'(!)        = ''              | ''                 | 'CS22497F200'           |'R1206'| '(SMR1206AW)'                  | '2.49K'   | '1%'    | '1/2W'   | 'DISCRETE' | 'RES CHIP 2.49K 1/2W +-1%(1206)'                   | 'CHIP1206'     | ''          | ''            | '20140818'
 '2.49K'      | '1%'      | '1/2W'   | '1206LF'  | 'EMPTY'  | 'CS22497F200'(!)        = ''              | ''                 | 'CS22497F200'           |'R1206'| '(SMR1206AW)'                  | '2.49K'   | '1%'    | '1/2W'   | 'IO'       | 'RES CHIP 2.49K 1/2W +-1%(1206)'                   | 'CHIP1206'     | ''          | ''            | '20140818'
 '1.1K'       | '0.1%'    | '1/16W'  | '0402LF'  | 'CHIP'   | 'CS21102BB00'(!)        = ''              | ''                 | 'CS21102BB00'           |'R0402'| '(R0402-0201)'                 | '1.1K'    | '0.1%'  | '1/16W'  | 'DISCRETE' | 'RES CHIP 1.1K 1/16W +-0.1%(0402)'                 | 'CHIP0402'     | ''          | ''            | '20140818'
 '1.1K'       | '0.1%'    | '1/16W'  | '0402LF'  | 'EMPTY'  | 'CS21102BB00'(!)        = ''              | ''                 | 'CS21102BB00'           |'R0402'| '(R0402-0201)'                 | '1.1K'    | '0.1%'  | '1/16W'  | 'IO'       | 'RES CHIP 1.1K 1/16W +-0.1%(0402)'                 | 'CHIP0402'     | ''          | ''            | '20140818'
 '52.3K'      | '1%'      | '1/16W'  | '0402LF'  | 'CHIP'   | 'CS35232FB10'(!)        = 'End of Design' | 'Comp-Approve'     | 'CS35232FB10'           |'R0402'| '(R0402-0201)'                 | '52.3K'   | '1%'    | '1/16W'  | 'DISCRETE' | 'RES CHIP 52.3K 1/16W +-1% (0402)'                 | 'CHIP0402'     | ''          | ''            | '20140818'
 '52.3K'      | '1%'      | '1/16W'  | '0402LF'  | 'EMPTY'  | 'CS35232FB10'(!)        = 'End of Design' | 'Comp-Approve'     | 'CS35232FB10'           |'R0402'| '(R0402-0201)'                 | '52.3K'   | '1%'    | '1/16W'  | 'IO'       | 'RES CHIP 52.3K 1/16W +-1% (0402)'                 | 'CHIP0402'     | ''          | ''            | '20140818'
 '1'          | '1%'      | '1/16W'  | '0402LF'  | 'CHIP'   | 'CS-1002FB23'(!)        = 'End of Design' | 'Comp-Approve'     | 'CS-1002FB23'           |'R0402'| '(R0402-0201)'                 | '1'       | '1%'    | '1/16W'  | 'DISCRETE' | 'RES CHIP 1 1/16W +-1%(0402)'                      | 'CHIP0402'     | ''          | ''            | '20140818'
 '1'          | '1%'      | '1/16W'  | '0402LF'  | 'EMPTY'  | 'CS-1002FB23'(!)        = 'End of Design' | 'Comp-Approve'     | 'CS-1002FB23'           |'R0402'| '(R0402-0201)'                 | '1'       | '1%'    | '1/16W'  | 'IO'       | 'RES CHIP 1 1/16W +-1%(0402)'                      | 'CHIP0402'     | ''          | ''            | '20140818'
 '0.5'        | '1%'      | '1/10W'  | '0603LF'  | 'CHIP'   | 'CS+5003F911'(!)        = ''              | ''                 | 'CS+5003F911'           |'R0603'| '(SMR0603AW)'                  | '0.5'     | '1%'    | '1/10W'  | 'DISCRETE' | 'RES CHIP 0.5 1/10W +-1%(0603)'                    | 'CHIP0603'     | ''          | ''            | '20140818'
 '0.5'        | '1%'      | '1/10W'  | '0603LF'  | 'EMPTY'  | 'CS+5003F911'(!)        = ''              | ''                 | 'CS+5003F911'           |'R0603'| '(SMR0603AW)'                  | '0.5'     | '1%'    | '1/10W'  | 'IO'       | 'RES CHIP 0.5 1/10W +-1%(0603)'                    | 'CHIP0603'     | ''          | ''            | '20140818'
 '1.91K'      | '1%'      | '1/10W'  | '0603LF'  | 'CHIP'   | 'CS21913F910'(!)        = ''              | ''                 | 'CS21913F910'           |'R0603'| '(SMR0603AW)'                  | '1.91K'   | '1%'    | '1/10W'  | 'DISCRETE' | 'RESISTER CHIP 1.91K 1/10W +-1%(0603)'             | 'CHIP0603'     | ''          | ''            | '20140818'
 '1.91K'      | '1%'      | '1/10W'  | '0603LF'  | 'EMPTY'  | 'CS21913F910'(!)        = ''              | ''                 | 'CS21913F910'           |'R0603'| '(SMR0603AW)'                  | '1.91K'   | '1%'    | '1/10W'  | 'IO'       | 'RESISTER CHIP 1.91K 1/10W +-1%(0603)'             | 'CHIP0603'     | ''          | ''            | '20140818'
 '30K'        | '1%'      | '1/10W'  | '0603LF'  | 'CHIP'   | 'CS33003F910'(!)        = ''              | ''                 | 'CS33003F910'           |'R0603'| '(SMR0603AW)'                  | '30K'     | '1%'    | '1/10W'  | 'DISCRETE' | 'RESISTOR CHIP 30K.1/10W.+-1%(0603)'               | 'CHIP0603'     | ''          | ''            | '20140818'
 '30K'        | '1%'      | '1/10W'  | '0603LF'  | 'EMPTY'  | 'CS33003F910'(!)        = ''              | ''                 | 'CS33003F910'           |'R0603'| '(SMR0603AW)'                  | '30K'     | '1%'    | '1/10W'  | 'IO'       | 'RESISTOR CHIP 30K.1/10W.+-1%(0603)'               | 'CHIP0603'     | ''          | ''            | '20140818'
 '0'          | '5%'      | '1W'     | '2512LF'  | 'CHIP'   | 'CS00008J125'(!)        = ''              | ''                 | 'CS00008J125'           |'R2512'| '(SMR2512AW)'                  | '0'       | '5%'    | '1W'     | 'DISCRETE' | 'RESISTOR CHIP 0 1W +-5% (2512)'                   | 'CHIP2512'     | ''          | ''            | '20140818'
 '0'          | '5%'      | '1W'     | '2512LF'  | 'EMPTY'  | 'CS00008J125'(!)        = ''              | ''                 | 'CS00008J125'           |'R2512'| '(SMR2512AW)'                  | '0'       | '5%'    | '1W'     | 'IO'       | 'RESISTOR CHIP 0 1W +-5% (2512)'                   | 'CHIP2512'     | ''          | ''            | '20140818'
 '39.2'       | '1%'      | '1/16W'  | '0402LF'  | 'CHIP'   | 'CS03922FB10'(!)        = 'End of Design' | 'Comp-Approve'     | 'CS03922FB10'           |'R0402'| '(R0402-0201)'                 | '39.2'    | '1%'    | '1/16W'  | 'DISCRETE' | 'RES CHIP 39.2 1/16W +-1%(0402)'                   | 'CHIP0402'     | ''          | ''            | '20140818'
 '39.2'       | '1%'      | '1/16W'  | '0402LF'  | 'EMPTY'  | 'CS03922FB10'(!)        = 'End of Design' | 'Comp-Approve'     | 'CS03922FB10'           |'R0402'| '(R0402-0201)'                 | '39.2'    | '1%'    | '1/16W'  | 'IO'       | 'RES CHIP 39.2 1/16W +-1%(0402)'                   | 'CHIP0402'     | ''          | ''            | '20140818'
 '191K'       | '1%'      | '1/8W'   | '0805LF'  | 'CHIP'   | 'CS41914FA00'(!)        = ''              | ''                 | 'CS41914FA00'           |'R0805'| '(SMR0805AW)'                  | '191K'    | '1%'    | '1/8W'   | 'DISCRETE' | 'RES CHIP 191K 1/8W +-1%(0805)'                    | 'CHIP0805'     | ''          | ''            | '20140819'
 '191K'       | '1%'      | '1/8W'   | '0805LF'  | 'EMPTY'  | 'CS41914FA00'(!)        = ''              | ''                 | 'CS41914FA00'           |'R0805'| '(SMR0805AW)'                  | '191K'    | '1%'    | '1/8W'   | 'IO'       | 'RES CHIP 191K 1/8W +-1%(0805)'                    | 'CHIP0805'     | ''          | ''            | '20140819'
 '28'         | '1%'      | '1/10W'  | '0603LF'  | 'CHIP'   | 'CS02803F900'(!)        = ''              | ''                 | 'CS02803F900'           |'R0603'| '(SMR0603AW)'                  | '28'      | '1%'    | '1/10W'  | 'DISCRETE' | 'RES CHIP 28 1/10W +-1%(0603)'                     | 'CHIP0603'     | ''          | ''            | '20140819'
 '28'         | '1%'      | '1/10W'  | '0603LF'  | 'EMPTY'  | 'CS02803F900'(!)        = ''              | ''                 | 'CS02803F900'           |'R0603'| '(SMR0603AW)'                  | '28'      | '1%'    | '1/10W'  | 'IO'       | 'RES CHIP 28 1/10W +-1%(0603)'                     | 'CHIP0603'     | ''          | ''            | '20140819'
 '52.3'       | '1%'      | '1/10W'  | '0603LF'  | 'CHIP'   | 'CS05233F900'(!)        = ''              | ''                 | 'CS05233F900'           |'R0603'| '(SMR0603AW)'                  | '52.3'    | '1%'    | '1/10W'  | 'DISCRETE' | 'RES CHIP 52.3 1/10W +-1%(0603)'                   | 'CHIP0603'     | ''          | ''            | '20140819'
 '52.3'       | '1%'      | '1/10W'  | '0603LF'  | 'EMPTY'  | 'CS05233F900'(!)        = ''              | ''                 | 'CS05233F900'           |'R0603'| '(SMR0603AW)'                  | '52.3'    | '1%'    | '1/10W'  | 'IO'       | 'RES CHIP 52.3 1/10W +-1%(0603)'                   | 'CHIP0603'     | ''          | ''            | '20140819'
 '0.008'      | '1%'      | '3W'     | '2512LF'  | 'CHIP'   | 'CS+008DFR00'(!)        = ''              | ''                 | 'CS+008DFR00'           |'R2512XA'| '(SMR2512AW)'                  | '0.008'   | '1%'    | '3W'     | 'DISCRETE' | 'RES CHIP 0.008 3W +-1%(2512)'                     | 'CHIP2512'     | ''          | ''            | '20140819'
 '0.008'      | '1%'      | '3W'     | '2512LF'  | 'EMPTY'  | 'CS+008DFR00'(!)        = ''              | ''                 | 'CS+008DFR00'           |'R2512XA'| '(SMR2512AW)'                  | '0.008'   | '1%'    | '3W'     | 'IO'       | 'RES CHIP 0.008 3W +-1%(2512)'                     | 'CHIP2512'     | ''          | ''            | '20140819'
 '0.002'      | '1%'      | '3W'     | '2512LF'  | 'CHIP'   | 'CS+002DFR00'(!)        = ''              | ''                 | 'CS+002DFR00'           |'R2512XJ'| '(SMR2512AW)'                  | '0.002'   | '1%'    | '3W'     | 'DISCRETE' | 'RES CHIP 0.002 3W +-1%(2512)'                     | 'CHIP2512'     | ''          | ''            | '20140819'
 '0.002'      | '1%'      | '3W'     | '2512LF'  | 'EMPTY'  | 'CS+002DFR00'(!)        = ''              | ''                 | 'CS+002DFR00'           |'R2512XJ'| '(SMR2512AW)'                  | '0.002'   | '1%'    | '3W'     | 'IO'       | 'RES CHIP 0.002 3W +-1%(2512)'                     | 'CHIP2512'     | ''          | ''            | '20140819'
 '180'        | '1%'      | '1/4W'   | '1206LF'  | 'CHIP'   | 'CS11806F215'(!)        = ''              | ''                 | 'CS11806F215'           |'R1206'| '(SMR1206AW)'                  | '180'     | '1%'    | '1/4W'   | 'DISCRETE' | 'RES CHIP 180 1/4W(+-1%,3216)'                     | 'CHIP1206'     | ''          | ''            | '20140819'
 '180'        | '1%'      | '1/4W'   | '1206LF'  | 'EMPTY'  | 'CS11806F215'(!)        = ''              | ''                 | 'CS11806F215'           |'R1206'| '(SMR1206AW)'                  | '180'     | '1%'    | '1/4W'   | 'IO'       | 'RES CHIP 180 1/4W(+-1%,3216)'                     | 'CHIP1206'     | ''          | ''            | '20140819'
 '1'          | '5%'      | '1/2W'   | '2010LF'  | 'CHIP'   | 'CS-1007JJ01'(!)        = ''              | ''                 | 'CS-1007JJ01'           |'R2010'| '(SMR2010AW)'                  | '1'       | '5%'    | '1/2W'   | 'DISCRETE' | 'RES CHIP 1 1/2W +-5%(2010)'                       | 'CHIP2010'     | ''          | ''            | '20140826'
 '1'          | '5%'      | '1/2W'   | '2010LF'  | 'EMPTY'  | 'CS-1007JJ01'(!)        = ''              | ''                 | 'CS-1007JJ01'           |'R2010'| '(SMR2010AW)'                  | '1'       | '5%'    | '1/2W'   | 'IO'       | 'RES CHIP 1 1/2W +-5%(2010)'                       | 'CHIP2010'     | ''          | ''            | '20140826'
 '28'         | '1%'      | '1/16W'  | '0402LF'  | 'CHIP'   | 'CS02802FB00'(!)        = ''              | ''                 | 'CS02802FB00'           |'R0402'| '(R0402-0201)'                 | '28'      | '1%'    | '1/16W'  | 'DISCRETE' | 'RES CHIP 28 1/16W +-1%(0402)'                     | 'CHIP0402'     | ''          | ''            | '20140826'
 '28'         | '1%'      | '1/16W'  | '0402LF'  | 'EMPTY'  | 'CS02802FB00'(!)        = ''              | ''                 | 'CS02802FB00'           |'R0402'| '(R0402-0201)'                 | '28'      | '1%'    | '1/16W'  | 'IO'       | 'RES CHIP 28 1/16W +-1%(0402)'                     | 'CHIP0402'     | ''          | ''            | '20140826'
 '3.32K'      | '1%'      | '1/16W'  | '0402LF'  | 'CHIP'   | 'CS23322FB20'(!)        = 'End of Design' | 'Comp-Approve'     | 'CS23322FB20'           |'R0402'| '(R0402-0201)'                 | '3.32K'   | '1%'    | '1/16W'  | 'DISCRETE' | 'RES CHIP 3.32K 1/16W +-1% (0402)'                 | 'CHIP0402'     | ''          | ''            | '20140826'
 '3.32K'      | '1%'      | '1/16W'  | '0402LF'  | 'EMPTY'  | 'CS23322FB20'(!)        = 'End of Design' | 'Comp-Approve'     | 'CS23322FB20'           |'R0402'| '(R0402-0201)'                 | '3.32K'   | '1%'    | '1/16W'  | 'IO'       | 'RES CHIP 3.32K 1/16W +-1% (0402)'                 | 'CHIP0402'     | ''          | ''            | '20140826'
 '200'        | '5%'      | '1W'     | '2512LF'  | 'CHIP'   | 'CS12008JR00'(!)        = ''              | ''                 | 'CS12008JR00'           |'R2512'| '(SMR2512AW)'                  | '200'     | '5%'    | '1W'     | 'DISCRETE' | 'RES CHIP 200 1W +-5%(2512)'                       | 'CHIP2512'     | ''          | ''            | '20140826'
 '200'        | '5%'      | '1W'     | '2512LF'  | 'EMPTY'  | 'CS12008JR00'(!)        = ''              | ''                 | 'CS12008JR00'           |'R2512'| '(SMR2512AW)'                  | '200'     | '5%'    | '1W'     | 'IO'       | 'RES CHIP 200 1W +-5%(2512)'                       | 'CHIP2512'     | ''          | ''            | '20140826'
 '300'        | '5%'      | '1/16W'  | '0402LF'  | 'CHIP'   | 'CS13002JB20'(!)        = 'End of Design' | 'Comp-Approve'     | 'CS13002JB20'           |'R0402'| '(R0402-0201)'                 | '300'     | '5%'    | '1/16W'  | 'DISCRETE' | 'RES CHIP 300 1/16W +-5% (0402)'                   | 'CHIP0402'     | ''          | ''            | '20140902'
 '300'        | '5%'      | '1/16W'  | '0402LF'  | 'EMPTY'  | 'CS13002JB20'(!)        = 'End of Design' | 'Comp-Approve'     | 'CS13002JB20'           |'R0402'| '(R0402-0201)'                 | '300'     | '5%'    | '1/16W'  | 'IO'       | 'RES CHIP 300 1/16W +-5% (0402)'                   | 'CHIP0402'     | ''          | ''            | '20140902'
 '10'         | '5%'      | '1/2W'   | '1210LF'  | 'CHIP'   | 'CS01007J300'(!)        = ''              | ''                 | 'CS01007J300'           |'R1210'| '(SMR1210AW)'                  | '10'      | '5%'    | '1/2W'   | 'DISCRETE' | 'RES CHIP 10 1/2W +-5%(1210)'                      | 'CHIP1210'     | ''          | ''            | '20140910'
 '10'         | '5%'      | '1/2W'   | '1210LF'  | 'EMPTY'  | 'CS01007J300'(!)        = ''              | ''                 | 'CS01007J300'           |'R1210'| '(SMR1210AW)'                  | '10'      | '5%'    | '1/2W'   | 'IO'       | 'RES CHIP 10 1/2W +-5%(1210)'                      | 'CHIP1210'     | ''          | ''            | '20140910'
 '2.1K'       | '0.1%'    | '1/16W'  | '0402LF'  | 'CHIP'   | 'CS22102BB00'(!)        = ''              | ''                 | 'CS22102BB00'           |'R0402'| '(R0402-0201)'                 | '2.1K'    | '0.1%'  | '1/16W'  | 'DISCRETE' | 'RES CHIP 2.1K 1/16W +/-0.1%(0402)'                | 'CHIP0402'     | ''          | ''            | '20140918'
 '2.1K'       | '0.1%'    | '1/16W'  | '0402LF'  | 'EMPTY'  | 'CS22102BB00'(!)        = ''              | ''                 | 'CS22102BB00'           |'R0402'| '(R0402-0201)'                 | '2.1K'    | '0.1%'  | '1/16W'  | 'IO'       | 'RES CHIP 2.1K 1/16W +/-0.1%(0402)'                | 'CHIP0402'     | ''          | ''            | '20140918'
 '1.2K'       | '1%'      | '1/16W'  | '0402LF'  | 'CHIP'   | 'CS21202FB13'(!)        = 'End of Design' | 'Comp-Approve'     | 'CS21202FB13'           |'R0402'| '(R0402-0201)'                 | '1.2K'    | '1%'    | '1/16W'  | 'DISCRETE' | 'RES CHIP 1.2K 1/16W+-1%(0402)'                    | 'CHIP0402'     | ''          | ''            | '20141003'
 '1.2K'       | '1%'      | '1/16W'  | '0402LF'  | 'EMPTY'  | 'CS21202FB13'(!)        = 'End of Design' | 'Comp-Approve'     | 'CS21202FB13'           |'R0402'| '(R0402-0201)'                 | '1.2K'    | '1%'    | '1/16W'  | 'IO'       | 'RES CHIP 1.2K 1/16W+-1%(0402)'                    | 'CHIP0402'     | ''          | ''            | '20141003'
 '10M'        | '1%'      | '1/10W'  | '0603LF'  | 'CHIP'   | 'CS61003F900'(!)        = ''              | ''                 | 'CS61003F900'           |'R0603'| '(SMR0603AW)'                  | '10M'     | '1%'    | '1/10W'  | 'DISCRETE' | 'RES CHIP 10M 1/10W +-1%(0603)'                    | 'CHIP0603'     | ''          | ''            | '20141008'
 '10M'        | '1%'      | '1/10W'  | '0603LF'  | 'EMPTY'  | 'CS61003F900'(!)        = ''              | ''                 | 'CS61003F900'           |'R0603'| '(SMR0603AW)'                  | '10M'     | '1%'    | '1/10W'  | 'IO'       | 'RES CHIP 10M 1/10W +-1%(0603)'                    | 'CHIP0603'     | ''          | ''            | '20141008'
 '200K'       | '0.1%'    | '1/10W'  | '0603LF'  | 'CHIP'   | 'CS42003B901'(!)        = ''              | ''                 | 'CS42003B901'           |'R0603'| '(SMR0603AW)'                  | '200K'    | '0.1%'  | '1/10W'  | 'DISCRETE' | 'RESISTOR CHIP 200K 1/10W +-0.1%(0603)'            | 'CHIP0603'     | ''          | ''            | '20141013'
 '200K'       | '0.1%'    | '1/10W'  | '0603LF'  | 'EMPTY'  | 'CS42003B901'(!)        = ''              | ''                 | 'CS42003B901'           |'R0603'| '(SMR0603AW)'                  | '200K'    | '0.1%'  | '1/10W'  | 'IO'       | 'RESISTOR CHIP 200K 1/10W +-0.1%(0603)'            | 'CHIP0603'     | ''          | ''            | '20141013'
 '0.01'       | '1%'      | '3W'     | '2512LF'  | 'CHIP'   | 'CS+100DFR00'(!)        = ''              | ''                 | 'CS+100DFR00'           |'R2512XA'| '(SMR2512AW)'                  | '0.01'    | '1%'    | '3W'     | 'DISCRETE' | 'RES CHIP 0.01 3W +-1%(2512)'                      | 'CHIP2512'     | ''          | ''            | '20141013'
 '0.01'       | '1%'      | '3W'     | '2512LF'  | 'EMPTY'  | 'CS+100DFR00'(!)        = ''              | ''                 | 'CS+100DFR00'           |'R2512XA'| '(SMR2512AW)'                  | '0.01'    | '1%'    | '3W'     | 'IO'       | 'RES CHIP 0.01 3W +-1%(2512)'                      | 'CHIP2512'     | ''          | ''            | '20141013'
 '113'        | '1%'      | '1/16W'  | '0402LF'  | 'CHIP'   | 'CS11132FB01'(!)        = 'End of Design' | 'Comp-Approve'     | 'CS11132FB01'           |'R0402'| '(R0402-0201)'                 | '113'     | '1%'    | '1/16W'  | 'DISCRETE' | 'RES CHIP 113 1/16W +-1%(0402)'                    | 'CHIP0402'     | ''          | ''            | '20141016'
 '113'        | '1%'      | '1/16W'  | '0402LF'  | 'EMPTY'  | 'CS11132FB01'(!)        = 'End of Design' | 'Comp-Approve'     | 'CS11132FB01'           |'R0402'| '(R0402-0201)'                 | '113'     | '1%'    | '1/16W'  | 'IO'       | 'RES CHIP 113 1/16W +-1%(0402)'                    | 'CHIP0402'     | ''          | ''            | '20141016'
 '249'        | '1%'      | '1/10W'  | '0603LF'  | 'CHIP'   | 'CS12493F935'(!)        = 'End of Design' | 'Comp-Approve'     | 'CS12493F935'           |'R0603'| '(SMR0603AW)'                  | '249'     | '1%'    | '1/10W'  | 'DISCRETE' | 'RES CHIP 249 1/10W +-1%(0603)EP'                  | 'CHIP0603'     | ''          | ''            | '20141016'
 '249'        | '1%'      | '1/10W'  | '0603LF'  | 'EMPTY'  | 'CS12493F935'(!)        = 'End of Design' | 'Comp-Approve'     | 'CS12493F935'           |'R0603'| '(SMR0603AW)'                  | '249'     | '1%'    | '1/10W'  | 'IO'       | 'RES CHIP 249 1/10W +-1%(0603)EP'                  | 'CHIP0603'     | ''          | ''            | '20141016'
 '249'        | '0.1%'    | '1/10W'  | '0603LF'  | 'CHIP'   | 'CS12493B900'(!)        = ''              | ''                 | 'CS12493B900'           |'R0603'| '(SMR0603AW)'                  | '249'     | '0.1%'  | '1/10W'  | 'DISCRETE' | 'RES CHIP 249 1/10W +-0.1%(0603)'                  | 'CHIP0603'     | ''          | ''            | '20141016'
 '249'        | '0.1%'    | '1/10W'  | '0603LF'  | 'EMPTY'  | 'CS12493B900'(!)        = ''              | ''                 | 'CS12493B900'           |'R0603'| '(SMR0603AW)'                  | '249'     | '0.1%'  | '1/10W'  | 'IO'       | 'RES CHIP 249 1/10W +-0.1%(0603)'                  | 'CHIP0603'     | ''          | ''            | '20141016'
 '0.008'      | '1%'      | '1/2W'   | '2010LF'  | 'CHIP'   | 'CS+0087FJ00'(!)        = ''              | ''                 | 'CS+0087FJ00'           |'R2010XC'| '(SMR2010AW)'                  | '0.008'   | '1%'    | '1/2W'   | 'DISCRETE' | 'RES CHIP 0.008 1/2W +-1%(2010)'                   | 'CHIP2010'     | ''          | ''            | '20141020'
 '0.008'      | '1%'      | '1/2W'   | '2010LF'  | 'EMPTY'  | 'CS+0087FJ00'(!)        = ''              | ''                 | 'CS+0087FJ00'           |'R2010XC'| '(SMR2010AW)'                  | '0.008'   | '1%'    | '1/2W'   | 'IO'       | 'RES CHIP 0.008 1/2W +-1%(2010)'                   | 'CHIP2010'     | ''          | ''            | '20141020'
 '0.005'      | '1%'      | '1W'     | '2512LF'  | 'CHIP'   | 'CS+0058F127'(!)        = ''              | ''                 | 'CS+0058F127'           |'R2512'| '(SMR2512AW)'                  | '0.005'   | '1%'    | '1W'     | 'DISCRETE' | 'RES CHIP 0.005 1W +-1%(2512)'                     | 'CHIP2512'     | ''          | ''            | '20141021'
 '0.005'      | '1%'      | '1W'     | '2512LF'  | 'EMPTY'  | 'CS+0058F127'(!)        = ''              | ''                 | 'CS+0058F127'           |'R2512'| '(SMR2512AW)'                  | '0.005'   | '1%'    | '1W'     | 'IO'       | 'RES CHIP 0.005 1W +-1%(2512)'                     | 'CHIP2512'     | ''          | ''            | '20141021'
 '36'         | '1%'      | '1/16W'  | '0402LF'  | 'CHIP'   | 'CS03602FB10'(!)        = 'End of Design' | 'Comp-Approve'     | 'CS03602FB10'           |'R0402'| '(R0402-0201)'                 | '36'      | '1%'    | '1/16W'  | 'DISCRETE' | 'RES CHIP 36 1/16W +-1%(0402)'                     | 'CHIP0402'     | ''          | ''            | '20141021'
 '36'         | '1%'      | '1/16W'  | '0402LF'  | 'EMPTY'  | 'CS03602FB10'(!)        = 'End of Design' | 'Comp-Approve'     | 'CS03602FB10'           |'R0402'| '(R0402-0201)'                 | '36'      | '1%'    | '1/16W'  | 'IO'       | 'RES CHIP 36 1/16W +-1%(0402)'                     | 'CHIP0402'     | ''          | ''            | '20141021'
 '100'        | '0.1%'    | '1/16W'  | '0402LF'  | 'CHIP'   | 'CS11002BB00'(!)        = ''              | ''                 | 'CS11002BB00'           |'R0402'| '(R0402-0201)'                 | '100'     | '0.1%'  | '1/16W'  | 'DISCRETE' | 'RES CHIP 100 1/16W +-0.1%(0402)'                  | 'CHIP0402'     | ''          | ''            | '20141021'
 '100'        | '0.1%'    | '1/16W'  | '0402LF'  | 'EMPTY'  | 'CS11002BB00'(!)        = ''              | ''                 | 'CS11002BB00'           |'R0402'| '(R0402-0201)'                 | '100'     | '0.1%'  | '1/16W'  | 'IO'       | 'RES CHIP 100 1/16W +-0.1%(0402)'                  | 'CHIP0402'     | ''          | ''            | '20141021'
 '0'          | '5%'      | '1/4W'   | '1206LF'  | 'CHIP'   | 'CS00006J248'(!)        = ''              | ''                 | 'CS00006J248'           |'R1206'| '(SMR1206AW)'                  | '0'       | '5%'    | '1/4W'   | 'DISCRETE' | 'RES CHIP 0 1/4W +-5%(1206)'                       | 'CHIP1206'     | ''          | ''            | '20141023'
 '0'          | '5%'      | '1/4W'   | '1206LF'  | 'EMPTY'  | 'CS00006J248'(!)        = ''              | ''                 | 'CS00006J248'           |'R1206'| '(SMR1206AW)'                  | '0'       | '5%'    | '1/4W'   | 'IO'       | 'RES CHIP 0 1/4W +-5%(1206)'                       | 'CHIP1206'     | ''          | ''            | '20141023'
 '7.5K'       | '0.1%'    | '1/16W'  | '0402LF'  | 'CHIP'   | 'CS27502BB00'(!)        = 'End of Design' | 'Comp-Approve'     | 'CS27502BB00'           |'R0402'| '(R0402-0201)'                 | '7.5K'    | '0.1%'  | '1/16W'  | 'DISCRETE' | 'RES CHIP 7.5K 1/16W +-0.1% (0402)'                | 'CHIP0402'     | ''          | ''            | '20141023'
 '7.5K'       | '0.1%'    | '1/16W'  | '0402LF'  | 'EMPTY'  | 'CS27502BB00'(!)        = 'End of Design' | 'Comp-Approve'     | 'CS27502BB00'           |'R0402'| '(R0402-0201)'                 | '7.5K'    | '0.1%'  | '1/16W'  | 'IO'       | 'RES CHIP 7.5K 1/16W +-0.1% (0402)'                | 'CHIP0402'     | ''          | ''            | '20141023'
 '3'          | '5%'      | '1W'     | '2512LF'  | 'CHIP'   | 'CS-3008JR00'(!)        = 'End of Design' | 'Comp-Release Qty' | 'CS-3008JR00'           |'R2512'| '(SMR2512)'                    | '3'       | '5%'    | '1W'     | 'DISCRETE' | 'RESISTOR CHIP 3 1W +-5%(2512)'                    | 'CHIP2512'     | ''          | ''            | '20141028'
 '3'          | '5%'      | '1W'     | '2512LF'  | 'EMPTY'  | 'CS-3008JR00'(!)        = 'End of Design' | 'Comp-Release Qty' | 'CS-3008JR00'           |'R2512'| '(SMR2512)'                    | '3'       | '5%'    | '1W'     | 'IO'       | 'RESISTOR CHIP 3 1W +-5%(2512)'                    | 'CHIP2512'     | ''          | ''            | '20141028'
 '8.25K'      | '0.1%'    | '1/16W'  | '0402LF'  | 'CHIP'   | 'CS28252BB00'(!)        = ''              | ''                 | 'CS28252BB00'           |'R0402'| '(R0402-0201)'                 | '8.25K'   | '0.1%'  | '1/16W'  | 'DISCRETE' | 'RES CHIP 8.25K 1/16W +-0.1%(0402)'                | 'CHIP0402'     | ''          | ''            | '20141029'
 '8.25K'      | '0.1%'    | '1/16W'  | '0402LF'  | 'EMPTY'  | 'CS28252BB00'(!)        = ''              | ''                 | 'CS28252BB00'           |'R0402'| '(R0402-0201)'                 | '8.25K'   | '0.1%'  | '1/16W'  | 'IO'       | 'RES CHIP 8.25K 1/16W +-0.1%(0402)'                | 'CHIP0402'     | ''          | ''            | '20141029'
 '28K'        | '0.1%'    | '1/16W'  | '0402LF'  | 'CHIP'   | 'CS32802BB00'(!)        = ''              | ''                 | 'CS32802BB00'           |'R0402'| '(R0402-0201)'                 | '28K'     | '0.1%'  | '1/16W'  | 'DISCRETE' | 'RES CHIP 28K 1/16W +-0.1%(0402)'                  | 'CHIP0402'     | ''          | ''            | '20141029'
 '28K'        | '0.1%'    | '1/16W'  | '0402LF'  | 'EMPTY'  | 'CS32802BB00'(!)        = ''              | ''                 | 'CS32802BB00'           |'R0402'| '(R0402-0201)'                 | '28K'     | '0.1%'  | '1/16W'  | 'IO'       | 'RES CHIP 28K 1/16W +-0.1%(0402)'                  | 'CHIP0402'     | ''          | ''            | '20141029'
 '22.9K'      | '0.1%'    | '1/16W'  | '0402LF'  | 'CHIP'   | 'CS32292BB00'(!)        = ''              | ''                 | 'CS32292BB00'           |'R0402'| '(R0402-0201)'                 | '22.9K'   | '0.1%'  | '1/16W'  | 'DISCRETE' | 'RES CHIP 22.9K 1/16W +-0.1%(0402)'                | 'CHIP0402'     | ''          | ''            | '20141029'
 '22.9K'      | '0.1%'    | '1/16W'  | '0402LF'  | 'EMPTY'  | 'CS32292BB00'(!)        = ''              | ''                 | 'CS32292BB00'           |'R0402'| '(R0402-0201)'                 | '22.9K'   | '0.1%'  | '1/16W'  | 'IO'       | 'RES CHIP 22.9K 1/16W +-0.1%(0402)'                | 'CHIP0402'     | ''          | ''            | '20141029'
 '22.1K'      | '0.1%'    | '1/16W'  | '0402LF'  | 'CHIP'   | 'CS32212BB00'(!)        = ''              | ''                 | 'CS32212BB00'           |'R0402'| '(R0402-0201)'                 | '22.1K'   | '0.1%'  | '1/16W'  | 'DISCRETE' | 'RES CHIP 22.1K 1/16W +-0.1%(0402)'                | 'CHIP0402'     | ''          | ''            | '20141029'
 '22.1K'      | '0.1%'    | '1/16W'  | '0402LF'  | 'EMPTY'  | 'CS32212BB00'(!)        = ''              | ''                 | 'CS32212BB00'           |'R0402'| '(R0402-0201)'                 | '22.1K'   | '0.1%'  | '1/16W'  | 'IO'       | 'RES CHIP 22.1K 1/16W +-0.1%(0402)'                | 'CHIP0402'     | ''          | ''            | '20141029'
 '12K'        | '0.1%'    | '1/16W'  | '0402LF'  | 'CHIP'   | 'CS31202BB00'(!)        = ''              | ''                 | 'CS31202BB00'           |'R0402'| '(R0402-0201)'                 | '12K'     | '0.1%'  | '1/16W'  | 'DISCRETE' | 'RES CHIP 12K 1/16W +-0.1%(0402)'                  | 'CHIP0402'     | ''          | ''            | '20141029'
 '12K'        | '0.1%'    | '1/16W'  | '0402LF'  | 'EMPTY'  | 'CS31202BB00'(!)        = ''              | ''                 | 'CS31202BB00'           |'R0402'| '(R0402-0201)'                 | '12K'     | '0.1%'  | '1/16W'  | 'IO'       | 'RES CHIP 12K 1/16W +-0.1%(0402)'                  | 'CHIP0402'     | ''          | ''            | '20141029'
 '1.87K'      | '0.1%'    | '1/16W'  | '0402LF'  | 'CHIP'   | 'CS21872B100'(!)        = ''              | ''                 | 'CS21872B100'           |'R0402'| '(R0402-0201)'                 | '1.87K'   | '0.1%'  | '1/16W'  | 'DISCRETE' | 'RES CHIP 1.87K(1/16W,+-0.1%,0402)'                | 'CHIP0402'     | ''          | ''            | '20141111'
 '1.87K'      | '0.1%'    | '1/16W'  | '0402LF'  | 'EMPTY'  | 'CS21872B100'(!)        = ''              | ''                 | 'CS21872B100'           |'R0402'| '(R0402-0201)'                 | '1.87K'   | '0.1%'  | '1/16W'  | 'IO'       | 'RES CHIP 1.87K(1/16W,+-0.1%,0402)'                | 'CHIP0402'     | ''          | ''            | '20141111'
 '10.4K'      | '0.1%'    | '1/16W'  | '0402LF'  | 'CHIP'   | 'CS31042B100'(!)        = ''              | ''                 | 'CS31042B100'           |'R0402'| '(R0402-0201)'                 | '10.4K'   | '0.1%'  | '1/16W'  | 'DISCRETE' | 'RES CHIP 10.4K(1/16W,+-0.1%,0402)'                | 'CHIP0402'     | ''          | ''            | '20141111'
 '10.4K'      | '0.1%'    | '1/16W'  | '0402LF'  | 'EMPTY'  | 'CS31042B100'(!)        = ''              | ''                 | 'CS31042B100'           |'R0402'| '(R0402-0201)'                 | '10.4K'   | '0.1%'  | '1/16W'  | 'IO'       | 'RES CHIP 10.4K(1/16W,+-0.1%,0402)'                | 'CHIP0402'     | ''          | ''            | '20141111'
 '12.7K'      | '0.1%'    | '1/16W'  | '0402LF'  | 'CHIP'   | 'CS31272B100'(!)        = ''              | ''                 | 'CS31272B100'           |'R0402'| '(R0402-0201)'                 | '12.7K'   | '0.1%'  | '1/16W'  | 'DISCRETE' | 'RES CHIP 12.7K(1/16W,+-0.1%,0402)'                | 'CHIP0402'     | ''          | ''            | '20141111'
 '12.7K'      | '0.1%'    | '1/16W'  | '0402LF'  | 'EMPTY'  | 'CS31272B100'(!)        = ''              | ''                 | 'CS31272B100'           |'R0402'| '(R0402-0201)'                 | '12.7K'   | '0.1%'  | '1/16W'  | 'IO'       | 'RES CHIP 12.7K(1/16W,+-0.1%,0402)'                | 'CHIP0402'     | ''          | ''            | '20141111'
 '47K'        | '0.1%'    | '1/16W'  | '0402LF'  | 'CHIP'   | 'CS34702B100'(!)        = ''              | ''                 | 'CS34702B100'           |'R0402'| '(R0402-0201)'                 | '47K'     | '0.1%'  | '1/16W'  | 'DISCRETE' | 'RES CHIP 47K(1/16W,+-0.1%,0402)'                  | 'CHIP0402'     | ''          | ''            | '20141111'
 '47K'        | '0.1%'    | '1/16W'  | '0402LF'  | 'EMPTY'  | 'CS34702B100'(!)        = ''              | ''                 | 'CS34702B100'           |'R0402'| '(R0402-0201)'                 | '47K'     | '0.1%'  | '1/16W'  | 'IO'       | 'RES CHIP 47K(1/16W,+-0.1%,0402)'                  | 'CHIP0402'     | ''          | ''            | '20141111'
 '115K'       | '0.1%'    | '1/16W'  | '0402LF'  | 'CHIP'   | 'CS41152B100'(!)        = ''              | ''                 | 'CS41152B100'           |'R0402'| '(R0402-0201)'                 | '115K'    | '0.1%'  | '1/16W'  | 'DISCRETE' | 'RES CHIP 115K(1/16W,+-0.1%,0402)'                 | 'CHIP0402'     | ''          | ''            | '20141111'
 '115K'       | '0.1%'    | '1/16W'  | '0402LF'  | 'EMPTY'  | 'CS41152B100'(!)        = ''              | ''                 | 'CS41152B100'           |'R0402'| '(R0402-0201)'                 | '115K'    | '0.1%'  | '1/16W'  | 'IO'       | 'RES CHIP 115K(1/16W,+-0.1%,0402)'                 | 'CHIP0402'     | ''          | ''            | '20141111'
 '1.3K'       | '1%'      | '1/8W'   | '0805LF'  | 'CHIP'   | 'CS21304FA00'(!)        = ''              | ''                 | 'CS21304FA00'           |'R0805'| '(SMR0805AW)'                  | '1.3K'    | '1%'    | '1/8W'   | 'DISCRETE' | 'RES CHIP 1.3K 1/8W +-1%(0805)'                    | 'CHIP0805'     | ''          | ''            | '20141128'
 '1.3K'       | '1%'      | '1/8W'   | '0805LF'  | 'EMPTY'  | 'CS21304FA00'(!)        = ''              | ''                 | 'CS21304FA00'           |'R0805'| '(SMR0805AW)'                  | '1.3K'    | '1%'    | '1/8W'   | 'IO'       | 'RES CHIP 1.3K 1/8W +-1%(0805)'                    | 'CHIP0805'     | ''          | ''            | '20141128'
 '249'        | '0.1%'    | '1/16W'  | '0402LF'  | 'CHIP'   | 'CS12492BB00'(!)        = ''              | ''                 | 'CS12492BB00'           |'R0402'| '(R0402-0201)'                 | '249'     | '0.1%'  | '1/16W'  | 'DISCRETE' | 'RES CHIP 249 1/16W +-0.1%(0402)'                  | 'CHIP0402'     | ''          | ''            | '20150106'
 '249'        | '0.1%'    | '1/16W'  | '0402LF'  | 'EMPTY'  | 'CS12492BB00'(!)        = ''              | ''                 | 'CS12492BB00'           |'R0402'| '(R0402-0201)'                 | '249'     | '0.1%'  | '1/16W'  | 'IO'       | 'RES CHIP 249 1/16W +-0.1%(0402)'                  | 'CHIP0402'     | ''          | ''            | '20150106'
 '0.001'      | '1%'      | '3W'     | '2512LF'  | 'CHIP'   | 'CS0000DFR01'(!)        = 'Potential'     | 'End of Life'      | 'CS0000DFR01'           |'R2512XG_EOL'| '(SMR2512AW)'                  | '0.001'   | '1%'    | '3W'     | 'DISCRETE' | 'RES CHIP 0.001 3W(+-1%,2512)'                     | 'CHIP2512'     | ''          | ''            | '20150107'
 '0.001'      | '1%'      | '3W'     | '2512LF'  | 'EMPTY'  | 'CS0000DFR01'(!)        = 'Potential'     | 'End of Life'      | 'CS0000DFR01'           |'R2512XG_EOL'| '(SMR2512AW)'                  | '0.001'   | '1%'    | '3W'     | 'IO'       | 'RES CHIP 0.001 3W(+-1%,2512)'                     | 'CHIP2512'     | ''          | ''            | '20150107'
 '45.3'       | '1%'      | '1/16W'  | '0402LF'  | 'CHIP'   | 'CS04532FB12'(!)        = 'End of Design' | 'Comp-Approve'     | 'CS04532FB12'           |'R0402'| '(R0402-0201)'                 | '45.3'    | '1%'    | '1/16W'  | 'DISCRETE' | 'RES CHIP 45.3 1/16W +-1%( 0402)'                  | 'CHIP0402'     | ''          | ''            | '20150114'
 '45.3'       | '1%'      | '1/16W'  | '0402LF'  | 'EMPTY'  | 'CS04532FB12'(!)        = 'End of Design' | 'Comp-Approve'     | 'CS04532FB12'           |'R0402'| '(R0402-0201)'                 | '45.3'    | '1%'    | '1/16W'  | 'IO'       | 'RES CHIP 45.3 1/16W +-1%( 0402)'                  | 'CHIP0402'     | ''          | ''            | '20150114'
 '270K'       | '1%'      | '1/16W'  | '0402LF'  | 'CHIP'   | 'CS42702FB00'(!)        = ''              | ''                 | 'CS42702FB00'           |'R0402'| '(R0402-0201)'                 | '270K'    | '1%'    | '1/16W'  | 'DISCRETE' | 'RES CHIP 270K 1/16W +-1%(0402)'                   | 'CHIP0402'     | ''          | ''            | '20150127'
 '270K'       | '1%'      | '1/16W'  | '0402LF'  | 'EMPTY'  | 'CS42702FB00'(!)        = ''              | ''                 | 'CS42702FB00'           |'R0402'| '(R0402-0201)'                 | '270K'    | '1%'    | '1/16W'  | 'IO'       | 'RES CHIP 270K 1/16W +-1%(0402)'                   | 'CHIP0402'     | ''          | ''            | '20150127'
 '36'         | '5%'      | '1/16W'  | '0402LF'  | 'CHIP'   | 'CS03602JB00'(!)        = 'End of Design' | 'Comp-Approve'     | 'CS03602JB00'           |'R0402'| '(R0402-0201)'                 | '36'      | '5%'    | '1/16W'  | 'DISCRETE' | 'RES CHIP 36 1/16W +-5%(0402)'                     | 'CHIP0402'     | ''          | ''            | '20150130'
 '36'         | '5%'      | '1/16W'  | '0402LF'  | 'EMPTY'  | 'CS03602JB00'(!)        = 'End of Design' | 'Comp-Approve'     | 'CS03602JB00'           |'R0402'| '(R0402-0201)'                 | '36'      | '5%'    | '1/16W'  | 'IO'       | 'RES CHIP 36 1/16W +-5%(0402)'                     | 'CHIP0402'     | ''          | ''            | '20150130'
 '0.62'       | '5%'      | '15W'    | 'THLF'    | 'CHIP'   | 'CL+620AJ000'(!)        = ''              | ''                 | 'CL+620AJ000'           |'R18949D'| '(R18949D)'                    | '0.62'    | '5%'    | '15W'    | 'DISCRETE' | 'RESISTOR CEMENT 0.62 15W +-5%(SQP)'               | 'R18949D'      | ''          | ''            | '20150130'
 '0.62'       | '5%'      | '15W'    | 'THLF'    | 'EMPTY'  | 'CL+620AJ000'(!)        = ''              | ''                 | 'CL+620AJ000'           |'R18949D'| '(R18949D)'                    | '0.62'    | '5%'    | '15W'    | 'IO'       | 'RESISTOR CEMENT 0.62 15W +-5%(SQP)'               | 'R18949D'      | ''          | ''            | '20150130'
 '0.39'       | '5%'      | '15W'    | 'THLF'    | 'CHIP'   | 'CL+390AJ000'(!)        = ''              | ''                 | 'CL+390AJ000'           |'R18949D'| '(R18949D)'                    | '0.39'    | '5%'    | '15W'    | 'DISCRETE' | 'RESISTOR CEMENT 0.39 15W +-5%(SQP)'               | 'R18949D'      | ''          | ''            | '20150130'
 '0.39'       | '5%'      | '15W'    | 'THLF'    | 'EMPTY'  | 'CL+390AJ000'(!)        = ''              | ''                 | 'CL+390AJ000'           |'R18949D'| '(R18949D)'                    | '0.39'    | '5%'    | '15W'    | 'IO'       | 'RESISTOR CEMENT 0.39 15W +-5%(SQP)'               | 'R18949D'      | ''          | ''            | '20150130'
 '3.16K'      | '1%'      | '1/10W'  | '0603LF'  | 'CHIP'   | 'CS23163F901'(!)        = ''              | ''                 | 'CS23163F901'           |'R0603'| '(SMR0603AW)'                  | '3.16K'   | '1%'    | '1/10W'  | 'DISCRETE' | 'RES CHIP 3.16K 1/10W +-1%(0603)'                  | 'CHIP0603'     | ''          | ''            | '20150203'
 '3.16K'      | '1%'      | '1/10W'  | '0603LF'  | 'EMPTY'  | 'CS23163F901'(!)        = ''              | ''                 | 'CS23163F901'           |'R0603'| '(SMR0603AW)'                  | '3.16K'   | '1%'    | '1/10W'  | 'IO'       | 'RES CHIP 3.16K 1/10W +-1%(0603)'                  | 'CHIP0603'     | ''          | ''            | '20150203'
 '866'        | '1%'      | '1/16W'  | '0402LF'  | 'CHIP'   | 'CS18662FB00'(!)        = 'End of Design' | 'Comp-Approve'     | 'CS18662FB00'           |'R0402'| '(R0402-0201)'                 | '866'     | '1%'    | '1/16W'  | 'DISCRETE' | 'RES CHIP 866 1/16W +-1%(0402)'                    | 'CHIP0402'     | ''          | ''            | '20150203'
 '866'        | '1%'      | '1/16W'  | '0402LF'  | 'EMPTY'  | 'CS18662FB00'(!)        = 'End of Design' | 'Comp-Approve'     | 'CS18662FB00'           |'R0402'| '(R0402-0201)'                 | '866'     | '1%'    | '1/16W'  | 'IO'       | 'RES CHIP 866 1/16W +-1%(0402)'                    | 'CHIP0402'     | ''          | ''            | '20150203'
 '45.3K'      | '1%'      | '1/8W'   | '0805LF'  | 'CHIP'   | 'CS34534FA00'(!)        = ''              | ''                 | 'CS34534FA00'           |'R0805'| '(SMR0805AW)'                  | '45.3K'   | '1%'    | '1/8W'   | 'DISCRETE' | 'RES CHIP 45.3K 1/8W +-1%(0805)'                   | 'CHIP0805'     | ''          | ''            | '20150210'
 '45.3K'      | '1%'      | '1/8W'   | '0805LF'  | 'EMPTY'  | 'CS34534FA00'(!)        = ''              | ''                 | 'CS34534FA00'           |'R0805'| '(SMR0805AW)'                  | '45.3K'   | '1%'    | '1/8W'   | 'IO'       | 'RES CHIP 45.3K 1/8W +-1%(0805)'                   | 'CHIP0805'     | ''          | ''            | '20150210'
 '220K'       | '1%'      | '1/16W'  | '0402LF'  | 'CHIP'   | 'CS42202FB10'(!)        = 'End of Design' | 'Comp-Approve'     | 'CS42202FB10'           |'R0402'| '(R0402-0201)'                 | '220K'    | '1%'    | '1/16W'  | 'DISCRETE' | 'RES CHIP 220K 1/16W +-1%(0402)'                   | 'CHIP0402'     | ''          | ''            | '20150302'
 '220K'       | '1%'      | '1/16W'  | '0402LF'  | 'EMPTY'  | 'CS42202FB10'(!)        = 'End of Design' | 'Comp-Approve'     | 'CS42202FB10'           |'R0402'| '(R0402-0201)'                 | '220K'    | '1%'    | '1/16W'  | 'IO'       | 'RES CHIP 220K 1/16W +-1%(0402)'                   | 'CHIP0402'     | ''          | ''            | '20150302'
 '3.16K'      | '1%'      | '1/10W'  | '0603LF'  | 'CHIP'   | 'CS23163F919'(!)        = ''              | ''                 | 'CS23163F919'           |'R0603'| '(SMR0603AW)'                  | '3.16K'   | '1%'    | '1/10W'  | 'DISCRETE' | 'RESISTER CHIP 3.16K 1/10W +-1%(0603)EP'           | 'CHIP0603'     | ''          | ''            | '20150302'
 '3.16K'      | '1%'      | '1/10W'  | '0603LF'  | 'EMPTY'  | 'CS23163F919'(!)        = ''              | ''                 | 'CS23163F919'           |'R0603'| '(SMR0603AW)'                  | '3.16K'   | '1%'    | '1/10W'  | 'IO'       | 'RESISTER CHIP 3.16K 1/10W +-1%(0603)EP'           | 'CHIP0603'     | ''          | ''            | '20150302'
 '3.9K'       | '5%'      | '1/16W'  | '0402LF'  | 'CHIP'   | 'CS23902JB00'(!)        = 'End of Design' | 'Comp-Approve'     | 'CS23902JB00'           |'R0402'| '(R0402-0201)'                 | '3.9K'    | '5%'    | '1/16W'  | 'DISCRETE' | 'RES CHIP 3.9K 1/16W +-5%(0402)'                   | 'CHIP0402'     | ''          | ''            | '20150303'
 '3.9K'       | '5%'      | '1/16W'  | '0402LF'  | 'EMPTY'  | 'CS23902JB00'(!)        = 'End of Design' | 'Comp-Approve'     | 'CS23902JB00'           |'R0402'| '(R0402-0201)'                 | '3.9K'    | '5%'    | '1/16W'  | 'IO'       | 'RES CHIP 3.9K 1/16W +-5%(0402)'                   | 'CHIP0402'     | ''          | ''            | '20150303'
 '68K'        | '1%'      | '1/16W'  | '0402LF'  | 'CHIP'   | 'CS36802FB00'(!)        = 'End of Design' | 'Comp-Approve'     | 'CS36802FB00'           |'R0402'| '(R0402-0201)'                 | '68K'     | '1%'    | '1/16W'  | 'DISCRETE' | 'RES CHIP 68K 1/16W +-1%(0402)'                    | 'CHIP0402'     | ''          | ''            | '20150303'
 '68K'        | '1%'      | '1/16W'  | '0402LF'  | 'EMPTY'  | 'CS36802FB00'(!)        = 'End of Design' | 'Comp-Approve'     | 'CS36802FB00'           |'R0402'| '(R0402-0201)'                 | '68K'     | '1%'    | '1/16W'  | 'IO'       | 'RES CHIP 68K 1/16W +-1%(0402)'                    | 'CHIP0402'     | ''          | ''            | '20150303'
 '787'        | '1%'      | '1/16W'  | '0402LF'  | 'CHIP'   | 'CS17872FB00'(!)        = 'End of Design' | 'Comp-Approve'     | 'CS17872FB00'           |'R0402'| '(R0402-0201)'                 | '787'     | '1%'    | '1/16W'  | 'DISCRETE' | 'RES CHIP 787 1/16W +-1%(0402)'                    | 'CHIP0402 '    | ''          | ''            | '20150310'
 '787'        | '1%'      | '1/16W'  | '0402LF'  | 'EMPTY'  | 'CS17872FB00'(!)        = 'End of Design' | 'Comp-Approve'     | 'CS17872FB00'           |'R0402'| '(R0402-0201)'                 | '787'     | '1%'    | '1/16W'  | 'IO'       | 'RES CHIP 787 1/16W +-1%(0402)'                    | 'CHIP0402 '    | ''          | ''            | '20150310'
 '787'        | '1%'      | '1/10W'  | '0603LF'  | 'CHIP'   | 'CS17873F901'(!)        = ''              | ''                 | 'CS17873F901'           |'R0603'| '(SMR0603AW)'                  | '787'     | '1%'    | '1/10W'  | 'DISCRETE' | 'RES CHIP 787 1/10W +-1%(0603)'                    | 'CHIP0603'     | ''          | ''            | '20150312'
 '787'        | '1%'      | '1/10W'  | '0603LF'  | 'EMPTY'  | 'CS17873F901'(!)        = ''              | ''                 | 'CS17873F901'           |'R0603'| '(SMR0603AW)'                  | '787'     | '1%'    | '1/10W'  | 'IO'       | 'RES CHIP 787 1/10W +-1%(0603)'                    | 'CHIP0603'     | ''          | ''            | '20150312'
 '866K'       | '1%'      | '1/16W'  | '0402LF'  | 'CHIP'   | 'CS48662FB00'(!)        = 'End of Design' | 'Comp-Approve'     | 'CS48662FB00'           |'R0402'| '(R0402-0201)'                 | '866K'    | '1%'    | '1/16W'  | 'DISCRETE' | 'RES CHIP 866K 1/16W +-1%(0402)'                   | 'CHIP0402'     | ''          | ''            | '20150316'
 '866K'       | '1%'      | '1/16W'  | '0402LF'  | 'EMPTY'  | 'CS48662FB00'(!)        = 'End of Design' | 'Comp-Approve'     | 'CS48662FB00'           |'R0402'| '(R0402-0201)'                 | '866K'    | '1%'    | '1/16W'  | 'IO'       | 'RES CHIP 866K 1/16W +-1%(0402)'                   | 'CHIP0402'     | ''          | ''            | '20150316'
 '2.94K'      | '0.1%'    | '1/16W'  | '0402LF'  | 'CHIP'   | 'CS22942BB00'(!)        = ''              | ''                 | 'CS22942BB00'           |'R0402'| '(R0402-0201)'                 | '2.94K'   | '0.1%'  | '1/16W'  | 'DISCRETE' | 'RES CHIP 2.94K 1/16W +-0.1%(0402)'                | 'CHIP0402 '    | ''          | ''            | '20150324'
 '2.94K'      | '0.1%'    | '1/16W'  | '0402LF'  | 'EMPTY'  | 'CS22942BB00'(!)        = ''              | ''                 | 'CS22942BB00'           |'R0402'| '(R0402-0201)'                 | '2.94K'   | '0.1%'  | '1/16W'  | 'IO'       | 'RES CHIP 2.94K 1/16W +-0.1%(0402)'                | 'CHIP0402 '    | ''          | ''            | '20150324'
 '1.24K'      | '0.1%'    | '1/10W'  | '0603LF'  | 'CHIP'   | 'CS21243B900'(!)        = ''              | ''                 | 'CS21243B900'           |'R0603'| '(SMR0603AW)'                  | '1.24K'   | '0.1%'  | '1/10W'  | 'DISCRETE' | 'RES CHIP 1.24K 1/10W +-0.1%(0603)'                | 'CHIP0603'     | ''          | ''            | '20150324'
 '1.24K'      | '0.1%'    | '1/10W'  | '0603LF'  | 'EMPTY'  | 'CS21243B900'(!)        = ''              | ''                 | 'CS21243B900'           |'R0603'| '(SMR0603AW)'                  | '1.24K'   | '0.1%'  | '1/10W'  | 'IO'       | 'RES CHIP 1.24K 1/10W +-0.1%(0603)'                | 'CHIP0603'     | ''          | ''            | '20150324'
 '3.32K'      | '0.1%'    | '1/10W'  | '0603LF'  | 'CHIP'   | 'CS23323B900'(!)        = ''              | ''                 | 'CS23323B900'           |'R0603'| '(SMR0603AW)'                  | '3.32K'   | '0.1%'  | '1/10W'  | 'DISCRETE' | 'RES CHIP 3.32K 1/10W +-0.1%(0603)'                | 'CHIP0603'     | ''          | ''            | '20150324'
 '3.32K'      | '0.1%'    | '1/10W'  | '0603LF'  | 'EMPTY'  | 'CS23323B900'(!)        = ''              | ''                 | 'CS23323B900'           |'R0603'| '(SMR0603AW)'                  | '3.32K'   | '0.1%'  | '1/10W'  | 'IO'       | 'RES CHIP 3.32K 1/10W +-0.1%(0603)'                | 'CHIP0603'     | ''          | ''            | '20150324'
 '0.51'       | '1%'      | '1/4W'   | '0805LF'  | 'CHIP'   | 'CS+5106FA00'(!)        = ''              | ''                 | 'CS+5106FA00'           |'R0805'| '(SMR0805AW)'                  | '0.51'    | '1%'    | '1/4W'   | 'DISCRETE' | 'RES CHIP 0.51 1/4W.+-1%(0805)'                    | 'CHIP0805'     | ''          | ''            | '20150327'
 '0.51'       | '1%'      | '1/4W'   | '0805LF'  | 'EMPTY'  | 'CS+5106FA00'(!)        = ''              | ''                 | 'CS+5106FA00'           |'R0805'| '(SMR0805AW)'                  | '0.51'    | '1%'    | '1/4W'   | 'IO'       | 'RES CHIP 0.51 1/4W.+-1%(0805)'                    | 'CHIP0805'     | ''          | ''            | '20150327'
 '4.53K'      | '1%'      | '1/10W'  | '0603LF'  | 'CHIP'   | 'CS24533F921'(!)        = ''              | ''                 | 'CS24533F921'           |'R0603'| '(SMR0603AW)'                  | '4.53K'   | '1%'    | '1/10W'  | 'DISCRETE' | 'RESISTOR CHIP 4.53K 1/10W +-1%(0603)'             | 'CHIP0603'     | ''          | ''            | '20150410'
 '4.53K'      | '1%'      | '1/10W'  | '0603LF'  | 'EMPTY'  | 'CS24533F921'(!)        = ''              | ''                 | 'CS24533F921'           |'R0603'| '(SMR0603AW)'                  | '4.53K'   | '1%'    | '1/10W'  | 'IO'       | 'RESISTOR CHIP 4.53K 1/10W +-1%(0603)'             | 'CHIP0603'     | ''          | ''            | '20150410'
 '549'        | '1%'      | '1/16W'  | '0402LF'  | 'CHIP'   | 'CS15492FB29'(!)        = 'End of Design' | 'Comp-Release Qty' | 'CS15492FB29'           |'R0402'| '(R0402-0201)'                 | '549'     | '1%'    | '1/16W'  | 'DISCRETE' | 'RES CHIP 549 1/16W +-1%(0402)'                    | 'CHIP0402 '    | ''          | ''            | '20150328'
 '549'        | '1%'      | '1/16W'  | '0402LF'  | 'EMPTY'  | 'CS15492FB29'(!)        = 'End of Design' | 'Comp-Release Qty' | 'CS15492FB29'           |'R0402'| '(R0402-0201)'                 | '549'     | '1%'    | '1/16W'  | 'IO'       | 'RES CHIP 549 1/16W +-1%(0402)'                    | 'CHIP0402 '    | ''          | ''            | '20150328'
 '100'        | '1%'      | '2W'     | '2512LF'  | 'CHIP'   | 'CS1100AFR00'(!)        = ''              | ''                 | 'CS1100AFR00'           |'R2512'| '(SMR2512AW)'                  | '100'     | '1%'    | '2W'     | 'DISCRETE' | 'RES CHIP 100 2W +-1%(2512)'                       | 'CHIP2512 '    | ''          | ''            | '20150511'
 '100'        | '1%'      | '2W'     | '2512LF'  | 'EMPTY'  | 'CS1100AFR00'(!)        = ''              | ''                 | 'CS1100AFR00'           |'R2512'| '(SMR2512AW)'                  | '100'     | '1%'    | '2W'     | 'IO'       | 'RES CHIP 100 2W +-1%(2512)'                       | 'CHIP2512 '    | ''          | ''            | '20150511'
 '10K'        | '1%'      | '1/20W'  | '0201LF'  | 'CHIP'   | 'CS31001FE14'(!)        = ''              | ''                 | 'CS31001FE14'           |'R0201'| '(SMR0201AW)'                  | '10K'     | '1%'    | '1/20W'  | 'DISCRETE' | 'RES CHIP 10K(1/20W,+-1%,0201)'                    | 'CHIP0201'     | ''          | ''            | '20150511'
 '10K'        | '1%'      | '1/20W'  | '0201LF'  | 'EMPTY'  | 'CS31001FE14'(!)        = ''              | ''                 | 'CS31001FE14'           |'R0201'| '(SMR0201AW)'                  | '10K'     | '1%'    | '1/20W'  | 'IO'       | 'RES CHIP 10K(1/20W,+-1%,0201)'                    | 'CHIP0201'     | ''          | ''            | '20150511'
 '0.005'      | '1%'      | '1/4W'   | '0603LF'  | 'CHIP'   | 'CS+0056F900'(!)        = 'End of Design' | 'Comp-Approve'     | 'CS+0056F900'           |'R0603_H38'| '(SMR0603AW)'                  | '0.005'   | '1%'    | '1/4W'   | 'DISCRETE' | 'RES CHIP 0.005 1/4W +-1%(0603)'                   | 'CHIP0603'     | ''          | ''            | '20150518'
 '0.005'      | '1%'      | '1/4W'   | '0603LF'  | 'EMPTY'  | 'CS+0056F900'(!)        = 'End of Design' | 'Comp-Approve'     | 'CS+0056F900'           |'R0603_H38'| '(SMR0603AW)'                  | '0.005'   | '1%'    | '1/4W'   | 'IO'       | 'RES CHIP 0.005 1/4W +-1%(0603)'                   | 'CHIP0603'     | ''          | ''            | '20150518'
 '69.8'       | '1%'      | '1/16W'  | '0402LF'  | 'CHIP'   | 'CS06982FB00'(!)        = 'End of Design' | 'Comp-Approve'     | 'CS06982FB00'           |'R0402'| '(R0402-0201)'                 | '69.8'    | '1%'    | '1/16W'  | 'DISCRETE' | 'RES CHIP 69.8 1/16W +-1% (0402)'                  | 'CHIP0402 '    | ''          | ''            | '20150522'
 '69.8'       | '1%'      | '1/16W'  | '0402LF'  | 'EMPTY'  | 'CS06982FB00'(!)        = 'End of Design' | 'Comp-Approve'     | 'CS06982FB00'           |'R0402'| '(R0402-0201)'                 | '69.8'    | '1%'    | '1/16W'  | 'IO'       | 'RES CHIP 69.8 1/16W +-1% (0402)'                  | 'CHIP0402 '    | ''          | ''            | '20150522'
 '5.6'        | '1%'      | '1/10W'  | '0603LF'  | 'CHIP'   | 'CS-5603F914'(!)        = 'End of Design' | 'Comp-Approve'     | 'CS-5603F914'           |'R0603'| '(SMR0603AW)'                  | '5.6'     | '1%'    | '1/10W'  | 'DISCRETE' | 'RES CHIP 5.6 1/10W +-1%(0603)'                    | 'CHIP0603'     | ''          | ''            | '20150610'
 '5.6'        | '1%'      | '1/10W'  | '0603LF'  | 'EMPTY'  | 'CS-5603F914'(!)        = 'End of Design' | 'Comp-Approve'     | 'CS-5603F914'           |'R0603'| '(SMR0603AW)'                  | '5.6'     | '1%'    | '1/10W'  | 'IO'       | 'RES CHIP 5.6 1/10W +-1%(0603)'                    | 'CHIP0603'     | ''          | ''            | '20150610'
 '49.9'       | '0.1%'    | '1/16W'  | '0402LF'  | 'CHIP'   | 'CS04992BB01'(!)        = ''              | ''                 | 'CS04992BB01'           |'R0402'| '(R0402-0201)'                 | '49.9'    | '0.1%'  | '1/16W'  | 'DISCRETE' | 'RES CHIP 49.9 1/16W +-0.1%(0402)'                 | 'CHIP0402'     | ''          | ''            | '20150611'
 '49.9'       | '0.1%'    | '1/16W'  | '0402LF'  | 'EMPTY'  | 'CS04992BB01'(!)        = ''              | ''                 | 'CS04992BB01'           |'R0402'| '(R0402-0201)'                 | '49.9'    | '0.1%'  | '1/16W'  | 'IO'       | 'RES CHIP 49.9 1/16W +-0.1%(0402)'                 | 'CHIP0402'     | ''          | ''            | '20150611'
 '59'         | '1%'      | '1/16W'  | '0402LF'  | 'CHIP'   | 'CS05902FB00'(!)        = 'End of Design' | 'Comp-Approve'     | 'CS05902FB00'           |'R0402'| '(R0402-0201)'                 | '59'      | '1%'    | '1/16W'  | 'DISCRETE' | 'RES CHIP 59 1/16W +-1%(0402)'                     | 'CHIP0402'     | ''          | ''            | '20150611'
 '59'         | '1%'      | '1/16W'  | '0402LF'  | 'EMPTY'  | 'CS05902FB00'(!)        = 'End of Design' | 'Comp-Approve'     | 'CS05902FB00'           |'R0402'| '(R0402-0201)'                 | '59'      | '1%'    | '1/16W'  | 'IO'       | 'RES CHIP 59 1/16W +-1%(0402)'                     | 'CHIP0402'     | ''          | ''            | '20150611'
 '475K'       | '1%'      | '1/16W'  | '0402LF'  | 'CHIP'   | 'CS44755FB04'(!)        = ''              | ''                 | 'CS44755FB04'           |'R0402'| '(R0402-0201)'                 | '475K'    | '1%'    | '1/16W'  | 'DISCRETE' | 'RES CHIP 475K 1/16W +-1%(0402)'                   | 'CHIP0402'     | ''          | ''            | '20150612'
 '475K'       | '1%'      | '1/16W'  | '0402LF'  | 'EMPTY'  | 'CS44755FB04'(!)        = ''              | ''                 | 'CS44755FB04'           |'R0402'| '(R0402-0201)'                 | '475K'    | '1%'    | '1/16W'  | 'IO'       | 'RES CHIP 475K 1/16W +-1%(0402)'                   | 'CHIP0402'     | ''          | ''            | '20150612'
 '127K'       | '1%'      | '1/16W'  | '0402LF'  | 'CHIP'   | 'CS41272FB19'(!)        = 'End of Design' | 'Comp-Approve'     | 'CS41272FB19'           |'R0402'| '(R0402-0201)'                 | '127K'    | '1%'    | '1/16W'  | 'DISCRETE' | 'RES CHIP 127K 1/16W +-1%(0402)'                   | 'CHIP0402'     | ''          | ''            | '20150615'
 '127K'       | '1%'      | '1/16W'  | '0402LF'  | 'EMPTY'  | 'CS41272FB19'(!)        = 'End of Design' | 'Comp-Approve'     | 'CS41272FB19'           |'R0402'| '(R0402-0201)'                 | '127K'    | '1%'    | '1/16W'  | 'IO'       | 'RES CHIP 127K 1/16W +-1%(0402)'                   | 'CHIP0402'     | ''          | ''            | '20150615'
 '15.8K'      | '1%'      | '1/16W'  | '0402LF'  | 'CHIP'   | 'CS31582FB12'(!)        = 'End of Design' | 'Comp-Approve'     | 'CS31582FB12'           |'R0402'| '(R0402-0201)'                 | '15.8K'   | '1%'    | '1/16W'  | 'DISCRETE' | 'RES CHIP 15.8K 1/16W +-1% (0402)'                 | 'CHIP0402'     | ''          | ''            | '20150615'
 '15.8K'      | '1%'      | '1/16W'  | '0402LF'  | 'EMPTY'  | 'CS31582FB12'(!)        = 'End of Design' | 'Comp-Approve'     | 'CS31582FB12'           |'R0402'| '(R0402-0201)'                 | '15.8K'   | '1%'    | '1/16W'  | 'IO'       | 'RES CHIP 15.8K 1/16W +-1% (0402)'                 | 'CHIP0402'     | ''          | ''            | '20150615'
 '100K'       | '0.1%'    | '1/16W'  | '0402LF'  | 'CHIP'   | 'CS41002BB06'(!)        = ''              | ''                 | 'CS41002BB06'           |'R0402'| '(R0402-0201)'                 | '100K'    | '0.1%'  | '1/16W'  | 'DISCRETE' | 'RES CHIP 100K 1/16W +-0.1%(0402)'                 | 'CHIP0402'     | ''          | ''            | '20150623'
 '100K'       | '0.1%'    | '1/16W'  | '0402LF'  | 'EMPTY'  | 'CS41002BB06'(!)        = ''              | ''                 | 'CS41002BB06'           |'R0402'| '(R0402-0201)'                 | '100K'    | '0.1%'  | '1/16W'  | 'IO'       | 'RES CHIP 100K 1/16W +-0.1%(0402)'                 | 'CHIP0402'     | ''          | ''            | '20150623'
 '133K'       | '0.1%'    | '1/16W'  | '0402LF'  | 'CHIP'   | 'CS41332BB00'(!)        = ''              | ''                 | 'CS41332BB00'           |'R0402'| '(R0402-0201)'                 | '133K'    | '0.1%'  | '1/16W'  | 'DISCRETE' | 'RES CHIP 133K 1/16W +-0.1%(0402)'                 | 'CHIP0402'     | ''          | ''            | '20150623'
 '133K'       | '0.1%'    | '1/16W'  | '0402LF'  | 'EMPTY'  | 'CS41332BB00'(!)        = ''              | ''                 | 'CS41332BB00'           |'R0402'| '(R0402-0201)'                 | '133K'    | '0.1%'  | '1/16W'  | 'IO'       | 'RES CHIP 133K 1/16W +-0.1%(0402)'                 | 'CHIP0402'     | ''          | ''            | '20150623'
 '5.9K'       | '0.1%'    | '1/16W'  | '0402LF'  | 'CHIP'   | 'CS25902BB00'(!)        = ''              | ''                 | 'CS25902BB00'           |'R0402'| '(R0402-0201)'                 | '5.9K'    | '0.1%'  | '1/16W'  | 'DISCRETE' | 'RES CHIP 5.9K 1/16W +-0.1% (0402)'                | 'CHIP0402'     | ''          | ''            | '20150624'
 '5.9K'       | '0.1%'    | '1/16W'  | '0402LF'  | 'EMPTY'  | 'CS25902BB00'(!)        = ''              | ''                 | 'CS25902BB00'           |'R0402'| '(R0402-0201)'                 | '5.9K'    | '0.1%'  | '1/16W'  | 'IO'       | 'RES CHIP 5.9K 1/16W +-0.1% (0402)'                | 'CHIP0402'     | ''          | ''            | '20150624'
 '118K'       | '0.1%'    | '1/16W'  | '0402LF'  | 'CHIP'   | 'CS41182BB00'(!)        = ''              | ''                 | 'CS41182BB00'           |'R0402'| '(R0402-0201)'                 | '118K'    | '0.1%'  | '1/16W'  | 'DISCRETE' | 'RES CHIP 118K 1/16W +-0.1% (0402)'                | 'CHIP0402'     | ''          | ''            | '20150624'
 '118K'       | '0.1%'    | '1/16W'  | '0402LF'  | 'EMPTY'  | 'CS41182BB00'(!)        = ''              | ''                 | 'CS41182BB00'           |'R0402'| '(R0402-0201)'                 | '118K'    | '0.1%'  | '1/16W'  | 'IO'       | 'RES CHIP 118K 1/16W +-0.1% (0402)'                | 'CHIP0402'     | ''          | ''            | '20150624'
 '16.9K'      | '0.1%'    | '1/16W'  | '0402LF'  | 'CHIP'   | 'CS31692BB00'(!)        = ''              | ''                 | 'CS31692BB00'           |'R0402'| '(R0402-0201)'                 | '16.9K'   | '0.1%'  | '1/16W'  | 'DISCRETE' | 'RES CHIP 16.9K 1/16W +-0.1%(0402)'                | 'CHIP0402'     | ''          | ''            | '20150702'
 '16.9K'      | '0.1%'    | '1/16W'  | '0402LF'  | 'EMPTY'  | 'CS31692BB00'(!)        = ''              | ''                 | 'CS31692BB00'           |'R0402'| '(R0402-0201)'                 | '16.9K'   | '0.1%'  | '1/16W'  | 'IO'       | 'RES CHIP 16.9K 1/16W +-0.1%(0402)'                | 'CHIP0402'     | ''          | ''            | '20150702'
 '7.87K'      | '1%'      | '1/16W'  | '0402LF'  | 'CHIP'   | 'CS27872FB13'(!)        = 'End of Design' | 'Comp-Approve'     | 'CS27872FB13'           |'R0402'| '(R0402-0201)'                 | '7.87K'   | '1%'    | '1/16W'  | 'DISCRETE' | 'RES CHIP 7.87K 1/16W +-1%(0402)'                  | 'CHIP0402'     | ''          | ''            | '20150720'
 '7.87K'      | '1%'      | '1/16W'  | '0402LF'  | 'EMPTY'  | 'CS27872FB13'(!)        = 'End of Design' | 'Comp-Approve'     | 'CS27872FB13'           |'R0402'| '(R0402-0201)'                 | '7.87K'   | '1%'    | '1/16W'  | 'IO'       | 'RES CHIP 7.87K 1/16W +-1%(0402)'                  | 'CHIP0402'     | ''          | ''            | '20150720'
 '158K'       | '1%'      | '1/16W'  | '0402LF'  | 'CHIP'   | 'CS41582FB14'(!)        = 'End of Design' | 'Comp-Approve'     | 'CS41582FB14'           |'R0402'| '(R0402-0201)'                 | '158K'    | '1%'    | '1/16W'  | 'DISCRETE' | 'RES CHIP 158K 1/16W +-1% (0402)'                  | 'CHIP0402'     | ''          | ''            | '20150728'
 '158K'       | '1%'      | '1/16W'  | '0402LF'  | 'EMPTY'  | 'CS41582FB14'(!)        = 'End of Design' | 'Comp-Approve'     | 'CS41582FB14'           |'R0402'| '(R0402-0201)'                 | '158K'    | '1%'    | '1/16W'  | 'IO'       | 'RES CHIP 158K 1/16W +-1% (0402)'                  | 'CHIP0402'     | ''          | ''            | '20150728'
 '15K'        | '1%'      | '1/10W'  | '0603LF'  | 'CHIP'   | 'CS31503F939'(!)        = ''              | ''                 | 'CS31503F939'           |'R0603'| '(SMR0603AW)'                  | '15K'     | '1%'    | '1/10W'  | 'DISCRETE' | 'RESISTOR CHIP 15K 1/10W+-1%(0603)'                | 'CHIP0603'     | ''          | ''            | '20150728'
 '15K'        | '1%'      | '1/10W'  | '0603LF'  | 'EMPTY'  | 'CS31503F939'(!)        = ''              | ''                 | 'CS31503F939'           |'R0603'| '(SMR0603AW)'                  | '15K'     | '1%'    | '1/10W'  | 'IO'       | 'RESISTOR CHIP 15K 1/10W+-1%(0603)'                | 'CHIP0603'     | ''          | ''            | '20150728'
 '2.26M'      | '1%'      | '1/8W'   | '0805LF'  | 'CHIP'   | 'CS52264FA00'(!)        = ''              | ''                 | 'CS52264FA00'           |'R0805'| '(SMR0805AW)'                  | '2.26M'   | '1%'    | '1/8W'   | 'DISCRETE' | 'RES CHIP 2.26M 1/8W +-1% (0805)'                  | 'CHIP0805'     | ''          | ''            | '20150803'
 '2.26M'      | '1%'      | '1/8W'   | '0805LF'  | 'EMPTY'  | 'CS52264FA00'(!)        = ''              | ''                 | 'CS52264FA00'           |'R0805'| '(SMR0805AW)'                  | '2.26M'   | '1%'    | '1/8W'   | 'IO'       | 'RES CHIP 2.26M 1/8W +-1% (0805)'                  | 'CHIP0805'     | ''          | ''            | '20150803'
 '20K'        | '1%'      | '1/8W'   | '0805LF'  | 'CHIP'   | 'CS32004FA00'(!)        = ''              | ''                 | 'CS32004FA00'           |'R0805'| '(SMR0805AW)'                  | '20K'     | '1%'    | '1/8W'   | 'DISCRETE' | 'RES CHIP 20K 1/8W +-1%(0805)'                     | 'CHIP0805'     | ''          | ''            | '20150803'
 '20K'        | '1%'      | '1/8W'   | '0805LF'  | 'EMPTY'  | 'CS32004FA00'(!)        = ''              | ''                 | 'CS32004FA00'           |'R0805'| '(SMR0805AW)'                  | '20K'     | '1%'    | '1/8W'   | 'IO'       | 'RES CHIP 20K 1/8W +-1%(0805)'                     | 'CHIP0805'     | ''          | ''            | '20150803'
 '4.99K'      | '0.1%'    | '1/16W'  | '0402LF'  | 'CHIP'   | 'CS24992BB00'(!)        = ''              | ''                 | 'CS24992BB00'           |'R0402'| '(R0402-0201)'                 | '4.99K'   | '0.1%'  | '1/16W'  | 'DISCRETE' | 'RES CHIP 4.99K 1/16W +-0.1%(0402)'                | 'CHIP0402'     | ''          | ''            | '20150805'
 '4.99K'      | '0.1%'    | '1/16W'  | '0402LF'  | 'EMPTY'  | 'CS24992BB00'(!)        = ''              | ''                 | 'CS24992BB00'           |'R0402'| '(R0402-0201)'                 | '4.99K'   | '0.1%'  | '1/16W'  | 'IO'       | 'RES CHIP 4.99K 1/16W +-0.1%(0402)'                | 'CHIP0402'     | ''          | ''            | '20150805'
 '30K'        | '0.1%'    | '1/16W'  | '0402LF'  | 'CHIP'   | 'CS33002BB00'(!)        = ''              | ''                 | 'CS33002BB00'           |'R0402'| '(R0402-0201)'                 | '30K'     | '0.1%'  | '1/16W'  | 'DISCRETE' | 'RES CHIP 30K 1/16W +-0.1%(0402)HF'                | 'CHIP0402'     | ''          | ''            | '20150805'
 '30K'        | '0.1%'    | '1/16W'  | '0402LF'  | 'EMPTY'  | 'CS33002BB00'(!)        = ''              | ''                 | 'CS33002BB00'           |'R0402'| '(R0402-0201)'                 | '30K'     | '0.1%'  | '1/16W'  | 'IO'       | 'RES CHIP 30K 1/16W +-0.1%(0402)HF'                | 'CHIP0402'     | ''          | ''            | '20150805'
 '24K'        | '0.1%'    | '1/16W'  | '0402LF'  | 'CHIP'   | 'CS32402BB00'(!)        = ''              | ''                 | 'CS32402BB00'           |'R0402'| '(R0402-0201)'                 | '24K'     | '0.1%'  | '1/16W'  | 'DISCRETE' | 'RES CHIP 24K 1/16W +-0.1% (0402)'                 | 'CHIP0402'     | ''          | ''            | '20150805'
 '24K'        | '0.1%'    | '1/16W'  | '0402LF'  | 'EMPTY'  | 'CS32402BB00'(!)        = ''              | ''                 | 'CS32402BB00'           |'R0402'| '(R0402-0201)'                 | '24K'     | '0.1%'  | '1/16W'  | 'IO'       | 'RES CHIP 24K 1/16W +-0.1% (0402)'                 | 'CHIP0402'     | ''          | ''            | '20150805'
 '29.4K'      | '0.1%'    | '1/16W'  | '0402LF'  | 'CHIP'   | 'CS32942BB00'(!)        = ''              | ''                 | 'CS32942BB00'           |'R0402'| '(R0402-0201)'                 | '29.4K'   | '0.1%'  | '1/16W'  | 'DISCRETE' | 'RES CHIP 29.4K 1/16W +-0.1%(0402)'                | 'CHIP0402'     | ''          | ''            | '20150807'
 '29.4K'      | '0.1%'    | '1/16W'  | '0402LF'  | 'EMPTY'  | 'CS32942BB00'(!)        = ''              | ''                 | 'CS32942BB00'           |'R0402'| '(R0402-0201)'                 | '29.4K'   | '0.1%'  | '1/16W'  | 'IO'       | 'RES CHIP 29.4K 1/16W +-0.1%(0402)'                | 'CHIP0402'     | ''          | ''            | '20150807'
 '60.4K'      | '0.1%'    | '1/16W'  | '0402LF'  | 'CHIP'   | 'CS36042BB00'(!)        = ''              | ''                 | 'CS36042BB00'           |'R0402'| '(R0402-0201)'                 | '60.4K'   | '0.1%'  | '1/16W'  | 'DISCRETE' | 'RES CHIP 60.4K 1/16W +-0.1%(0402)'                | 'CHIP0402'     | ''          | ''            | '20150807'
 '60.4K'      | '0.1%'    | '1/16W'  | '0402LF'  | 'EMPTY'  | 'CS36042BB00'(!)        = ''              | ''                 | 'CS36042BB00'           |'R0402'| '(R0402-0201)'                 | '60.4K'   | '0.1%'  | '1/16W'  | 'IO'       | 'RES CHIP 60.4K 1/16W +-0.1%(0402)'                | 'CHIP0402'     | ''          | ''            | '20150807'
 '51.1K'      | '1%'      | '1/16W'  | '0402LF'  | 'CHIP'   | 'CS35112FB17'(!)        = 'End of Design' | 'Comp-Approve'     | 'CS35112FB17'           |'R0402'| '(R0402-0201)'                 | '51.1K'   | '1%'    | '1/16W'  | 'DISCRETE' | 'RES CHIP 51.1K 1/16W +-1%(0402) L-F'              | 'CHIP0402'     | ''          | ''            | '20150810'
 '51.1K'      | '1%'      | '1/16W'  | '0402LF'  | 'EMPTY'  | 'CS35112FB17'(!)        = 'End of Design' | 'Comp-Approve'     | 'CS35112FB17'           |'R0402'| '(R0402-0201)'                 | '51.1K'   | '1%'    | '1/16W'  | 'IO'       | 'RES CHIP 51.1K 1/16W +-1%(0402) L-F'              | 'CHIP0402'     | ''          | ''            | '20150810'
 '475K'       | '1%'      | '1/16W'  | '0402LF'  | 'CHIP'   | 'CS44752FB08'(!)        = 'End of Design' | 'Comp-Approve'     | 'CS44752FB08'           |'R0402'| '(R0402-0201)'                 | '475K'    | '1%'    | '1/16W'  | 'DISCRETE' | 'RES CHIP 475K 1/16W +-1%(0402)'                   | 'CHIP0402'     | ''          | ''            | '20150819'
 '475K'       | '1%'      | '1/16W'  | '0402LF'  | 'EMPTY'  | 'CS44752FB08'(!)        = 'End of Design' | 'Comp-Approve'     | 'CS44752FB08'           |'R0402'| '(R0402-0201)'                 | '475K'    | '1%'    | '1/16W'  | 'IO'       | 'RES CHIP 475K 1/16W +-1%(0402)'                   | 'CHIP0402'     | ''          | ''            | '20150819'
 '6.49K'      | '0.1%'    | '1/16W'  | '0402LF'  | 'CHIP'   | 'CS26492BB00'(!)        = ''              | ''                 | 'CS26492BB00'           |'R0402'| '(R0402-0201)'                 | '6.49K'   | '0.1%'  | '1/16W'  | 'DISCRETE' | 'RES CHIP 6.49K 1/16W +-0.1%(0402)'                | 'CHIP0402'     | ''          | ''            | '20150828'
 '6.49K'      | '0.1%'    | '1/16W'  | '0402LF'  | 'EMPTY'  | 'CS26492BB00'(!)        = ''              | ''                 | 'CS26492BB00'           |'R0402'| '(R0402-0201)'                 | '6.49K'   | '0.1%'  | '1/16W'  | 'IO'       | 'RES CHIP 6.49K 1/16W +-0.1%(0402)'                | 'CHIP0402'     | ''          | ''            | '20150828'
 '6.2K'       | '5%'      | '1/16W'  | '0402LF'  | 'CHIP'   | 'CS26202JB19'(!)        = 'End of Design' | 'Comp-Approve'     | 'CS26202JB19'           |'R0402'| '(R0402-0201)'                 | '6.2K'    | '5%'    | '1/16W'  | 'DISCRETE' | 'RES CHIP 6.2K 1/16W+-5%(0402)'                    | 'CHIP0402'     | ''          | ''            | '20150910'
 '6.2K'       | '5%'      | '1/16W'  | '0402LF'  | 'EMPTY'  | 'CS26202JB19'(!)        = 'End of Design' | 'Comp-Approve'     | 'CS26202JB19'           |'R0402'| '(R0402-0201)'                 | '6.2K'    | '5%'    | '1/16W'  | 'IO'       | 'RES CHIP 6.2K 1/16W+-5%(0402)'                    | 'CHIP0402'     | ''          | ''            | '20150910'
 '85.5K'      | '1%'      | '1/16W'  | '0402LF'  | 'CHIP'   | 'CS38552FB00'(!)        = ''              | ''                 | 'CS38552FB00'           |'R0402'| '(R0402-0201)'                 | '85.5K'   | '1%'    | '1/16W'  | 'DISCRETE' | 'RES CHIP 85.5K 1/16W +-1%(0402)'                  | 'CHIP0402'     | ''          | ''            | '20150915'
 '85.5K'      | '1%'      | '1/16W'  | '0402LF'  | 'EMPTY'  | 'CS38552FB00'(!)        = ''              | ''                 | 'CS38552FB00'           |'R0402'| '(R0402-0201)'                 | '85.5K'   | '1%'    | '1/16W'  | 'IO'       | 'RES CHIP 85.5K 1/16W +-1%(0402)'                  | 'CHIP0402'     | ''          | ''            | '20150915'
 '1.96K'      | '1%'      | '1/16W'  | '0402LF'  | 'CHIP'   | 'CS21962FB08'(!)        = 'End of Design' | 'Comp-Approve'     | 'CS21962FB08'           |'R0402'| '(R0402-0201)'                 | '1.96K'   | '1%'    | '1/16W'  | 'DISCRETE' | 'RES CHIP 1.96K 1/16W +-1%(0402)'                  | 'CHIP0402'     | ''          | ''            | '20151014'
 '1.96K'      | '1%'      | '1/16W'  | '0402LF'  | 'EMPTY'  | 'CS21962FB08'(!)        = 'End of Design' | 'Comp-Approve'     | 'CS21962FB08'           |'R0402'| '(R0402-0201)'                 | '1.96K'   | '1%'    | '1/16W'  | 'IO'       | 'RES CHIP 1.96K 1/16W +-1%(0402)'                  | 'CHIP0402'     | ''          | ''            | '20151014'
 '39'         | '1%'      | '1/16W'  | '0402LF'  | 'CHIP'   | 'CS03902FB11'(!)        = 'End of Design' | 'Comp-Approve'     | 'CS03902FB11'           |'R0402'| '(R0402-0201)'                 | '39'      | '1%'    | '1/16W'  | 'DISCRETE' | 'RES CHIP 39 1/16W +-1%(0402)'                     | 'CHIP0402'     | ''          | ''            | '20151020'
 '39'         | '1%'      | '1/16W'  | '0402LF'  | 'EMPTY'  | 'CS03902FB11'(!)        = 'End of Design' | 'Comp-Approve'     | 'CS03902FB11'           |'R0402'| '(R0402-0201)'                 | '39'      | '1%'    | '1/16W'  | 'IO'       | 'RES CHIP 39 1/16W +-1%(0402)'                     | 'CHIP0402'     | ''          | ''            | '20151020'
 '4.3K'       | '1%'      | '1/16W'  | '0402LF'  | 'CHIP'   | 'CS24302FB07'(!)        = 'End of Design' | 'Comp-Approve'     | 'CS24302FB07'           |'R0402'| '(R0402-0201)'                 | '4.3K'    | '1%'    | '1/16W'  | 'DISCRETE' | 'RES CHIP 4.3K 1/16W +-1%(0402)'                   | 'CHIP0402'     | ''          | ''            | '20151120'
 '4.3K'       | '1%'      | '1/16W'  | '0402LF'  | 'EMPTY'  | 'CS24302FB07'(!)        = 'End of Design' | 'Comp-Approve'     | 'CS24302FB07'           |'R0402'| '(R0402-0201)'                 | '4.3K'    | '1%'    | '1/16W'  | 'IO'       | 'RES CHIP 4.3K 1/16W +-1%(0402)'                   | 'CHIP0402'     | ''          | ''            | '20151120'
 '20K'        | '0.1%'    | '1/16W'  | '0402LF'  | 'CHIP'   | 'CS32002BB00'(!)        = ''              | ''                 | 'CS32002BB00'           |'R0402'| '(R0402-0201)'                 | '20K'     | '0.1%'  | '1/16W'  | 'DISCRETE' | 'RES CHIP 20K 1/16W +-0.1%(0402)'                  | 'CHIP0402'     | ''          | ''            | '20151203'
 '20K'        | '0.1%'    | '1/16W'  | '0402LF'  | 'EMPTY'  | 'CS32002BB00'(!)        = ''              | ''                 | 'CS32002BB00'           |'R0402'| '(R0402-0201)'                 | '20K'     | '0.1%'  | '1/16W'  | 'IO'       | 'RES CHIP 20K 1/16W +-0.1%(0402)'                  | 'CHIP0402'     | ''          | ''            | '20151203'
 '1.69M'      | '1%'      | '1/16W'  | '0402LF'  | 'CHIP'   | 'CS51692FB06'(!)        = ''              | ''                 | 'CS51692FB06'           |'R0402'| '(R0402-0201)'                 | '1.69M'   | '1%'    | '1/16W'  | 'DISCRETE' | 'RES CHIP 1.69M.1/16W +-1%(0402)EP'                | 'CHIP0402'     | ''          | ''            | '20151207'
 '1.69M'      | '1%'      | '1/16W'  | '0402LF'  | 'EMPTY'  | 'CS51692FB06'(!)        = ''              | ''                 | 'CS51692FB06'           |'R0402'| '(R0402-0201)'                 | '1.69M'   | '1%'    | '1/16W'  | 'IO'       | 'RES CHIP 1.69M.1/16W +-1%(0402)EP'                | 'CHIP0402'     | ''          | ''            | '20151207'
 '681K'       | '1%'      | '1/16W'  | '0402LF'  | 'CHIP'   | 'CS46812FB00'(!)        = 'End of Design' | 'Comp-Approve'     | 'CS46812FB00'           |'R0402'| '(R0402-0201)'                 | '681K'    | '1%'    | '1/16W'  | 'DISCRETE' | 'RES CHIP 681K 1/16W +-1%(0402)'                   | 'CHIP0402'     | ''          | ''            | '20151208'
 '681K'       | '1%'      | '1/16W'  | '0402LF'  | 'EMPTY'  | 'CS46812FB00'(!)        = 'End of Design' | 'Comp-Approve'     | 'CS46812FB00'           |'R0402'| '(R0402-0201)'                 | '681K'    | '1%'    | '1/16W'  | 'IO'       | 'RES CHIP 681K 1/16W +-1%(0402)'                   | 'CHIP0402'     | ''          | ''            | '20151208'
 '1.07K'      | '0.1%'    | '1/16W'  | '0402LF'  | 'CHIP'   | 'CS21072BB00'(!)        = ''              | ''                 | 'CS21072BB00'           |'R0402'| '(R0402-0201)'                 | '1.07K'   | '0.1%'  | '1/16W'  | 'DISCRETE' | 'RES CHIP 1.07K 1/16W +-0.1% (0402)'               | 'CHIP0402'     | ''          | ''            | '20151208'
 '1.07K'      | '0.1%'    | '1/16W'  | '0402LF'  | 'EMPTY'  | 'CS21072BB00'(!)        = ''              | ''                 | 'CS21072BB00'           |'R0402'| '(R0402-0201)'                 | '1.07K'   | '0.1%'  | '1/16W'  | 'IO'       | 'RES CHIP 1.07K 1/16W +-0.1% (0402)'               | 'CHIP0402'     | ''          | ''            | '20151208'
 '150'        | '5%'      | '1/16W'  | '0402LF'  | 'CHIP'   | 'TMP_QCS11502JB22'(!)   = 'End of Design' | 'Comp-Approve'     | 'CS11502JB22'           |'R0402'| '(R0402-0201)'                 | '150'     | '5%'    | '1/16W'  | 'DISCRETE' | 'RES CHIP 150 1/16W +-5%(0402)'                    | 'CHIP0402'     | ''          | ''            | '20151222'
 '150'        | '5%'      | '1/16W'  | '0402LF'  | 'EMPTY'  | 'TMP_QCS11502JB22'(!)   = 'End of Design' | 'Comp-Approve'     | 'CS11502JB22'           |'R0402'| '(R0402-0201)'                 | '150'     | '5%'    | '1/16W'  | 'IO'       | 'RES CHIP 150 1/16W +-5%(0402)'                    | 'CHIP0402'     | ''          | ''            | '20151222'
 '0'          | '5%'      | '1/20W'  | '0201LF'  | 'CHIP'   | 'CS00001JE18'(!)        = ''              | ''                 | 'CS00001JE18'           |'R0201'| '(SMR0201AW)'                  | '0'       | '5%'    | '1/20W'  | 'DISCRETE' | 'RES CHIP 0(1/20W,+-5%,0201)'                      | 'CHIP0201'     | ''          | ''            | '20151228'
 '0'          | '5%'      | '1/20W'  | '0201LF'  | 'EMPTY'  | 'CS00001JE18'(!)        = ''              | ''                 | 'CS00001JE18'           |'R0201'| '(SMR0201AW)'                  | '0'       | '5%'    | '1/20W'  | 'IO'       | 'RES CHIP 0(1/20W,+-5%,0201)'                      | 'CHIP0201'     | ''          | ''            | '20151228'
 '249K'       | '1%'      | '1/16W'  | '0402LF'  | 'CHIP'   | 'CS42492FB18'(!)        = 'End of Design' | 'Comp-Approve'     | 'CS42492FB18'           |'R0402'| '(R0402-0201)'                 | '249K'    | '1%'    | '1/16W'  | 'DISCRETE' | 'RES CHIP 249K 1/16W +-1%(0402)EP'                 | 'CHIP0402'     | ''          | ''            | '20151228'
 '249K'       | '1%'      | '1/16W'  | '0402LF'  | 'EMPTY'  | 'CS42492FB18'(!)        = 'End of Design' | 'Comp-Approve'     | 'CS42492FB18'           |'R0402'| '(R0402-0201)'                 | '249K'    | '1%'    | '1/16W'  | 'IO'       | 'RES CHIP 249K 1/16W +-1%(0402)EP'                 | 'CHIP0402'     | ''          | ''            | '20151228'
 '0.001'      | '1%'      | '1W'     | '2512LF'  | 'CHIP'   | 'CS+0018FR03'(!)        = ''              | ''                 | 'CS+0018FR03'           |'R2512A'| '(SMR2512AW)'                  | '0.001'   | '1%'    | '1W'     | 'DISCRETE' | 'RES CHIP 0.001 1W +-1%(2512)AEC'                  | 'CHIP2512'     | ''          | ''            | '20151229'
 '0.001'      | '1%'      | '1W'     | '2512LF'  | 'EMPTY'  | 'CS+0018FR03'(!)        = ''              | ''                 | 'CS+0018FR03'           |'R2512A'| '(SMR2512AW)'                  | '0.001'   | '1%'    | '1W'     | 'IO'       | 'RES CHIP 0.001 1W +-1%(2512)AEC'                  | 'CHIP2512'     | ''          | ''            | '20151229'
 '0.0005'     | '1%'      | '1W'     | '2512LF'  | 'CHIP'   | 'CS00008FR03'(!)        = ''              | ''                 | 'CS00008FR03'           |'R2512A'| '(SMR2512AW)'                  | '0.0005'  | '1%'    | '1W'     | 'DISCRETE' | 'RES CHIP 0.0005 1W +-1%(2512)AEC'                 | 'CHIP2512'     | ''          | ''            | '20160105'
 '0.0005'     | '1%'      | '1W'     | '2512LF'  | 'EMPTY'  | 'CS00008FR03'(!)        = ''              | ''                 | 'CS00008FR03'           |'R2512A'| '(SMR2512AW)'                  | '0.0005'  | '1%'    | '1W'     | 'IO'       | 'RES CHIP 0.0005 1W +-1%(2512)AEC'                 | 'CHIP2512'     | ''          | ''            | '20160105'
 '41.2K'      | '1%'      | '1/16W'  | '0402LF'  | 'CHIP'   | 'CS34122FB19'(!)        = ''              | ''                 | 'CS34122FB19'           |'R0402'| '(R0402-0201)'                 | '41.2K'   | '1%'    | '1/16W'  | 'DISCRETE' | 'RES CHIP 41.2K 1/16W +-1%(0402)'                  | 'CHIP0402'     | ''          | ''            | '20160112'
 '41.2K'      | '1%'      | '1/16W'  | '0402LF'  | 'EMPTY'  | 'CS34122FB19'(!)        = ''              | ''                 | 'CS34122FB19'           |'R0402'| '(R0402-0201)'                 | '41.2K'   | '1%'    | '1/16W'  | 'IO'       | 'RES CHIP 41.2K 1/16W +-1%(0402)'                  | 'CHIP0402'     | ''          | ''            | '20160112'
 '15'         | '1%'      | '1/20W'  | '0201LF'  | 'CHIP'   | 'CS01501FE01'(!)        = ''              | 'End of Life'      | 'CS01501FE01'           |'R0201_EOL'| '(SMR0201AW)'                  | '15'      | '1%'    | '1/20W'  | 'DISCRETE' | 'RES CHIP 15 1/20W +-1%(0201)'                     | 'CHIP0201'     | ''          | ''            | '20160112'
 '15'         | '1%'      | '1/20W'  | '0201LF'  | 'EMPTY'  | 'CS01501FE01'(!)        = ''              | 'End of Life'      | 'CS01501FE01'           |'R0201_EOL'| '(SMR0201AW)'                  | '15'      | '1%'    | '1/20W'  | 'IO'       | 'RES CHIP 15 1/20W +-1%(0201)'                     | 'CHIP0201'     | ''          | ''            | '20160112'
 '1.54M'      | '1%'      | '1/8W'   | '0805LF'  | 'CHIP'   | 'CS51544FA00'(!)        = ''              | ''                 | 'CS51544FA00'           |'R0805'| '(SMR0805AW)'                  | '1.54M'   | '1%'    | '1/8W'   | 'DISCRETE' | 'RES CHIP 1.54M 1/8W +-1% (0805)'                  | 'CHIP0805'     | ''          | ''            | '20160112'
 '1.54M'      | '1%'      | '1/8W'   | '0805LF'  | 'EMPTY'  | 'CS51544FA00'(!)        = ''              | ''                 | 'CS51544FA00'           |'R0805'| '(SMR0805AW)'                  | '1.54M'   | '1%'    | '1/8W'   | 'IO'       | 'RES CHIP 1.54M 1/8W +-1% (0805)'                  | 'CHIP0805'     | ''          | ''            | '20160112'
 '147K'       | '1%'      | '1/16W'  | '0402LF'  | 'CHIP'   | 'CS41472FB04'(!)        = ''              | ''                 | 'CS41472FB04'           |'R0402'| '(R0402-0201)'                 | '147K'    | '1%'    | '1/16W'  | 'DISCRETE' | 'RES CHIP 147K 1/16W +-1%(0402)AEC'                | 'CHIP0402'     | ''          | ''            | '20160111'
 '147K'       | '1%'      | '1/16W'  | '0402LF'  | 'EMPTY'  | 'CS41472FB04'(!)        = ''              | ''                 | 'CS41472FB04'           |'R0402'| '(R0402-0201)'                 | '147K'    | '1%'    | '1/16W'  | 'IO'       | 'RES CHIP 147K 1/16W +-1%(0402)AEC'                | 'CHIP0402'     | ''          | ''            | '20160111'
 '0'          | '1%'      | '1/16W'  | '0402LF'  | 'CHIP'   | 'CS00002FB03'(!)        = ''              | ''                 | 'CS00002FB03'           |'R0402'| '(R0402_OCTAGONXA,R0402-0201)' | '0'       | '1%'    | '1/16W'  | 'DISCRETE' | 'RES CHIP 0 1/16W +-1%(0402)AEC'                   | 'CHIP0402'     | ''          | ''            | '20160111'
 '0'          | '1%'      | '1/16W'  | '0402LF'  | 'EMPTY'  | 'CS00002FB03'(!)        = ''              | ''                 | 'CS00002FB03'           |'R0402'| '(R0402_OCTAGONXA,R0402-0201)' | '0'       | '1%'    | '1/16W'  | 'IO'       | 'RES CHIP 0 1/16W +-1%(0402)AEC'                   | 'CHIP0402'     | ''          | ''            | '20160111'
 '0'          | '5%'      | '1/16W'  | '0402LF'  | 'CHIP'   | 'CS00002JB17'(!)        = ''              | ''                 | 'CS00002JB17'           |'R0402'| '(R0402-0201)'                 | '0'       | '5%'    | '1/16W'  | 'DISCRETE' | 'RES CHIP 0 1/16W +-5%(0402)AEC'                   | 'CHIP0402'     | ''          | ''            | '20160111'
 '0'          | '5%'      | '1/16W'  | '0402LF'  | 'EMPTY'  | 'CS00002JB17'(!)        = ''              | ''                 | 'CS00002JB17'           |'R0402'| '(R0402-0201)'                 | '0'       | '5%'    | '1/16W'  | 'IO'       | 'RES CHIP 0 1/16W +-5%(0402)AEC'                   | 'CHIP0402'     | ''          | ''            | '20160111'
 '1'          | '1%'      | '1/16W'  | '0402LF'  | 'CHIP'   | 'CS-1002FB09'(!)        = ''              | ''                 | 'CS-1002FB09'           |'R0402'| '(R0402-0201)'                 | '1'       | '1%'    | '1/16W'  | 'DISCRETE' | 'RES CHIP 1 1/16W +-1%(0402)AEC'                   | 'CHIP0402'     | ''          | ''            | '20160111'
 '1'          | '1%'      | '1/16W'  | '0402LF'  | 'EMPTY'  | 'CS-1002FB09'(!)        = ''              | ''                 | 'CS-1002FB09'           |'R0402'| '(R0402-0201)'                 | '1'       | '1%'    | '1/16W'  | 'IO'       | 'RES CHIP 1 1/16W +-1%(0402)AEC'                   | 'CHIP0402'     | ''          | ''            | '20160111'
 '1'          | '5%'      | '1/16W'  | '0402LF'  | 'CHIP'   | 'CS-1002JB06'(!)        = ''              | ''                 | 'CS-1002JB06'           |'R0402'| '(R0402-0201)'                 | '1'       | '5%'    | '1/16W'  | 'DISCRETE' | 'RES CHIP 1 1/16W +-5%(0402)AEC'                   | 'CHIP0402'     | ''          | ''            | '20160111'
 '1'          | '5%'      | '1/16W'  | '0402LF'  | 'EMPTY'  | 'CS-1002JB06'(!)        = ''              | ''                 | 'CS-1002JB06'           |'R0402'| '(R0402-0201)'                 | '1'       | '5%'    | '1/16W'  | 'IO'       | 'RES CHIP 1 1/16W +-5%(0402)AEC'                   | 'CHIP0402'     | ''          | ''            | '20160111'
 '1.8K'       | '1%'      | '1/16W'  | '0402LF'  | 'CHIP'   | 'CS21802FB03'(!)        = ''              | ''                 | 'CS21802FB03'           |'R0402'| '(R0402-0201)'                 | '1.8K'    | '1%'    | '1/16W'  | 'DISCRETE' | 'RES CHIP 1.8K 1/16W +-1%(0402)AEC'                | 'CHIP0402'     | ''          | ''            | '20160111'
 '1.8K'       | '1%'      | '1/16W'  | '0402LF'  | 'EMPTY'  | 'CS21802FB03'(!)        = ''              | ''                 | 'CS21802FB03'           |'R0402'| '(R0402-0201)'                 | '1.8K'    | '1%'    | '1/16W'  | 'IO'       | 'RES CHIP 1.8K 1/16W +-1%(0402)AEC'                | 'CHIP0402'     | ''          | ''            | '20160111'
 '10'         | '1%'      | '1/16W'  | '0402LF'  | 'CHIP'   | 'CS01002FB11'(!)        = ''              | ''                 | 'CS01002FB11'           |'R0402'| '(R0402-0201)'                 | '10'      | '1%'    | '1/16W'  | 'DISCRETE' | 'RES CHIP 10 1/16W +-1%(0402)AEC'                  | 'CHIP0402'     | ''          | ''            | '20160111'
 '10'         | '1%'      | '1/16W'  | '0402LF'  | 'EMPTY'  | 'CS01002FB11'(!)        = ''              | ''                 | 'CS01002FB11'           |'R0402'| '(R0402-0201)'                 | '10'      | '1%'    | '1/16W'  | 'IO'       | 'RES CHIP 10 1/16W +-1%(0402)AEC'                  | 'CHIP0402'     | ''          | ''            | '20160111'
 '100'        | '0.1%'    | '1/16W'  | '0402LF'  | 'CHIP'   | 'CS11002BB01'(!)        = ''              | ''                 | 'CS11002BB01'           |'R0402'| '(R0402-0201)'                 | '100'     | '0.1%'  | '1/16W'  | 'DISCRETE' | 'RES CHIP 100 1/16W +-0.1%(0402)AEC'               | 'CHIP0402'     | ''          | ''            | '20160111'
 '100'        | '0.1%'    | '1/16W'  | '0402LF'  | 'EMPTY'  | 'CS11002BB01'(!)        = ''              | ''                 | 'CS11002BB01'           |'R0402'| '(R0402-0201)'                 | '100'     | '0.1%'  | '1/16W'  | 'IO'       | 'RES CHIP 100 1/16W +-0.1%(0402)AEC'               | 'CHIP0402'     | ''          | ''            | '20160111'
 '100'        | '1%'      | '1/16W'  | '0402LF'  | 'CHIP'   | 'CS11002FB11'(!)        = ''              | ''                 | 'CS11002FB11'           |'R0402'| '(R0402-0201)'                 | '100'     | '1%'    | '1/16W'  | 'DISCRETE' | 'RES CHIP 100 1/16W +-1%(0402)AEC'                 | 'CHIP0402'     | ''          | ''            | '20160111'
 '100'        | '1%'      | '1/16W'  | '0402LF'  | 'EMPTY'  | 'CS11002FB11'(!)        = ''              | ''                 | 'CS11002FB11'           |'R0402'| '(R0402-0201)'                 | '100'     | '1%'    | '1/16W'  | 'IO'       | 'RES CHIP 100 1/16W +-1%(0402)AEC'                 | 'CHIP0402'     | ''          | ''            | '20160111'
 '100K'       | '0.1%'    | '1/16W'  | '0402LF'  | 'CHIP'   | 'CS41002BB02'(!)        = ''              | ''                 | 'CS41002BB02'           |'R0402'| '(R0402-0201)'                 | '100K'    | '0.1%'  | '1/16W'  | 'DISCRETE' | 'RES CHIP 100K 1/16W +-0.1%(0402)AEC'              | 'CHIP0402'     | ''          | ''            | '20160111'
 '100K'       | '0.1%'    | '1/16W'  | '0402LF'  | 'EMPTY'  | 'CS41002BB02'(!)        = ''              | ''                 | 'CS41002BB02'           |'R0402'| '(R0402-0201)'                 | '100K'    | '0.1%'  | '1/16W'  | 'IO'       | 'RES CHIP 100K 1/16W +-0.1%(0402)AEC'              | 'CHIP0402'     | ''          | ''            | '20160111'
 '100K'       | '1%'      | '1/16W'  | '0402LF'  | 'CHIP'   | 'CS41002FB16'(!)        = ''              | ''                 | 'CS41002FB16'           |'R0402'| '(R0402-0201)'                 | '100K'    | '1%'    | '1/16W'  | 'DISCRETE' | 'RES CHIP 100K 1/16W +-1%(0402)AEC'                | 'CHIP0402'     | ''          | ''            | '20160113'
 '100K'       | '1%'      | '1/16W'  | '0402LF'  | 'EMPTY'  | 'CS41002FB16'(!)        = ''              | ''                 | 'CS41002FB16'           |'R0402'| '(R0402-0201)'                 | '100K'    | '1%'    | '1/16W'  | 'IO'       | 'RES CHIP 100K 1/16W +-1%(0402)AEC'                | 'CHIP0402'     | ''          | ''            | '20160113'
 '10K'        | '0.1%'    | '1/16W'  | '0402LF'  | 'CHIP'   | 'CS31002BB05'(!)        = ''              | ''                 | 'CS31002BB05'           |'R0402'| '(R0402-0201)'                 | '10K'     | '0.1%'  | '1/16W'  | 'DISCRETE' | 'RES CHIP 10K 1/16W +-0.1%(0402)AEC'               | 'CHIP0402'     | ''          | ''            | '20160113'
 '10K'        | '0.1%'    | '1/16W'  | '0402LF'  | 'EMPTY'  | 'CS31002BB05'(!)        = ''              | ''                 | 'CS31002BB05'           |'R0402'| '(R0402-0201)'                 | '10K'     | '0.1%'  | '1/16W'  | 'IO'       | 'RES CHIP 10K 1/16W +-0.1%(0402)AEC'               | 'CHIP0402'     | ''          | ''            | '20160113'
 '10K'        | '1%'      | '1/16W'  | '0402LF'  | 'CHIP'   | 'CS31002FB13'(!)        = ''              | ''                 | 'CS31002FB13'           |'R0402'| '(R0402-0201)'                 | '10K'     | '1%'    | '1/16W'  | 'DISCRETE' | 'RES CHIP 10K 1/16W +-1%(0402)AEC'                 | 'CHIP0402'     | ''          | ''            | '20160113'
 '10K'        | '1%'      | '1/16W'  | '0402LF'  | 'EMPTY'  | 'CS31002FB13'(!)        = ''              | ''                 | 'CS31002FB13'           |'R0402'| '(R0402-0201)'                 | '10K'     | '1%'    | '1/16W'  | 'IO'       | 'RES CHIP 10K 1/16W +-1%(0402)AEC'                 | 'CHIP0402'     | ''          | ''            | '20160113'
 '10K'        | '5%'      | '1/16W'  | '0402LF'  | 'CHIP'   | 'CS31002JB09'(!)        = ''              | ''                 | 'CS31002JB09'           |'R0402'| '(R0402-0201)'                 | '10K'     | '5%'    | '1/16W'  | 'DISCRETE' | 'RES CHIP 10K 1/16W +-5%(0402)AEC'                 | 'CHIP0402'     | ''          | ''            | '20160113'
 '10K'        | '5%'      | '1/16W'  | '0402LF'  | 'EMPTY'  | 'CS31002JB09'(!)        = ''              | ''                 | 'CS31002JB09'           |'R0402'| '(R0402-0201)'                 | '10K'     | '5%'    | '1/16W'  | 'IO'       | 'RES CHIP 10K 1/16W +-5%(0402)AEC'                 | 'CHIP0402'     | ''          | ''            | '20160113'
 '11.8K'      | '1%'      | '1/16W'  | '0402LF'  | 'CHIP'   | 'CS31182FB04'(!)        = ''              | ''                 | 'CS31182FB04'           |'R0402'| '(R0402-0201)'                 | '11.8K'   | '1%'    | '1/16W'  | 'DISCRETE' | 'RES CHIP 11.8K 1/16W +-1%(0402)AEC'               | 'CHIP0402'     | ''          | ''            | '20160113'
 '11.8K'      | '1%'      | '1/16W'  | '0402LF'  | 'EMPTY'  | 'CS31182FB04'(!)        = ''              | ''                 | 'CS31182FB04'           |'R0402'| '(R0402-0201)'                 | '11.8K'   | '1%'    | '1/16W'  | 'IO'       | 'RES CHIP 11.8K 1/16W +-1%(0402)AEC'               | 'CHIP0402'     | ''          | ''            | '20160113'
 '43K'        | '1%'      | '1/10W'  | '0603LF'  | 'CHIP'   | 'CS34303F901'(!)        = 'End of Design' | 'Comp-Approve'     | 'CS34303F901'           |'R0603'| '(SMR0603AW)'                  | '43K'     | '1%'    | '1/10W'  | 'DISCRETE' | 'RES CHIP 43K 1/10W +-1%(0603)'                    | 'CHIPR0603'    | ''          | ''            | '20160115'
 '43K'        | '1%'      | '1/10W'  | '0603LF'  | 'EMPTY'  | 'CS34303F901'(!)        = 'End of Design' | 'Comp-Approve'     | 'CS34303F901'           |'R0603'| '(SMR0603AW)'                  | '43K'     | '1%'    | '1/10W'  | 'IO'       | 'RES CHIP 43K 1/10W +-1%(0603)'                    | 'CHIPR0603'    | ''          | ''            | '20160115'
 '1K'         | '1%'      | '1/16W'  | '0402LF'  | 'CHIP'   | 'CS21002BB01'(!)        = ''              | 'End of Life'      | 'CS21002BB01'           |'R0402_EOL'| '(R0402-0201)'                 | '1K'      | '1%'    | '1/16W'  | 'DISCRETE' | 'RES CHIP 1K 1/16W +-0.1%(0402)AEC'                | 'CHIPR0402'    | ''          | ''            | '20160115'
 '1K'         | '1%'      | '1/16W'  | '0402LF'  | 'EMPTY'  | 'CS21002BB01'(!)        = ''              | 'End of Life'      | 'CS21002BB01'           |'R0402_EOL'| '(R0402-0201)'                 | '1K'      | '1%'    | '1/16W'  | 'IO'       | 'RES CHIP 1K 1/16W +-0.1%(0402)AEC'                | 'CHIPR0402'    | ''          | ''            | '20160115'
 '0.005'      | '1%'      | '1W'     | '2512LF'  | 'CHIP'   | 'CS+0058FR02'(!)        = 'Non-Preferred' | 'End of Life'      | 'CS+0058FR02'           |'R2512A_EOL'| '(SMR2512AW)'                  | '0.005'   | '1%'    | '1W'     | 'DISCRETE' | 'RES CHIP 0.005 1W +-1%(2512)AEC'                  | 'CHIP2512'     | ''          | ''            | '20160115'
 '0.005'      | '1%'      | '1W'     | '2512LF'  | 'EMPTY'  | 'CS+0058FR02'(!)        = 'Non-Preferred' | 'End of Life'      | 'CS+0058FR02'           |'R2512A_EOL'| '(SMR2512AW)'                  | '0.005'   | '1%'    | '1W'     | 'IO'       | 'RES CHIP 0.005 1W +-1%(2512)AEC'                  | 'CHIP2512'     | ''          | ''            | '20160115'
 '113'        | '1%'      | '1/16W'  | '0402LF'  | 'CHIP'   | 'CS11132FB04'(!)        = ''              | ''                 | 'CS11132FB04'           |'R0402'| '(R0402-0201)'                 | '113'     | '1%'    | '1/16W'  | 'DISCRETE' | 'RES CHIP 113 1/16W +-1%(0402)AEC'                 | 'CHIP0402'     | ''          | ''            | '20160116'
 '113'        | '1%'      | '1/16W'  | '0402LF'  | 'EMPTY'  | 'CS11132FB04'(!)        = ''              | ''                 | 'CS11132FB04'           |'R0402'| '(R0402-0201)'                 | '113'     | '1%'    | '1/16W'  | 'IO'       | 'RES CHIP 113 1/16W +-1%(0402)AEC'                 | 'CHIP0402'     | ''          | ''            | '20160116'
 '115K'       | '1%'      | '1/16W'  | '0402LF'  | 'CHIP'   | 'CS41152FB01'(!)        = ''              | ''                 | 'CS41152FB01'           |'R0402'| '(R0402-0201)'                 | '115K'    | '1%'    | '1/16W'  | 'DISCRETE' | 'RES CHIP 115K 1/16W +-1%(0402)AEC'                | 'CHIP0402'     | ''          | ''            | '20160116'
 '115K'       | '1%'      | '1/16W'  | '0402LF'  | 'EMPTY'  | 'CS41152FB01'(!)        = ''              | ''                 | 'CS41152FB01'           |'R0402'| '(R0402-0201)'                 | '115K'    | '1%'    | '1/16W'  | 'IO'       | 'RES CHIP 115K 1/16W +-1%(0402)AEC'                | 'CHIP0402'     | ''          | ''            | '20160116'
 '12.1K'      | '1%'      | '1/16W'  | '0402LF'  | 'CHIP'   | 'CS31212FB06'(!)        = ''              | ''                 | 'CS31212FB06'           |'R0402'| '(R0402-0201)'                 | '12.1K'   | '1%'    | '1/16W'  | 'DISCRETE' | 'RES CHIP 12.1K 1/16W +-1%(0402)AEC'               | 'CHIP0402'     | ''          | ''            | '20160116'
 '12.1K'      | '1%'      | '1/16W'  | '0402LF'  | 'EMPTY'  | 'CS31212FB06'(!)        = ''              | ''                 | 'CS31212FB06'           |'R0402'| '(R0402-0201)'                 | '12.1K'   | '1%'    | '1/16W'  | 'IO'       | 'RES CHIP 12.1K 1/16W +-1%(0402)AEC'               | 'CHIP0402'     | ''          | ''            | '20160116'
 '120'        | '1%'      | '1/16W'  | '0402LF'  | 'CHIP'   | 'CS11202FB04'(!)        = ''              | ''                 | 'CS11202FB04'           |'R0402'| '(R0402-0201)'                 | '120'     | '1%'    | '1/16W'  | 'DISCRETE' | 'RES CHIP 120 1/16W +-1%(0402)AEC'                 | 'CHIP0402'     | ''          | ''            | '20160116'
 '120'        | '1%'      | '1/16W'  | '0402LF'  | 'EMPTY'  | 'CS11202FB04'(!)        = ''              | ''                 | 'CS11202FB04'           |'R0402'| '(R0402-0201)'                 | '120'     | '1%'    | '1/16W'  | 'IO'       | 'RES CHIP 120 1/16W +-1%(0402)AEC'                 | 'CHIP0402'     | ''          | ''            | '20160116'
 '12K'        | '1%'      | '1/16W'  | '0402LF'  | 'CHIP'   | 'CS31202FB05'(!)        = ''              | ''                 | 'CS31202FB05'           |'R0402'| '(R0402-0201)'                 | '12K'     | '1%'    | '1/16W'  | 'DISCRETE' | 'RES CHIP 12K 1/16W +-1%(0402)AEC'                 | 'CHIP0402'     | ''          | ''            | '20160116'
 '12K'        | '1%'      | '1/16W'  | '0402LF'  | 'EMPTY'  | 'CS31202FB05'(!)        = ''              | ''                 | 'CS31202FB05'           |'R0402'| '(R0402-0201)'                 | '12K'     | '1%'    | '1/16W'  | 'IO'       | 'RES CHIP 12K 1/16W +-1%(0402)AEC'                 | 'CHIP0402'     | ''          | ''            | '20160116'
 '15'         | '1%'      | '1/16W'  | '0402LF'  | 'CHIP'   | 'CS01502FB04'(!)        = ''              | ''                 | 'CS01502FB04'           |'R0402'| '(R0402-0201)'                 | '15'      | '1%'    | '1/16W'  | 'DISCRETE' | 'RES CHIP 15 1/16W +-1%(0402)AEC'                  | 'CHIP0402'     | ''          | ''            | '20160116'
 '15'         | '1%'      | '1/16W'  | '0402LF'  | 'EMPTY'  | 'CS01502FB04'(!)        = ''              | ''                 | 'CS01502FB04'           |'R0402'| '(R0402-0201)'                 | '15'      | '1%'    | '1/16W'  | 'IO'       | 'RES CHIP 15 1/16W +-1%(0402)AEC'                  | 'CHIP0402'     | ''          | ''            | '20160116'
 '15.8K'      | '1%'      | '1/16W'  | '0402LF'  | 'CHIP'   | 'CS31582FB03'(!)        = ''              | ''                 | 'CS31582FB03'           |'R0402'| '(R0402-0201)'                 | '15.8K'   | '1%'    | '1/16W'  | 'DISCRETE' | 'RES CHIP 15.8K 1/16W +-1%(0402)AEC'               | 'CHIP0402'     | ''          | ''            | '20160116'
 '15.8K'      | '1%'      | '1/16W'  | '0402LF'  | 'EMPTY'  | 'CS31582FB03'(!)        = ''              | ''                 | 'CS31582FB03'           |'R0402'| '(R0402-0201)'                 | '15.8K'   | '1%'    | '1/16W'  | 'IO'       | 'RES CHIP 15.8K 1/16W +-1%(0402)AEC'               | 'CHIP0402'     | ''          | ''            | '20160116'
 '150'        | '1%'      | '1/16W'  | '0402LF'  | 'CHIP'   | 'CS11502FB08'(!)        = ''              | ''                 | 'CS11502FB08'           |'R0402'| '(R0402-0201)'                 | '150'     | '1%'    | '1/16W'  | 'DISCRETE' | 'RES CHIP 150 1/16W +-1%(0402)AEC'                 | 'CHIP0402'     | ''          | ''            | '20160116'
 '150'        | '1%'      | '1/16W'  | '0402LF'  | 'EMPTY'  | 'CS11502FB08'(!)        = ''              | ''                 | 'CS11502FB08'           |'R0402'| '(R0402-0201)'                 | '150'     | '1%'    | '1/16W'  | 'IO'       | 'RES CHIP 150 1/16W +-1%(0402)AEC'                 | 'CHIP0402'     | ''          | ''            | '20160116'
 '150'        | '5%'      | '1/16W'  | '0402LF'  | 'CHIP'   | 'CS11502JB03'(!)        = ''              | ''                 | 'CS11502JB03'           |'R0402'| '(R0402-0201)'                 | '150'     | '5%'    | '1/16W'  | 'DISCRETE' | 'RES CHIP 150 1/16W +-5%(0402)AEC'                 | 'CHIP0402'     | ''          | ''            | '20160116'
 '150'        | '5%'      | '1/16W'  | '0402LF'  | 'EMPTY'  | 'CS11502JB03'(!)        = ''              | ''                 | 'CS11502JB03'           |'R0402'| '(R0402-0201)'                 | '150'     | '5%'    | '1/16W'  | 'IO'       | 'RES CHIP 150 1/16W +-5%(0402)AEC'                 | 'CHIP0402'     | ''          | ''            | '20160116'
 '150K'       | '1%'      | '1/16W'  | '0402LF'  | 'CHIP'   | 'CS41502FB05'(!)        = ''              | ''                 | 'CS41502FB05'           |'R0402'| '(R0402-0201)'                 | '150K'    | '1%'    | '1/16W'  | 'DISCRETE' | 'RES CHIP 150K 1/16W +-1%(0402)AEC'                | 'CHIP0402'     | ''          | ''            | '20160116'
 '150K'       | '1%'      | '1/16W'  | '0402LF'  | 'EMPTY'  | 'CS41502FB05'(!)        = ''              | ''                 | 'CS41502FB05'           |'R0402'| '(R0402-0201)'                 | '150K'    | '1%'    | '1/16W'  | 'IO'       | 'RES CHIP 150K 1/16W +-1%(0402)AEC'                | 'CHIP0402'     | ''          | ''            | '20160116'
 '154K'       | '1%'      | '1/16W'  | '0402LF'  | 'CHIP'   | 'CS41542FB06'(!)        = ''              | ''                 | 'CS41542FB06'           |'R0402'| '(R0402-0201)'                 | '154K'    | '1%'    | '1/16W'  | 'DISCRETE' | 'RES CHIP 154K 1/16W +-1%(0402)AEC'                | 'CHIP0402'     | ''          | ''            | '20160116'
 '154K'       | '1%'      | '1/16W'  | '0402LF'  | 'EMPTY'  | 'CS41542FB06'(!)        = ''              | ''                 | 'CS41542FB06'           |'R0402'| '(R0402-0201)'                 | '154K'    | '1%'    | '1/16W'  | 'IO'       | 'RES CHIP 154K 1/16W +-1%(0402)AEC'                | 'CHIP0402'     | ''          | ''            | '20160116'
 '15K'        | '1%'      | '1/16W'  | '0402LF'  | 'CHIP'   | 'CS31502FB06'(!)        = ''              | ''                 | 'CS31502FB06'           |'R0402'| '(R0402-0201)'                 | '15K'     | '1%'    | '1/16W'  | 'DISCRETE' | 'RES CHIP 15K 1/16W +-1%(0402)AEC'                 | 'CHIP0402'     | ''          | ''            | '20160116'
 '15K'        | '1%'      | '1/16W'  | '0402LF'  | 'EMPTY'  | 'CS31502FB06'(!)        = ''              | ''                 | 'CS31502FB06'           |'R0402'| '(R0402-0201)'                 | '15K'     | '1%'    | '1/16W'  | 'IO'       | 'RES CHIP 15K 1/16W +-1%(0402)AEC'                 | 'CHIP0402'     | ''          | ''            | '20160116'
 '169'        | '1%'      | '1/16W'  | '0402LF'  | 'CHIP'   | 'CS11692FB02'(!)        = ''              | ''                 | 'CS11692FB02'           |'R0402'| '(R0402-0201)'                 | '169'     | '1%'    | '1/16W'  | 'DISCRETE' | 'RES CHIP 169 1/16W +-1%(0402)AEC'                 | 'CHIP0402'     | ''          | ''            | '20160116'
 '169'        | '1%'      | '1/16W'  | '0402LF'  | 'EMPTY'  | 'CS11692FB02'(!)        = ''              | ''                 | 'CS11692FB02'           |'R0402'| '(R0402-0201)'                 | '169'     | '1%'    | '1/16W'  | 'IO'       | 'RES CHIP 169 1/16W +-1%(0402)AEC'                 | 'CHIP0402'     | ''          | ''            | '20160116'
 '16K'        | '1%'      | '1/16W'  | '0402LF'  | 'CHIP'   | 'CS31602FB02'(!)        = ''              | ''                 | 'CS31602FB02'           |'R0402'| '(R0402-0201)'                 | '16K'     | '1%'    | '1/16W'  | 'DISCRETE' | 'RES CHIP 16K 1/16W +-1%(0402)AEC'                 | 'CHIP0402'     | ''          | ''            | '20160116'
 '16K'        | '1%'      | '1/16W'  | '0402LF'  | 'EMPTY'  | 'CS31602FB02'(!)        = ''              | ''                 | 'CS31602FB02'           |'R0402'| '(R0402-0201)'                 | '16K'     | '1%'    | '1/16W'  | 'IO'       | 'RES CHIP 16K 1/16W +-1%(0402)AEC'                 | 'CHIP0402'     | ''          | ''            | '20160116'
 '1K'         | '5%'      | '1/16W'  | '0402LF'  | 'CHIP'   | 'CS21002JB08'(!)        = ''              | ''                 | 'CS21002JB08'           |'R0402'| '(R0402-0201)'                 | '1K'      | '5%'    | '1/16W'  | 'DISCRETE' | 'RES CHIP 1K 1/16W +-5%(0402)AEC'                  | 'CHIP0402'     | ''          | ''            | '20160116'
 '1K'         | '5%'      | '1/16W'  | '0402LF'  | 'EMPTY'  | 'CS21002JB08'(!)        = ''              | ''                 | 'CS21002JB08'           |'R0402'| '(R0402-0201)'                 | '1K'      | '5%'    | '1/16W'  | 'IO'       | 'RES CHIP 1K 1/16W +-5%(0402)AEC'                  | 'CHIP0402'     | ''          | ''            | '20160116'
 '1M'         | '1%'      | '1/16W'  | '0402LF'  | 'CHIP'   | 'CS51002FB06'(!)        = ''              | ''                 | 'CS51002FB06'           |'R0402'| '(R0402-0201)'                 | '1M'      | '1%'    | '1/16W'  | 'DISCRETE' | 'RES CHIP 1M 1/16W +-1%(0402)AEC'                  | 'CHIP0402'     | ''          | ''            | '20160116'
 '1M'         | '1%'      | '1/16W'  | '0402LF'  | 'EMPTY'  | 'CS51002FB06'(!)        = ''              | ''                 | 'CS51002FB06'           |'R0402'| '(R0402-0201)'                 | '1M'      | '1%'    | '1/16W'  | 'IO'       | 'RES CHIP 1M 1/16W +-1%(0402)AEC'                  | 'CHIP0402'     | ''          | ''            | '20160116'
 '2'          | '1%'      | '1/16W'  | '0402LF'  | 'CHIP'   | 'CS-2002FB03'(!)        = ''              | ''                 | 'CS-2002FB03'           |'R0402'| '(R0402-0201)'                 | '2'       | '1%'    | '1/16W'  | 'DISCRETE' | 'RES CHIP 2 1/16W +-1%(0402)AEC'                   | 'CHIP0402'     | ''          | ''            | '20160116'
 '2'          | '1%'      | '1/16W'  | '0402LF'  | 'EMPTY'  | 'CS-2002FB03'(!)        = ''              | ''                 | 'CS-2002FB03'           |'R0402'| '(R0402-0201)'                 | '2'       | '1%'    | '1/16W'  | 'IO'       | 'RES CHIP 2 1/16W +-1%(0402)AEC'                   | 'CHIP0402'     | ''          | ''            | '20160116'
 '2.2K'       | '1%'      | '1/16W'  | '0402LF'  | 'CHIP'   | 'CS22202FB02'(!)        = ''              | ''                 | 'CS22202FB02'           |'R0402'| '(R0402-0201)'                 | '2.2K'    | '1%'    | '1/16W'  | 'DISCRETE' | 'RES CHIP 2.2K 1/16W +-1%(0402)AEC'                | 'CHIP0402'     | ''          | ''            | '20160116'
 '2.2K'       | '1%'      | '1/16W'  | '0402LF'  | 'EMPTY'  | 'CS22202FB02'(!)        = ''              | ''                 | 'CS22202FB02'           |'R0402'| '(R0402-0201)'                 | '2.2K'    | '1%'    | '1/16W'  | 'IO'       | 'RES CHIP 2.2K 1/16W +-1%(0402)AEC'                | 'CHIP0402'     | ''          | ''            | '20160116'
 '20'         | '1%'      | '1/16W'  | '0402LF'  | 'CHIP'   | 'CS02002FB04'(!)        = ''              | ''                 | 'CS02002FB04'           |'R0402'| '(R0402-0201)'                 | '20'      | '1%'    | '1/16W'  | 'DISCRETE' | 'RES CHIP 20 1/16W +-1%(0402)AEC'                  | 'CHIP0402'     | ''          | ''            | '20160116'
 '20'         | '1%'      | '1/16W'  | '0402LF'  | 'EMPTY'  | 'CS02002FB04'(!)        = ''              | ''                 | 'CS02002FB04'           |'R0402'| '(R0402-0201)'                 | '20'      | '1%'    | '1/16W'  | 'IO'       | 'RES CHIP 20 1/16W +-1%(0402)AEC'                  | 'CHIP0402'     | ''          | ''            | '20160116'
 '200'        | '1%'      | '1/16W'  | '0402LF'  | 'CHIP'   | 'CS12002FB12'(!)        = ''              | ''                 | 'CS12002FB12'           |'R0402'| '(R0402-0201)'                 | '200'     | '1%'    | '1/16W'  | 'DISCRETE' | 'RES CHIP 200 1/16W +-1%(0402)AEC'                 | 'CHIP0402'     | ''          | ''            | '20160116'
 '200'        | '1%'      | '1/16W'  | '0402LF'  | 'EMPTY'  | 'CS12002FB12'(!)        = ''              | ''                 | 'CS12002FB12'           |'R0402'| '(R0402-0201)'                 | '200'     | '1%'    | '1/16W'  | 'IO'       | 'RES CHIP 200 1/16W +-1%(0402)AEC'                 | 'CHIP0402'     | ''          | ''            | '20160116'
 '200K'       | '1%'      | '1/16W'  | '0402LF'  | 'CHIP'   | 'CS42002FB10'(!)        = ''              | ''                 | 'CS42002FB10'           |'R0402'| '(R0402-0201)'                 | '200K'    | '1%'    | '1/16W'  | 'DISCRETE' | 'RES CHIP 200K 1/16W +-1%(0402)AEC'                | 'CHIP0402'     | ''          | ''            | '20160116'
 '200K'       | '1%'      | '1/16W'  | '0402LF'  | 'EMPTY'  | 'CS42002FB10'(!)        = ''              | ''                 | 'CS42002FB10'           |'R0402'| '(R0402-0201)'                 | '200K'    | '1%'    | '1/16W'  | 'IO'       | 'RES CHIP 200K 1/16W +-1%(0402)AEC'                | 'CHIP0402'     | ''          | ''            | '20160116'
 '200'        | '0.1%'    | '1/16W'  | '0402LF'  | 'CHIP'   | 'CS12002BB01'(!)        = ''              | ''                 | 'CS12002BB01'           |'R0402'| '(R0402-0201)'                 | '200'     | '0.1%'  | '1/16W'  | 'DISCRETE' | 'RES CHIP 200 1/16W +-0.1%(0402)AEC'               | 'CHIP0402'     | ''          | ''            | '20160120'
 '200'        | '0.1%'    | '1/16W'  | '0402LF'  | 'EMPTY'  | 'CS12002BB01'(!)        = ''              | ''                 | 'CS12002BB01'           |'R0402'| '(R0402-0201)'                 | '200'     | '0.1%'  | '1/16W'  | 'IO'       | 'RES CHIP 200 1/16W +-0.1%(0402)AEC'               | 'CHIP0402'     | ''          | ''            | '20160120'
 '200'        | '0.1%'    | '1/16W'  | '0402LF'  | 'CHIP'   | 'CS12002BB00'(!)        = ''              | ''                 | 'CS12002BB00'           |'R0402'| '(R0402-0201)'                 | '200'     | '0.1%'  | '1/16W'  | 'DISCRETE' | 'RES CHIP 200 1/16W +-0.1% (0402)'                 | 'CHIP0402'     | ''          | ''            | '20160120'
 '200'        | '0.1%'    | '1/16W'  | '0402LF'  | 'EMPTY'  | 'CS12002BB00'(!)        = ''              | ''                 | 'CS12002BB00'           |'R0402'| '(R0402-0201)'                 | '200'     | '0.1%'  | '1/16W'  | 'IO'       | 'RES CHIP 200 1/16W +-0.1% (0402)'                 | 'CHIP0402'     | ''          | ''            | '20160120'
 '20K'        | '1%'      | '1/16W'  | '0402LF'  | 'CHIP'   | 'CS32002FB12'(!)        = ''              | ''                 | 'CS32002FB12'           |'R0402'| '(R0402-0201)'                 | '20K'     | '1%'    | '1/16W'  | 'DISCRETE' | 'RES CHIP 20K 1/16W +-1%(0402)AEC'                 | 'CHIP0402'     | ''          | ''            | '20160120'
 '20K'        | '1%'      | '1/16W'  | '0402LF'  | 'EMPTY'  | 'CS32002FB12'(!)        = ''              | ''                 | 'CS32002FB12'           |'R0402'| '(R0402-0201)'                 | '20K'     | '1%'    | '1/16W'  | 'IO'       | 'RES CHIP 20K 1/16W +-1%(0402)AEC'                 | 'CHIP0402'     | ''          | ''            | '20160120'
 '22'         | '1%'      | '1/16W'  | '0402LF'  | 'CHIP'   | 'CS02202FB03'(!)        = ''              | ''                 | 'CS02202FB03'           |'R0402'| '(R0402-0201)'                 | '22'      | '1%'    | '1/16W'  | 'DISCRETE' | 'RES CHIP 22 1/16W +-1%(0402)AEC'                  | 'CHIP0402'     | ''          | ''            | '20160120'
 '22'         | '1%'      | '1/16W'  | '0402LF'  | 'EMPTY'  | 'CS02202FB03'(!)        = ''              | ''                 | 'CS02202FB03'           |'R0402'| '(R0402-0201)'                 | '22'      | '1%'    | '1/16W'  | 'IO'       | 'RES CHIP 22 1/16W +-1%(0402)AEC'                  | 'CHIP0402'     | ''          | ''            | '20160120'
 '220'        | '5%'      | '1/16W'  | '0402LF'  | 'CHIP'   | 'CS12202JB04'(!)        = ''              | ''                 | 'CS12202JB04'           |'R0402'| '(R0402-0201)'                 | '220'     | '5%'    | '1/16W'  | 'DISCRETE' | 'RES CHIP 220 1/16W +-5%(0402)AEC'                 | 'CHIP0402'     | ''          | ''            | '20160120'
 '220'        | '5%'      | '1/16W'  | '0402LF'  | 'EMPTY'  | 'CS12202JB04'(!)        = ''              | ''                 | 'CS12202JB04'           |'R0402'| '(R0402-0201)'                 | '220'     | '5%'    | '1/16W'  | 'IO'       | 'RES CHIP 220 1/16W +-5%(0402)AEC'                 | 'CHIP0402'     | ''          | ''            | '20160120'
 '221'        | '1%'      | '1/16W'  | '0402LF'  | 'CHIP'   | 'CS12212FB04'(!)        = ''              | ''                 | 'CS12212FB04'           |'R0402'| '(R0402-0201)'                 | '221'     | '1%'    | '1/16W'  | 'DISCRETE' | 'RES CHIP 221 1/16W +-1%(0402)AEC'                 | 'CHIP0402'     | ''          | ''            | '20160120'
 '221'        | '1%'      | '1/16W'  | '0402LF'  | 'EMPTY'  | 'CS12212FB04'(!)        = ''              | ''                 | 'CS12212FB04'           |'R0402'| '(R0402-0201)'                 | '221'     | '1%'    | '1/16W'  | 'IO'       | 'RES CHIP 221 1/16W +-1%(0402)AEC'                 | 'CHIP0402'     | ''          | ''            | '20160120'
 '240'        | '1%'      | '1/16W'  | '0402LF'  | 'CHIP'   | 'CS12402FB02'(!)        = ''              | ''                 | 'CS12402FB02'           |'R0402'| '(R0402-0201)'                 | '240'     | '1%'    | '1/16W'  | 'DISCRETE' | 'RES CHIP 240 1/16W +-1%(0402)AEC'                 | 'CHIP0402'     | ''          | ''            | '20160120'
 '240'        | '1%'      | '1/16W'  | '0402LF'  | 'EMPTY'  | 'CS12402FB02'(!)        = ''              | ''                 | 'CS12402FB02'           |'R0402'| '(R0402-0201)'                 | '240'     | '1%'    | '1/16W'  | 'IO'       | 'RES CHIP 240 1/16W +-1%(0402)AEC'                 | 'CHIP0402'     | ''          | ''            | '20160120'
 '249'        | '0.1%'    | '1/16W'  | '0402LF'  | 'CHIP'   | 'CS12492BB03'(!)        = ''              | ''                 | 'CS12492BB03'           |'R0402'| '(R0402-0201)'                 | '249'     | '0.1%'  | '1/16W'  | 'DISCRETE' | 'RES CHIP 249 1/16W +-0.1%(0402)AEC'               | 'CHIP0402'     | ''          | ''            | '20160120'
 '249'        | '0.1%'    | '1/16W'  | '0402LF'  | 'EMPTY'  | 'CS12492BB03'(!)        = ''              | ''                 | 'CS12492BB03'           |'R0402'| '(R0402-0201)'                 | '249'     | '0.1%'  | '1/16W'  | 'IO'       | 'RES CHIP 249 1/16W +-0.1%(0402)AEC'               | 'CHIP0402'     | ''          | ''            | '20160120'
 '25.5K'      | '1%'      | '1/16W'  | '0402LF'  | 'CHIP'   | 'CS32552FB04'(!)        = ''              | ''                 | 'CS32552FB04'           |'R0402'| '(R0402-0201)'                 | '25.5K'   | '1%'    | '1/16W'  | 'DISCRETE' | 'RES CHIP 25.5K 1/16W +-1%(0402)AEC'               | 'CHIP0402'     | ''          | ''            | '20160120'
 '25.5K'      | '1%'      | '1/16W'  | '0402LF'  | 'EMPTY'  | 'CS32552FB04'(!)        = ''              | ''                 | 'CS32552FB04'           |'R0402'| '(R0402-0201)'                 | '25.5K'   | '1%'    | '1/16W'  | 'IO'       | 'RES CHIP 25.5K 1/16W +-1%(0402)AEC'               | 'CHIP0402'     | ''          | ''            | '20160120'
 '255K'       | '1%'      | '1/16W'  | '0402LF'  | 'CHIP'   | 'CS42552FB03'(!)        = ''              | ''                 | 'CS42552FB03'           |'R0402'| '(R0402-0201)'                 | '255K'    | '1%'    | '1/16W'  | 'DISCRETE' | 'RES CHIP 255K 1/16W +-1%(0402)AEC'                | 'CHIP0402'     | ''          | ''            | '20160121'
 '255K'       | '1%'      | '1/16W'  | '0402LF'  | 'EMPTY'  | 'CS42552FB03'(!)        = ''              | ''                 | 'CS42552FB03'           |'R0402'| '(R0402-0201)'                 | '255K'    | '1%'    | '1/16W'  | 'IO'       | 'RES CHIP 255K 1/16W +-1%(0402)AEC'                | 'CHIP0402'     | ''          | ''            | '20160121'
 '27.4'       | '1%'      | '1/16W'  | '0402LF'  | 'CHIP'   | 'CS02742FB04'(!)        = ''              | ''                 | 'CS02742FB04'           |'R0402'| '(R0402-0201)'                 | '27.4'    | '1%'    | '1/16W'  | 'DISCRETE' | 'RES CHIP 27.4 1/16W +-1%(0402)AEC'                | 'CHIP0402'     | ''          | ''            | '20160121'
 '27.4'       | '1%'      | '1/16W'  | '0402LF'  | 'EMPTY'  | 'CS02742FB04'(!)        = ''              | ''                 | 'CS02742FB04'           |'R0402'| '(R0402-0201)'                 | '27.4'    | '1%'    | '1/16W'  | 'IO'       | 'RES CHIP 27.4 1/16W +-1%(0402)AEC'                | 'CHIP0402'     | ''          | ''            | '20160121'
 '2K'         | '1%'      | '1/16W'  | '0402LF'  | 'CHIP'   | 'CS22002FB11'(!)        = ''              | ''                 | 'CS22002FB11'           |'R0402'| '(R0402-0201)'                 | '2K'      | '1%'    | '1/16W'  | 'DISCRETE' | 'RES CHIP 2K 1/16W +-1%(0402)AEC'                  | 'CHIP0402'     | ''          | ''            | '20160121'
 '2K'         | '1%'      | '1/16W'  | '0402LF'  | 'EMPTY'  | 'CS22002FB11'(!)        = ''              | ''                 | 'CS22002FB11'           |'R0402'| '(R0402-0201)'                 | '2K'      | '1%'    | '1/16W'  | 'IO'       | 'RES CHIP 2K 1/16W +-1%(0402)AEC'                  | 'CHIP0402'     | ''          | ''            | '20160121'
 '3.01K'      | '1%'      | '1/16W'  | '0402LF'  | 'CHIP'   | 'CS23012FB09'(!)        = ''              | ''                 | 'CS23012FB09'           |'R0402'| '(R0402-0201)'                 | '3.01K'   | '1%'    | '1/16W'  | 'DISCRETE' | 'RES CHIP 3.01K 1/16W +-1%(0402)AEC'               | 'CHIP0402'     | ''          | ''            | '20160121'
 '3.01K'      | '1%'      | '1/16W'  | '0402LF'  | 'EMPTY'  | 'CS23012FB09'(!)        = ''              | ''                 | 'CS23012FB09'           |'R0402'| '(R0402-0201)'                 | '3.01K'   | '1%'    | '1/16W'  | 'IO'       | 'RES CHIP 3.01K 1/16W +-1%(0402)AEC'               | 'CHIP0402'     | ''          | ''            | '20160121'
 '33'         | '1%'      | '1/16W'  | '0402LF'  | 'CHIP'   | 'CS03302FB04'(!)        = ''              | ''                 | 'CS03302FB04'           |'R0402'| '(R0402-0201)'                 | '33'      | '1%'    | '1/16W'  | 'DISCRETE' | 'RES CHIP 33 1/16W +-1%(0402)AEC'                  | 'CHIP0402'     | ''          | ''            | '20160121'
 '33'         | '1%'      | '1/16W'  | '0402LF'  | 'EMPTY'  | 'CS03302FB04'(!)        = ''              | ''                 | 'CS03302FB04'           |'R0402'| '(R0402-0201)'                 | '33'      | '1%'    | '1/16W'  | 'IO'       | 'RES CHIP 33 1/16W +-1%(0402)AEC'                  | 'CHIP0402'     | ''          | ''            | '20160121'
 '33'         | '5%'      | '1/16W'  | '0402LF'  | 'CHIP'   | 'CS03302JB09'(!)        = ''              | ''                 | 'CS03302JB09'           |'R0402'| '(R0402-0201)'                 | '33'      | '5%'    | '1/16W'  | 'DISCRETE' | 'RES CHIP 33 1/16W +-5% (0402)AEC'                 | 'CHIP0402'     | ''          | ''            | '20160121'
 '33'         | '5%'      | '1/16W'  | '0402LF'  | 'EMPTY'  | 'CS03302JB09'(!)        = ''              | ''                 | 'CS03302JB09'           |'R0402'| '(R0402-0201)'                 | '33'      | '5%'    | '1/16W'  | 'IO'       | 'RES CHIP 33 1/16W +-5% (0402)AEC'                 | 'CHIP0402'     | ''          | ''            | '20160121'
 '332'        | '1%'      | '1/16W'  | '0402LF'  | 'CHIP'   | 'CS13322FB06'(!)        = ''              | ''                 | 'CS13322FB06'           |'R0402'| '(R0402-0201)'                 | '332'     | '1%'    | '1/16W'  | 'DISCRETE' | 'RES CHIP 332 1/16W +-1%(0402)AEC'                 | 'CHIP0402'     | ''          | ''            | '20160121'
 '332'        | '1%'      | '1/16W'  | '0402LF'  | 'EMPTY'  | 'CS13322FB06'(!)        = ''              | ''                 | 'CS13322FB06'           |'R0402'| '(R0402-0201)'                 | '332'     | '1%'    | '1/16W'  | 'IO'       | 'RES CHIP 332 1/16W +-1%(0402)AEC'                 | 'CHIP0402'     | ''          | ''            | '20160121'
 '348'        | '1%'      | '1/16W'  | '0402LF'  | 'CHIP'   | 'CS13482FB03'(!)        = ''              | ''                 | 'CS13482FB03'           |'R0402'| '(R0402-0201)'                 | '348'     | '1%'    | '1/16W'  | 'DISCRETE' | 'RES CHIP 348 1/16W +-1%(0402)AEC'                 | 'CHIP0402'     | ''          | ''            | '20160121'
 '348'        | '1%'      | '1/16W'  | '0402LF'  | 'EMPTY'  | 'CS13482FB03'(!)        = ''              | ''                 | 'CS13482FB03'           |'R0402'| '(R0402-0201)'                 | '348'     | '1%'    | '1/16W'  | 'IO'       | 'RES CHIP 348 1/16W +-1%(0402)AEC'                 | 'CHIP0402'     | ''          | ''            | '20160121'
 '348K'       | '1%'      | '1/16W'  | '0402LF'  | 'CHIP'   | 'CS43482FB02'(!)        = ''              | ''                 | 'CS43482FB02'           |'R0402'| '(R0402-0201)'                 | '348K'    | '1%'    | '1/16W'  | 'DISCRETE' | 'RES CHIP 348K 1/16W +-1%(0402)AEC'                | 'CHIP0402'     | ''          | ''            | '20160121'
 '348K'       | '1%'      | '1/16W'  | '0402LF'  | 'EMPTY'  | 'CS43482FB02'(!)        = ''              | ''                 | 'CS43482FB02'           |'R0402'| '(R0402-0201)'                 | '348K'    | '1%'    | '1/16W'  | 'IO'       | 'RES CHIP 348K 1/16W +-1%(0402)AEC'                | 'CHIP0402'     | ''          | ''            | '20160121'
 '34K'        | '1%'      | '1/16W'  | '0402LF'  | 'CHIP'   | 'CS33402FB03'(!)        = ''              | ''                 | 'CS33402FB03'           |'R0402'| '(R0402-0201)'                 | '34K'     | '1%'    | '1/16W'  | 'DISCRETE' | 'RES CHIP 34K 1/16W +-1%(0402)AEC'                 | 'CHIP0402'     | ''          | ''            | '20160121'
 '34K'        | '1%'      | '1/16W'  | '0402LF'  | 'EMPTY'  | 'CS33402FB03'(!)        = ''              | ''                 | 'CS33402FB03'           |'R0402'| '(R0402-0201)'                 | '34K'     | '1%'    | '1/16W'  | 'IO'       | 'RES CHIP 34K 1/16W +-1%(0402)AEC'                 | 'CHIP0402'     | ''          | ''            | '20160121'
 '36'         | '5%'      | '1/16W'  | '0402LF'  | 'CHIP'   | 'CS03602JB02'(!)        = ''              | ''                 | 'CS03602JB02'           |'R0402'| '(R0402-0201)'                 | '36'      | '5%'    | '1/16W'  | 'DISCRETE' | 'RES CHIP 36 1/16W +-5%(0402)AEC'                  | 'CHIP0402'     | ''          | ''            | '20160201'
 '36'         | '5%'      | '1/16W'  | '0402LF'  | 'EMPTY'  | 'CS03602JB02'(!)        = ''              | ''                 | 'CS03602JB02'           |'R0402'| '(R0402-0201)'                 | '36'      | '5%'    | '1/16W'  | 'IO'       | 'RES CHIP 36 1/16W +-5%(0402)AEC'                  | 'CHIP0402'     | ''          | ''            | '20160201'
 '37.4K'      | '1%'      | '1/16W'  | '0402LF'  | 'CHIP'   | 'CS33742FB06'(!)        = ''              | ''                 | 'CS33742FB06'           |'R0402'| '(R0402-0201)'                 | '37.4K'   | '1%'    | '1/16W'  | 'DISCRETE' | 'RES CHIP 37.4K 1/16W +-1%(0402)AEC'               | 'CHIP0402'     | ''          | ''            | '20160201'
 '37.4K'      | '1%'      | '1/16W'  | '0402LF'  | 'EMPTY'  | 'CS33742FB06'(!)        = ''              | ''                 | 'CS33742FB06'           |'R0402'| '(R0402-0201)'                 | '37.4K'   | '1%'    | '1/16W'  | 'IO'       | 'RES CHIP 37.4K 1/16W +-1%(0402)AEC'               | 'CHIP0402'     | ''          | ''            | '20160201'
 '0.0003'     | '1%'      | '4W'     | '2725LF'  | 'CHIP'   | 'CS0000FFT04'(!)        = 'End of Design' | 'Comp-Approve'     | 'CS0000FFT04'           |'R2725'| '(SMR2725AW)'                  | '0.0003'  | '1%'    | '4W'     | 'DISCRETE' | 'RES CHIP 0.0003 4W +-1%(2725)'                    | 'CHIP2725'     | ''          | ''            | '20160201'
 '0.0003'     | '1%'      | '4W'     | '2725LF'  | 'EMPTY'  | 'CS0000FFT04'(!)        = 'End of Design' | 'Comp-Approve'     | 'CS0000FFT04'           |'R2725'| '(SMR2725AW)'                  | '0.0003'  | '1%'    | '4W'     | 'IO'       | 'RES CHIP 0.0003 4W +-1%(2725)'                    | 'CHIP2725'     | ''          | ''            | '20160201'
 '82K'        | '1%'      | '1/8W'   | '0805LF'  | 'CHIP'   | 'CS38204FA00'(!)        = ''              | ''                 | 'CS38204FA00'           |'R0805'| '(SMR0805AW)'                  | '82K'     | '1%'    | '1/8W'   | 'DISCRETE' | 'RES CHIP 82K 1/8W +-1%(0805)'                     | 'CHIP0805'     | ''          | ''            | '20160205'
 '82K'        | '1%'      | '1/8W'   | '0805LF'  | 'EMPTY'  | 'CS38204FA00'(!)        = ''              | ''                 | 'CS38204FA00'           |'R0805'| '(SMR0805AW)'                  | '82K'     | '1%'    | '1/8W'   | 'IO'       | 'RES CHIP 82K 1/8W +-1%(0805)'                     | 'CHIP0805'     | ''          | ''            | '20160205'
 '665K'       | '0.1%'    | '1/16W'  | '0402LF'  | 'CHIP'   | 'CS46652BB00'(!)        = ''              | ''                 | 'CS46652BB00'           |'R0402'| '(R0402-0201)'                 | '665K'    | '0.1%'  | '1/16W'  | 'DISCRETE' | 'RES CHIP 665K 1/16W +-0.1%(0402)'                 | 'CHIP0402'     | ''          | ''            | '20160205'
 '665K'       | '0.1%'    | '1/16W'  | '0402LF'  | 'EMPTY'  | 'CS46652BB00'(!)        = ''              | ''                 | 'CS46652BB00'           |'R0402'| '(R0402-0201)'                 | '665K'    | '0.1%'  | '1/16W'  | 'IO'       | 'RES CHIP 665K 1/16W +-0.1%(0402)'                 | 'CHIP0402'     | ''          | ''            | '20160205'
 '4.02'       | '1%'      | '1/16W'  | '0402LF'  | 'CHIP'   | 'CS-4022FB00'(!)        = ''              | ''                 | 'CS-4022FB00'           |'R0402'| '(R0402-0201)'                 | '4.02'    | '1%'    | '1/16W'  | 'DISCRETE' | 'RES CHIP 4.02 1/16W +-1%(0402)'                   | 'CHIP0402'     | ''          | ''            | '20160205'
 '4.02'       | '1%'      | '1/16W'  | '0402LF'  | 'EMPTY'  | 'CS-4022FB00'(!)        = ''              | ''                 | 'CS-4022FB00'           |'R0402'| '(R0402-0201)'                 | '4.02'    | '1%'    | '1/16W'  | 'IO'       | 'RES CHIP 4.02 1/16W +-1%(0402)'                   | 'CHIP0402'     | ''          | ''            | '20160205'
 '665K'       | '0.1%'    | '1/8W'   | '0805LF'  | 'CHIP'   | 'CS46654BA00'(!)        = ''              | ''                 | 'CS46654BA00'           |'R0805'| '(SMR0805AW)'                  | '665K'    | '0.1%'  | '1/8W'   | 'DISCRETE' | 'RES CHIP 665K 1/8W +-0.1%(0805)AEC'               | 'CHIP0805'     | ''          | ''            | '20160303'
 '665K'       | '0.1%'    | '1/8W'   | '0805LF'  | 'EMPTY'  | 'CS46654BA00'(!)        = ''              | ''                 | 'CS46654BA00'           |'R0805'| '(SMR0805AW)'                  | '665K'    | '0.1%'  | '1/8W'   | 'IO'       | 'RES CHIP 665K 1/8W +-0.1%(0805)AEC'               | 'CHIP0805'     | ''          | ''            | '20160303'
 '0.001'      | '1%'      | '3W'     | '2512LF'  | 'CHIP'   | 'CS+001DFR00'(!)        = ''              | ''                 | 'CS+001DFR00'           |'R2512XJ'| '(SMR2512AW)'                  | '0.001'   | '1%'    | '3W'     | 'DISCRETE' | 'RES CHIP 0.001 3W(+-1%,2512)'                     | 'CHIP2512'     | ''          | ''            | '20160303'
 '0.001'      | '1%'      | '3W'     | '2512LF'  | 'EMPTY'  | 'CS+001DFR00'(!)        = ''              | ''                 | 'CS+001DFR00'           |'R2512XJ'| '(SMR2512AW)'                  | '0.001'   | '1%'    | '3W'     | 'IO'       | 'RES CHIP 0.001 3W(+-1%,2512)'                     | 'CHIP2512'     | ''          | ''            | '20160303'
 '0.002'      | '1%'      | '1W'     | '1206LF'  | 'CHIP'   | 'CS+0028F201'(!)        = ''              | ''                 | 'CS+0028F201'           |'R1206XA'| '(SMR1206AW)'                  | '0.002'   | '1%'    | '1W'     | 'DISCRETE' | 'RES CHIP 0.002 1W +-1%(1206)'                     | 'CHIP1206'     | ''          | ''            | '20160307'
 '0.002'      | '1%'      | '1W'     | '1206LF'  | 'EMPTY'  | 'CS+0028F201'(!)        = ''              | ''                 | 'CS+0028F201'           |'R1206XA'| '(SMR1206AW)'                  | '0.002'   | '1%'    | '1W'     | 'IO'       | 'RES CHIP 0.002 1W +-1%(1206)'                     | 'CHIP1206'     | ''          | ''            | '20160307'
 '820'        | '1%'      | '1/4W'   | '0805LF'  | 'CHIP'   | 'CS18206FA00'(!)        = ''              | ''                 | 'CS18206FA00'           |'R0805'| '(SMR0805AW)'                  | '820'     | '1%'    | '1/4W'   | 'DISCRETE' | 'RES CHIP 820 1/4W +-1%(0805)'                     | 'CHIP0805'     | ''          | ''            | '20160310'
 '820'        | '1%'      | '1/4W'   | '0805LF'  | 'EMPTY'  | 'CS18206FA00'(!)        = ''              | ''                 | 'CS18206FA00'           |'R0805'| '(SMR0805AW)'                  | '820'     | '1%'    | '1/4W'   | 'IO'       | 'RES CHIP 820 1/4W +-1%(0805)'                     | 'CHIP0805'     | ''          | ''            | '20160310'
 '887'        | '1%'      | '1/16W'  | 'R0402LF' | 'CHIP'   | 'CS18872FB01'(!)        = 'End of Design' | 'Comp-Approve'     | 'CS18872FB01'           |'R0402'| '(R0402-0201)'                 | '887'     | '1%'    | '1/16W'  | 'DISCRETE' | 'RES CHIP 887 1/16W +-1%(0402)'                    | 'CHIP0402'     | ''          | ''            | '20160314'
 '887'        | '1%'      | '1/16W'  | 'R0402LF' | 'EMPTY'  | 'CS18872FB01'(!)        = 'End of Design' | 'Comp-Approve'     | 'CS18872FB01'           |'R0402'| '(R0402-0201)'                 | '887'     | '1%'    | '1/16W'  | 'IO'       | 'RES CHIP 887 1/16W +-1%(0402)'                    | 'CHIP0402'     | ''          | ''            | '20160314'
 '2.2'        | '1%'      | '1/10W'  | '0603LF'  | 'CHIP'   | 'CS-2203F901'(!)        = ''              | ''                 | 'CS-2203F901'           |'R0603'| '(SMR0603AW)'                  | '2.2'     | '1%'    | '1/10W'  | 'DISCRETE' | 'RES CHIP 2.2 1/10W +-1%(0603)AEC'                 | 'CHIPR0603'    | ''          | ''            | '20160315'
 '2.2'        | '1%'      | '1/10W'  | '0603LF'  | 'EMPTY'  | 'CS-2203F901'(!)        = ''              | ''                 | 'CS-2203F901'           |'R0603'| '(SMR0603AW)'                  | '2.2'     | '1%'    | '1/10W'  | 'IO'       | 'RES CHIP 2.2 1/10W +-1%(0603)AEC'                 | 'CHIPR0603'    | ''          | ''            | '20160315'
 '27'         | '1%'      | '1/16W'  | '0402LF'  | 'CHIP'   | 'CS02702FB11'(!)        = 'End of Design' | 'Comp-Approve'     | 'CS02702FB11'           |'R0402'| '(R0402-0201)'                 | '27'      | '1%'    | '1/16W'  | 'DISCRETE' | 'RES CHIP 27 1/16W +-1%(0402)'                     | 'CHIPR0402'    | ''          | ''            | '20160317'
 '27'         | '1%'      | '1/16W'  | '0402LF'  | 'EMPTY'  | 'CS02702FB11'(!)        = 'End of Design' | 'Comp-Approve'     | 'CS02702FB11'           |'R0402'| '(R0402-0201)'                 | '27'      | '1%'    | '1/16W'  | 'IO'       | 'RES CHIP 27 1/16W +-1%(0402)'                     | 'CHIPR0402'    | ''          | ''            | '20160317'
 '43K'        | '1%'      | '1/8W'   | '0805LF'  | 'CHIP'   | 'CS34304FA00'(!)        = ''              | ''                 | 'CS34304FA00'           |'R0805'| '(SMR0805AW)'                  | '43K'     | '1%'    | '1/8W'   | 'DISCRETE' | 'RES CHIP 43K 1/8W +-1% (0805)'                    | 'CHIPR0805'    | ''          | ''            | '20160321'
 '43K'        | '1%'      | '1/8W'   | '0805LF'  | 'EMPTY'  | 'CS34304FA00'(!)        = ''              | ''                 | 'CS34304FA00'           |'R0805'| '(SMR0805AW)'                  | '43K'     | '1%'    | '1/8W'   | 'IO'       | 'RES CHIP 43K 1/8W +-1% (0805)'                    | 'CHIPR0805'    | ''          | ''            | '20160321'
 '8.2'        | '5%'      | '1W'     | '2512LF'  | 'CHIP'   | 'CS00828JR00'(!)        = ''              | ''                 | 'CS00828JR00'           |'R2512XK'| '(SMR2512AW)'                  | '8.2'     | '5%'    | '1W'     | 'DISCRETE' | 'RES CHIP 8.2 1W +-5%(2512)'                       | 'CHIPR2512'    | ''          | ''            | '20160323'
 '8.2'        | '5%'      | '1W'     | '2512LF'  | 'EMPTY'  | 'CS00828JR00'(!)        = ''              | ''                 | 'CS00828JR00'           |'R2512XK'| '(SMR2512AW)'                  | '8.2'     | '5%'    | '1W'     | 'IO'       | 'RES CHIP 8.2 1W +-5%(2512)'                       | 'CHIPR2512'    | ''          | ''            | '20160323'
 '2.7M'       | '1%'      | '1/8W'   | '0805LF'  | 'CHIP'   | 'CS52704FA00'(!)        = ''              | ''                 | 'CS52704FA00'           |'R0805'| '(SMR0805AW)'                  | '2.7M'    | '1%'    | '1/8W'   | 'DISCRETE' | 'RES CHIP 2.7M(+-1%,1/8W,0805)TAI'                 | 'CHIPR0805'    | ''          | ''            | '20160325'
 '2.7M'       | '1%'      | '1/8W'   | '0805LF'  | 'EMPTY'  | 'CS52704FA00'(!)        = ''              | ''                 | 'CS52704FA00'           |'R0805'| '(SMR0805AW)'                  | '2.7M'    | '1%'    | '1/8W'   | 'IO'       | 'RES CHIP 2.7M(+-1%,1/8W,0805)TAI'                 | 'CHIPR0805'    | ''          | ''            | '20160325'
 '9.31K'      | '0.1%'    | '1/16W'  | '0402LF'  | 'CHIP'   | 'CS29312BB00'(!)        = 'End of Design' | 'Comp-Approve'     | 'CS29312BB00'           |'R0402'| '(R0402-0201)'                 | '9.31K'   | '0.1%'  | '1/16W'  | 'DISCRETE' | 'RES CHIP 9.31K 1/16W +-0.1%(0402)EF'              | 'CHIPR0402'    | ''          | ''            | '20160329'
 '9.31K'      | '0.1%'    | '1/16W'  | '0402LF'  | 'EMPTY'  | 'CS29312BB00'(!)        = 'End of Design' | 'Comp-Approve'     | 'CS29312BB00'           |'R0402'| '(R0402-0201)'                 | '9.31K'   | '0.1%'  | '1/16W'  | 'IO'       | 'RES CHIP 9.31K 1/16W +-0.1%(0402)EF'              | 'CHIPR0402'    | ''          | ''            | '20160329'
 '0.001'      | '1%'      | '1W'     | '2512LF'  | 'CHIP'   | 'CS+0018FR05'(!)        = ''              | ''                 | 'CS+0018FR05'           |'R2512XF'| '(SMR2512AW)'                  | '0.001'   | '1%'    | '1W'     | 'DISCRETE' | 'RES CHIP 0.001(+-1%,1W, 2512)TAI'                 | 'CHIPR2512'    | ''          | ''            | '20160411'
 '0.001'      | '1%'      | '1W'     | '2512LF'  | 'EMPTY'  | 'CS+0018FR05'(!)        = ''              | ''                 | 'CS+0018FR05'           |'R2512XF'| '(SMR2512AW)'                  | '0.001'   | '1%'    | '1W'     | 'IO'       | 'RES CHIP 0.001(+-1%,1W, 2512)TAI'                 | 'CHIPR2512'    | ''          | ''            | '20160411'
 '0.002'      | '1%'      | '1W'     | '2512LF'  | 'CHIP'   | 'CS+0028FR02'(!)        = ''              | ''                 | 'CS+0028FR02'           |'R2512XF'| '(SMR2512AW)'                  | '0.002'   | '1%'    | '1W'     | 'DISCRETE' | 'RES CHIP 0.002( +-1%,1W,2512)TAI'                 | 'CHIPR2512'    | ''          | ''            | '20160411'
 '0.002'      | '1%'      | '1W'     | '2512LF'  | 'EMPTY'  | 'CS+0028FR02'(!)        = ''              | ''                 | 'CS+0028FR02'           |'R2512XF'| '(SMR2512AW)'                  | '0.002'   | '1%'    | '1W'     | 'IO'       | 'RES CHIP 0.002( +-1%,1W,2512)TAI'                 | 'CHIPR2512'    | ''          | ''            | '20160411'
 '0.0005'     | '1%'      | '3W'     | '2512LF'  | 'CHIP'   | 'CS0000DFR04'(!)        = ''              | ''                 | 'CS0000DFR04'           |'R2512XF'| '(SMR2512AW)'                  | '0.0005'  | '1%'    | '3W'     | 'DISCRETE' | 'RES CHIP 0.0005(+-1%,3W,2512)TAI'                 | 'CHIPR2512'    | ''          | ''            | '20160411'
 '0.0005'     | '1%'      | '3W'     | '2512LF'  | 'EMPTY'  | 'CS0000DFR04'(!)        = ''              | ''                 | 'CS0000DFR04'           |'R2512XF'| '(SMR2512AW)'                  | '0.0005'  | '1%'    | '3W'     | 'IO'       | 'RES CHIP 0.0005(+-1%,3W,2512)TAI'                 | 'CHIPR2512'    | ''          | ''            | '20160411'
 '2.26K'      | '0.1%'    | '1/16W'  | '0402LF'  | 'CHIP'   | 'CS22262BB00'(!)        = ''              | ''                 | 'CS22262BB00'           |'R0402'| '(R0402-0201)'                 | '2.26K'   | '0.1%'  | '1/16W'  | 'DISCRETE' | 'RES CHIP 2.26K 1/16W +-0.1%(0402)'                | 'CHIPR0402'    | ''          | ''            | '20160415'
 '2.26K'      | '0.1%'    | '1/16W'  | '0402LF'  | 'EMPTY'  | 'CS22262BB00'(!)        = ''              | ''                 | 'CS22262BB00'           |'R0402'| '(R0402-0201)'                 | '2.26K'   | '0.1%'  | '1/16W'  | 'IO'       | 'RES CHIP 2.26K 1/16W +-0.1%(0402)'                | 'CHIPR0402'    | ''          | ''            | '20160415'
 '0.008'      | '1%'      | '3W'     | '2512LF'  | 'CHIP'   | 'CS+008DFR02'(!)        = ''              | ''                 | 'CS+008DFR02'           |'R2512XL'| '(SMR2512AW)'                  | '0.008'   | '1%'    | '3W'     | 'DISCRETE' | 'RES CHIP 0.008(+-1%,3W,2512)TAI'                  | 'CHIPR2512'    | ''          | ''            | '20160419'
 '0.008'      | '1%'      | '3W'     | '2512LF'  | 'EMPTY'  | 'CS+008DFR02'(!)        = ''              | ''                 | 'CS+008DFR02'           |'R2512XL'| '(SMR2512AW)'                  | '0.008'   | '1%'    | '3W'     | 'IO'       | 'RES CHIP 0.008(+-1%,3W,2512)TAI'                  | 'CHIPR2512'    | ''          | ''            | '20160419'
 '0.02'       | '1%'      | '1/2W'   | '0805LF'  | 'CHIP'   | 'CS+0207FA00'(!)        = 'End of Design' | 'Comp-Approve'     | 'CS+0207FA00'           |'R0805XA'| '(SMR0805AW)'                  | '0.02'    | '1%'    | '1/2W'   | 'DISCRETE' | 'RES CHIP 0.02 1/2W +-1% (0805)'                   | 'CHIPR0805'    | ''          | ''            | '20160420'
 '0.02'       | '1%'      | '1/2W'   | '0805LF'  | 'EMPTY'  | 'CS+0207FA00'(!)        = 'End of Design' | 'Comp-Approve'     | 'CS+0207FA00'           |'R0805XA'| '(SMR0805AW)'                  | '0.02'    | '1%'    | '1/2W'   | 'IO'       | 'RES CHIP 0.02 1/2W +-1% (0805)'                   | 'CHIPR0805'    | ''          | ''            | '20160420'
 '787K'       | '1%'      | '1/16W'  | '0402LF'  | 'CHIP'   | 'CS47872FB00'(!)        = 'End of Design' | 'Comp-Approve'     | 'CS47872FB00'           |'R0402'| '(R0402-0201)'                 | '787K'    | '1%'    | '1/16W'  | 'DISCRETE' | 'RES CHIP 787K 1/16W +-1%(0402)'                   | 'CHIPR0402'    | ''          | ''            | '20160421'
 '787K'       | '1%'      | '1/16W'  | '0402LF'  | 'EMPTY'  | 'CS47872FB00'(!)        = 'End of Design' | 'Comp-Approve'     | 'CS47872FB00'           |'R0402'| '(R0402-0201)'                 | '787K'    | '1%'    | '1/16W'  | 'IO'       | 'RES CHIP 787K 1/16W +-1%(0402)'                   | 'CHIPR0402'    | ''          | ''            | '20160421'
 '7.5'        | '1%'      | '2W'     | '2512LF'  | 'CHIP'   | 'CS-750AFR01'(!)        = ''              | ''                 | 'CS-750AFR01'           |'R2512XK'| '(SMR2512AW)'                  | '7.5'     | '1%'    | '2W'     | 'DISCRETE' | 'RES CHIP 7.5 2W +-1%(2512)'                       | 'CHIPR2512'    | ''          | ''            | '20160426'
 '7.5'        | '1%'      | '2W'     | '2512LF'  | 'EMPTY'  | 'CS-750AFR01'(!)        = ''              | ''                 | 'CS-750AFR01'           |'R2512XK'| '(SMR2512AW)'                  | '7.5'     | '1%'    | '2W'     | 'IO'       | 'RES CHIP 7.5 2W +-1%(2512)'                       | 'CHIPR2512'    | ''          | ''            | '20160426'
 '0.003'      | '1%'      | '4W'     | '2725LF'  | 'CHIP'   | 'CS+003FFT00'(!)        = 'End of Design' | 'Comp-Approve'     | 'CS+003FFT00'           |'R2725'| '(SMR2725AW)'                  | '0.003'   | '1%'    | '4W'     | 'DISCRETE' | 'RES CHIP 0.003 4W +-1% (2725)EF'                  | 'CHIPR2725'    | ''          | ''            | '20160426'
 '0.003'      | '1%'      | '4W'     | '2725LF'  | 'EMPTY'  | 'CS+003FFT00'(!)        = 'End of Design' | 'Comp-Approve'     | 'CS+003FFT00'           |'R2725'| '(SMR2725AW)'                  | '0.003'   | '1%'    | '4W'     | 'IO'       | 'RES CHIP 0.003 4W +-1% (2725)EF'                  | 'CHIPR2725'    | ''          | ''            | '20160426'
 '3.3'        | '1%'      | '1/10W'  | '0603LF'  | 'CHIP'   | 'CS-3303F901'(!)        = ''              | ''                 | 'CS-3303F901'           |'R0603'| '(SMR0603AW)'                  | '3.3'     | '1%'    | '1/10W'  | 'DISCRETE' | 'RES CHIP 3.3 1/10W +-1%(0603)AEC'                 | 'CHIPR0603'    | ''          | ''            | '20160503'
 '3.3'        | '1%'      | '1/10W'  | '0603LF'  | 'EMPTY'  | 'CS-3303F901'(!)        = ''              | ''                 | 'CS-3303F901'           |'R0603'| '(SMR0603AW)'                  | '3.3'     | '1%'    | '1/10W'  | 'IO'       | 'RES CHIP 3.3 1/10W +-1%(0603)AEC'                 | 'CHIPR0603'    | ''          | ''            | '20160503'
 '3.3'        | '1%'      | '1/16W'  | '0402LF'  | 'CHIP'   | 'CS-3302FB02'(!)        = ''              | ''                 | 'CS-3302FB02'           |'R0402'| '(R0402-0201)'                 | '3.3'     | '1%'    | '1/16W'  | 'DISCRETE' | 'RES CHIP 3.3 1/16W +-1%(0402)AEC'                 | 'CHIPR0402'    | ''          | ''            | '20160503'
 '3.3'        | '1%'      | '1/16W'  | '0402LF'  | 'EMPTY'  | 'CS-3302FB02'(!)        = ''              | ''                 | 'CS-3302FB02'           |'R0402'| '(R0402-0201)'                 | '3.3'     | '1%'    | '1/16W'  | 'IO'       | 'RES CHIP 3.3 1/16W +-1%(0402)AEC'                 | 'CHIPR0402'    | ''          | ''            | '20160503'
 '2.2'        | '1%'      | '1/4W'   | '1206LF'  | 'CHIP'   | 'CS-2206F201'(!)        = ''              | ''                 | 'CS-2206F201'           |'R1206'| '(SMR1206AW)'                  | '2.2'     | '1%'    | '1/4W'   | 'DISCRETE' | 'RES CHIP 2.2 1/4W +-1%(1206)AEC'                  | 'CHIPR1206'    | ''          | ''            | '20160503'
 '2.2'        | '1%'      | '1/4W'   | '1206LF'  | 'EMPTY'  | 'CS-2206F201'(!)        = ''              | ''                 | 'CS-2206F201'           |'R1206'| '(SMR1206AW)'                  | '2.2'     | '1%'    | '1/4W'   | 'IO'       | 'RES CHIP 2.2 1/4W +-1%(1206)AEC'                  | 'CHIPR1206'    | ''          | ''            | '20160503'
 '0'          | ''        | '1/8W'   | '0805LF'  | 'CHIP'   | 'CS00004TA02'(!)        = 'End of Design' | 'Comp-Approve'     | 'CS00004TA02'           |'R0805'| '(SMR0805AW)'                  | '0'       | ''      | '1/8W'   | 'DISCRETE' | 'RESISTOR CHIP 0 1/8W(0805)'                       | 'CHIPR0805'    | ''          | ''            | '20160511'
 '0'          | ''        | '1/8W'   | '0805LF'  | 'EMPTY'  | 'CS00004TA02'(!)        = 'End of Design' | 'Comp-Approve'     | 'CS00004TA02'           |'R0805'| '(SMR0805AW)'                  | '0'       | ''      | '1/8W'   | 'IO'       | 'RESISTOR CHIP 0 1/8W(0805)'                       | 'CHIPR0805'    | ''          | ''            | '20160511'
 '825K'       | '1%'      | '1/20W'  | '0201LF'  | 'CHIP'   | 'CS48251FE00'(!)        = ''              | ''                 | 'CS48251FE00'           |'R0201'| '(SMR0201AW)'                  | '825K'    | '1%'    | '1/20W'  | 'DISCRETE' | 'RESISTOR CHIP 825K 1/20W+-1%(0201)'               | 'CHIPR0201'    | ''          | ''            | '20160512'
 '825K'       | '1%'      | '1/20W'  | '0201LF'  | 'EMPTY'  | 'CS48251FE00'(!)        = ''              | ''                 | 'CS48251FE00'           |'R0201'| '(SMR0201AW)'                  | '825K'    | '1%'    | '1/20W'  | 'IO'       | 'RESISTOR CHIP 825K 1/20W+-1%(0201)'               | 'CHIPR0201'    | ''          | ''            | '20160512'
 '220'        | '5%'      | '1/10W'  | '0603LF'  | 'CHIP'   | 'CS12203J947'(!)        = ''              | ''                 | 'CS12203J947'           |'R0603'| '(SMR0603AW)'                  | '220'     | '5%'    | '1/10W'  | 'DISCRETE' | 'RES CHIP 220 1/10W +-5%(0603) EP'                 | 'CHIPR0603'    | ''          | ''            | '20160616'
 '220'        | '5%'      | '1/10W'  | '0603LF'  | 'EMPTY'  | 'CS12203J947'(!)        = ''              | ''                 | 'CS12203J947'           |'R0603'| '(SMR0603AW)'                  | '220'     | '5%'    | '1/10W'  | 'IO'       | 'RES CHIP 220 1/10W +-5%(0603) EP'                 | 'CHIPR0603'    | ''          | ''            | '20160616'
 '267K'       | '1%'      | '1/16W'  | '0402LF'  | 'CHIP'   | 'CS42672FB16'(!)        = 'End of Design' | 'Comp-Approve'     | 'CS42672FB16'           |'R0402'| '(R0402-0201)'                 | '267K'    | '1%'    | '1/16W'  | 'DISCRETE' | 'RES CHIP 267K 1/16W +-1%(0402)'                   | 'CHIPR0402'    | ''          | ''            | '20160617'
 '267K'       | '1%'      | '1/16W'  | '0402LF'  | 'EMPTY'  | 'CS42672FB16'(!)        = 'End of Design' | 'Comp-Approve'     | 'CS42672FB16'           |'R0402'| '(R0402-0201)'                 | '267K'    | '1%'    | '1/16W'  | 'IO'       | 'RES CHIP 267K 1/16W +-1%(0402)'                   | 'CHIPR0402'    | ''          | ''            | '20160617'
 '5.9K'       | '0.1%'    | '1/16W'  | '0402LF'  | 'CHIP'   | 'CS25902BB02'(!)        = 'Non-Preferred' | 'End of Life'      | 'CS25902BB02'           |'R0402_EOL'| '(R0402-0201)'                 | '5.9K'    | '0.1%'  | '1/16W'  | 'DISCRETE' | 'RES CHIP 5.9K 1/16W +-0.1% (0402)DAL_AEC'         | 'CHIPR0402'    | ''          | ''            | '20160628'
 '5.9K'       | '0.1%'    | '1/16W'  | '0402LF'  | 'EMPTY'  | 'CS25902BB02'(!)        = 'Non-Preferred' | 'End of Life'      | 'CS25902BB02'           |'R0402_EOL'| '(R0402-0201)'                 | '5.9K'    | '0.1%'  | '1/16W'  | 'IO'       | 'RES CHIP 5.9K 1/16W +-0.1% (0402)DAL_AEC'         | 'CHIPR0402'    | ''          | ''            | '20160628'
 '10K'        | '0.1%'    | '1/16W'  | '0402LF'  | 'CHIP'   | 'CS31002BB07'(!)        = 'Non-Preferred' | 'End of Life'      | 'CS31002BB07'           |'R0402_EOL'| '(R0402-0201)'                 | '10K'     | '0.1%'  | '1/16W'  | 'DISCRETE' | 'RES CHIP 10K 1/16W +-0.1%(0402)DAL_AEC'           | 'CHIPR0402'    | ''          | ''            | '20160628'
 '10K'        | '0.1%'    | '1/16W'  | '0402LF'  | 'EMPTY'  | 'CS31002BB07'(!)        = 'Non-Preferred' | 'End of Life'      | 'CS31002BB07'           |'R0402_EOL'| '(R0402-0201)'                 | '10K'     | '0.1%'  | '1/16W'  | 'IO'       | 'RES CHIP 10K 1/16W +-0.1%(0402)DAL_AEC'           | 'CHIPR0402'    | ''          | ''            | '20160628'
 '100K'       | '0.1%'    | '1/16W'  | '0402LF'  | 'CHIP'   | 'CS41002BB03'(!)        = 'Non-Preferred' | 'End of Life'      | 'CS41002BB03'           |'R0402_EOL'| '(R0402-0201)'                 | '100K'    | '0.1%'  | '1/16W'  | 'DISCRETE' | 'RES CHIP 100K 1/16W +-0.1%(0402)DAL_AEC'          | 'CHIPR0402'    | ''          | ''            | '20160628'
 '100K'       | '0.1%'    | '1/16W'  | '0402LF'  | 'EMPTY'  | 'CS41002BB03'(!)        = 'Non-Preferred' | 'End of Life'      | 'CS41002BB03'           |'R0402_EOL'| '(R0402-0201)'                 | '100K'    | '0.1%'  | '1/16W'  | 'IO'       | 'RES CHIP 100K 1/16W +-0.1%(0402)DAL_AEC'          | 'CHIPR0402'    | ''          | ''            | '20160628'
 '249'        | '0.1%'    | '1/16W'  | '0402LF'  | 'CHIP'   | 'CS12492BB04'(!)        = 'Non-Preferred' | 'End of Life'      | 'CS12492BB04'           |'R0402_EOL'| '(R0402-0201)'                 | '249'     | '0.1%'  | '1/16W'  | 'DISCRETE' | 'RES CHIP 249 1/16W +-0.1%(0402)DAL_AEC'           | 'CHIPR0402'    | ''          | ''            | '20160628'
 '249'        | '0.1%'    | '1/16W'  | '0402LF'  | 'EMPTY'  | 'CS12492BB04'(!)        = 'Non-Preferred' | 'End of Life'      | 'CS12492BB04'           |'R0402_EOL'| '(R0402-0201)'                 | '249'     | '0.1%'  | '1/16W'  | 'IO'       | 'RES CHIP 249 1/16W +-0.1%(0402)DAL_AEC'           | 'CHIPR0402'    | ''          | ''            | '20160628'
 '15'         | '5%'      | '1/16W'  | '0402LF'  | 'CHIP'   | 'CS01502JB06'(!)        = ''              | ''                 | 'CS01502JB06'           |'R0402'| '(R0402-0201)'                 | '15'      | '5%'    | '1/16W'  | 'DISCRETE' | 'RES CHIP 15 1/16W +-5%(0402)DAL_AEC'              | 'CHIPR0402'    | ''          | ''            | '20160628'
 '15'         | '5%'      | '1/16W'  | '0402LF'  | 'EMPTY'  | 'CS01502JB06'(!)        = ''              | ''                 | 'CS01502JB06'           |'R0402'| '(R0402-0201)'                 | '15'      | '5%'    | '1/16W'  | 'IO'       | 'RES CHIP 15 1/16W +-5%(0402)DAL_AEC'              | 'CHIPR0402'    | ''          | ''            | '20160628'
 '10'         | '5%'      | '1/16W'  | '0402LF'  | 'CHIP'   | 'CS01002JB08'(!)        = ''              | ''                 | 'CS01002JB08'           |'R0402'| '(R0402-0201)'                 | '10'      | '5%'    | '1/16W'  | 'DISCRETE' | 'RES CHIP 10 1/16W +5%(0402)DAL_AEC'               | 'CHIPR0402'    | ''          | ''            | '20160628'
 '10'         | '5%'      | '1/16W'  | '0402LF'  | 'EMPTY'  | 'CS01002JB08'(!)        = ''              | ''                 | 'CS01002JB08'           |'R0402'| '(R0402-0201)'                 | '10'      | '5%'    | '1/16W'  | 'IO'       | 'RES CHIP 10 1/16W +5%(0402)DAL_AEC'               | 'CHIPR0402'    | ''          | ''            | '20160628'
 '200'        | '0.1%'    | '1/16W'  | '0402LF'  | 'CHIP'   | 'CS12002BB02'(!)        = 'Non-Preferred' | 'End of Life'      | 'CS12002BB02'           |'R0402_EOL'| '(R0402-0201)'                 | '200'     | '0.1%'  | '1/16W'  | 'DISCRETE' | 'RES CHIP 200 1/16W +0.1% (0402)DAL_AEC'           | 'CHIPR0402'    | ''          | ''            | '20160629'
 '200'        | '0.1%'    | '1/16W'  | '0402LF'  | 'EMPTY'  | 'CS12002BB02'(!)        = 'Non-Preferred' | 'End of Life'      | 'CS12002BB02'           |'R0402_EOL'| '(R0402-0201)'                 | '200'     | '0.1%'  | '1/16W'  | 'IO'       | 'RES CHIP 200 1/16W +0.1% (0402)DAL_AEC'           | 'CHIPR0402'    | ''          | ''            | '20160629'
 '1'          | '5%'      | '1/16W'  | '0402LF'  | 'CHIP'   | 'CS-1002JB07'(!)        = ''              | ''                 | 'CS-1002JB07'           |'R0402'| '(R0402-0201)'                 | '1'       | '5%'    | '1/16W'  | 'DISCRETE' | 'RES CHIP 1 1/16W +-5%(0402) DAL_AEC'              | 'CHIPR0402'    | ''          | ''            | '20160629'
 '1'          | '5%'      | '1/16W'  | '0402LF'  | 'EMPTY'  | 'CS-1002JB07'(!)        = ''              | ''                 | 'CS-1002JB07'           |'R0402'| '(R0402-0201)'                 | '1'       | '5%'    | '1/16W'  | 'IO'       | 'RES CHIP 1 1/16W +-5%(0402) DAL_AEC'              | 'CHIPR0402'    | ''          | ''            | '20160629'
 '100'        | '0.1%'    | '1/16W'  | '0402LF'  | 'CHIP'   | 'CS11002BB03'(!)        = 'Non-Preferred' | 'End of Life'      | 'CS11002BB03'           |'R0402_EOL'| '(R0402-0201)'                 | '100'     | '0.1%'  | '1/16W'  | 'DISCRETE' | 'RES CHIP 100 1/16W +-0.1%(0402) DAL_AEC'          | 'CHIPR0402'    | ''          | ''            | '20160629'
 '100'        | '0.1%'    | '1/16W'  | '0402LF'  | 'EMPTY'  | 'CS11002BB03'(!)        = 'Non-Preferred' | 'End of Life'      | 'CS11002BB03'           |'R0402_EOL'| '(R0402-0201)'                 | '100'     | '0.1%'  | '1/16W'  | 'IO'       | 'RES CHIP 100 1/16W +-0.1%(0402) DAL_AEC'          | 'CHIPR0402'    | ''          | ''            | '20160629'
 '220'        | '5%'      | '1/16W'  | '0402LF'  | 'CHIP'   | 'CS12202JB05'(!)        = ''              | ''                 | 'CS12202JB05'           |'R0402'| '(R0402-0201)'                 | '220'     | '5%'    | '1/16W'  | 'DISCRETE' | 'RES CHIP 220 1/16W +-5%(0402)DAL_AEC'             | 'CHIPR0402'    | ''          | ''            | '20160629'
 '220'        | '5%'      | '1/16W'  | '0402LF'  | 'EMPTY'  | 'CS12202JB05'(!)        = ''              | ''                 | 'CS12202JB05'           |'R0402'| '(R0402-0201)'                 | '220'     | '5%'    | '1/16W'  | 'IO'       | 'RES CHIP 220 1/16W +-5%(0402)DAL_AEC'             | 'CHIPR0402'    | ''          | ''            | '20160629'
 '0'          | ''        | '1/16W'  | '0402LF'  | 'CHIP'   | 'CS00002TB01'(!)        = ''              | ''                 | 'CS00002TB01'           |'R0402'| '(R0402-0201)'                 | '0'       | ''      | '1/16W'  | 'DISCRETE' | 'RES CHIP 0 1/16W (0402) DAL_AEC'                  | 'CHIPR0402'    | ''          | ''            | '20160630'
 '0'          | ''        | '1/16W'  | '0402LF'  | 'EMPTY'  | 'CS00002TB01'(!)        = ''              | ''                 | 'CS00002TB01'           |'R0402'| '(R0402-0201)'                 | '0'       | ''      | '1/16W'  | 'IO'       | 'RES CHIP 0 1/16W (0402) DAL_AEC'                  | 'CHIPR0402'    | ''          | ''            | '20160630'
 '10'         | '1%'      | '1/16W'  | '0402LF'  | 'CHIP'   | 'CS01002FB13'(!)        = ''              | ''                 | 'CS01002FB13'           |'R0402'| '(R0402-0201)'                 | '10'      | '1%'    | '1/16W'  | 'DISCRETE' | 'RES CHIP 10 1/16W +-1%(0402) DAL_AEC'             | 'CHIPR0402'    | ''          | ''            | '20160630'
 '10'         | '1%'      | '1/16W'  | '0402LF'  | 'EMPTY'  | 'CS01002FB13'(!)        = ''              | ''                 | 'CS01002FB13'           |'R0402'| '(R0402-0201)'                 | '10'      | '1%'    | '1/16W'  | 'IO'       | 'RES CHIP 10 1/16W +-1%(0402) DAL_AEC'             | 'CHIPR0402'    | ''          | ''            | '20160630'
 '15'         | '1%'      | '1/16W'  | '0402LF'  | 'CHIP'   | 'CS01502FB05'(!)        = ''              | ''                 | 'CS01502FB05'           |'R0402'| '(R0402-0201)'                 | '15'      | '1%'    | '1/16W'  | 'DISCRETE' | 'RES CHIP 15 1/16W +-1%(0402)DAL_AEC'              | 'CHIPR0402'    | ''          | ''            | '20160630'
 '15'         | '1%'      | '1/16W'  | '0402LF'  | 'EMPTY'  | 'CS01502FB05'(!)        = ''              | ''                 | 'CS01502FB05'           |'R0402'| '(R0402-0201)'                 | '15'      | '1%'    | '1/16W'  | 'IO'       | 'RES CHIP 15 1/16W +-1%(0402)DAL_AEC'              | 'CHIPR0402'    | ''          | ''            | '20160630'
 '21'         | '1%'      | '1/16W'  | '0402LF'  | 'CHIP'   | 'CS02102FB05'(!)        = ''              | ''                 | 'CS02102FB05'           |'R0402'| '(R0402-0201)'                 | '21'      | '1%'    | '1/16W'  | 'DISCRETE' | 'RES CHIP 21 1/16W +-1%(0402)DAL_AEC'              | 'CHIPR0402'    | ''          | ''            | '20160630'
 '21'         | '1%'      | '1/16W'  | '0402LF'  | 'EMPTY'  | 'CS02102FB05'(!)        = ''              | ''                 | 'CS02102FB05'           |'R0402'| '(R0402-0201)'                 | '21'      | '1%'    | '1/16W'  | 'IO'       | 'RES CHIP 21 1/16W +-1%(0402)DAL_AEC'              | 'CHIPR0402'    | ''          | ''            | '20160630'
 '22'         | '1%'      | '1/16W'  | '0402LF'  | 'CHIP'   | 'CS02202FB05'(!)        = ''              | ''                 | 'CS02202FB05'           |'R0402'| '(R0402-0201)'                 | '22'      | '1%'    | '1/16W'  | 'DISCRETE' | 'RES CHIP 22 1/16W +-1%(0402)DAL_AEC'              | 'CHIPR0402'    | ''          | ''            | '20160630'
 '22'         | '1%'      | '1/16W'  | '0402LF'  | 'EMPTY'  | 'CS02202FB05'(!)        = ''              | ''                 | 'CS02202FB05'           |'R0402'| '(R0402-0201)'                 | '22'      | '1%'    | '1/16W'  | 'IO'       | 'RES CHIP 22 1/16W +-1%(0402)DAL_AEC'              | 'CHIPR0402'    | ''          | ''            | '20160630'
 '27.4'       | '1%'      | '1/16W'  | '0402LF'  | 'CHIP'   | 'CS02742FB05'(!)        = ''              | ''                 | 'CS02742FB05'           |'R0402'| '(R0402-0201)'                 | '27.4'    | '1%'    | '1/16W'  | 'DISCRETE' | 'RES CHIP 27.4 1/16W +-1%(0402)DAL_AEC'            | 'CHIPR0402'    | ''          | ''            | '20160630'
 '27.4'       | '1%'      | '1/16W'  | '0402LF'  | 'EMPTY'  | 'CS02742FB05'(!)        = ''              | ''                 | 'CS02742FB05'           |'R0402'| '(R0402-0201)'                 | '27.4'    | '1%'    | '1/16W'  | 'IO'       | 'RES CHIP 27.4 1/16W +-1%(0402)DAL_AEC'            | 'CHIPR0402'    | ''          | ''            | '20160630'
 '0.001'      | '1%'      | '1W'     | '2512LF'  | 'CHIP'   | 'CS+0018FR04'(!)        = ''              | ''                 | 'CS+0018FR04'           |'R2512A'| '(SMR2512AW)'                  | '0.001'   | '1%'    | '1W'     | 'DISCRETE' | 'RES CHIP 0.001 1W +-1% (2512)'                    | 'CHIPR2512'    | ''          | ''            | '20160705'
 '0.001'      | '1%'      | '1W'     | '2512LF'  | 'EMPTY'  | 'CS+0018FR04'(!)        = ''              | ''                 | 'CS+0018FR04'           |'R2512A'| '(SMR2512AW)'                  | '0.001'   | '1%'    | '1W'     | 'IO'       | 'RES CHIP 0.001 1W +-1% (2512)'                    | 'CHIPR2512'    | ''          | ''            | '20160705'
 '20'         | '1%'      | '1/16W'  | '0402LF'  | 'CHIP'   | 'CS02002FB05'(!)        = ''              | ''                 | 'CS02002FB05'           |'R0402'| '(R0402-0201)'                 | '20'      | '1%'    | '1/16W'  | 'DISCRETE' | 'RES CHIP 20 1/16W +-1%(0402)DAL_AEC'              | 'CHIPR0402'    | ''          | ''            | '20160706'
 '20'         | '1%'      | '1/16W'  | '0402LF'  | 'EMPTY'  | 'CS02002FB05'(!)        = ''              | ''                 | 'CS02002FB05'           |'R0402'| '(R0402-0201)'                 | '20'      | '1%'    | '1/16W'  | 'IO'       | 'RES CHIP 20 1/16W +-1%(0402)DAL_AEC'              | 'CHIPR0402'    | ''          | ''            | '20160706'
 '33'         | '1%'      | '1/16W'  | '0402LF'  | 'CHIP'   | 'CS03302FB05'(!)        = ''              | ''                 | 'CS03302FB05'           |'R0402'| '(R0402-0201)'                 | '33'      | '1%'    | '1/16W'  | 'DISCRETE' | 'RES CHIP 33 1/16W +-1%(0402)DAL_AEC'              | 'CHIPR0402'    | ''          | ''            | '20160706'
 '33'         | '1%'      | '1/16W'  | '0402LF'  | 'EMPTY'  | 'CS03302FB05'(!)        = ''              | ''                 | 'CS03302FB05'           |'R0402'| '(R0402-0201)'                 | '33'      | '1%'    | '1/16W'  | 'IO'       | 'RES CHIP 33 1/16W +-1%(0402)DAL_AEC'              | 'CHIPR0402'    | ''          | ''            | '20160706'
 '33.2'       | '1%'      | '1/16W'  | '0402LF'  | 'CHIP'   | 'CS03322FB09'(!)        = ''              | ''                 | 'CS03322FB09'           |'R0402'| '(R0402-0201)'                 | '33.2'    | '1%'    | '1/16W'  | 'DISCRETE' | 'RES CHIP 33.2 1/16W +-1%(0402)DAL_AEC'            | 'CHIPR0402'    | ''          | ''            | '20160706'
 '33.2'       | '1%'      | '1/16W'  | '0402LF'  | 'EMPTY'  | 'CS03322FB09'(!)        = ''              | ''                 | 'CS03322FB09'           |'R0402'| '(R0402-0201)'                 | '33.2'    | '1%'    | '1/16W'  | 'IO'       | 'RES CHIP 33.2 1/16W +-1%(0402)DAL_AEC'            | 'CHIPR0402'    | ''          | ''            | '20160706'
 '36'         | '1%'      | '1/16W'  | '0402LF'  | 'CHIP'   | 'CS03602FB03'(!)        = ''              | ''                 | 'CS03602FB03'           |'R0402'| '(R0402-0201)'                 | '36'      | '1%'    | '1/16W'  | 'DISCRETE' | 'RES CHIP 36 1/16W +-1%(0402)DAL_AEC'              | 'CHIPR0402'    | ''          | ''            | '20160706'
 '36'         | '1%'      | '1/16W'  | '0402LF'  | 'EMPTY'  | 'CS03602FB03'(!)        = ''              | ''                 | 'CS03602FB03'           |'R0402'| '(R0402-0201)'                 | '36'      | '1%'    | '1/16W'  | 'IO'       | 'RES CHIP 36 1/16W +-1%(0402)DAL_AEC'              | 'CHIPR0402'    | ''          | ''            | '20160706'
 '39'         | '1%'      | '1/16W'  | '0402LF'  | 'CHIP'   | 'CS03902FB03'(!)        = ''              | ''                 | 'CS03902FB03'           |'R0402'| '(R0402-0201)'                 | '39'      | '1%'    | '1/16W'  | 'DISCRETE' | 'RES CHIP 39 1/16W +-1%(0402)DAL_AEC'              | 'CHIPR0402'    | ''          | ''            | '20160706'
 '39'         | '1%'      | '1/16W'  | '0402LF'  | 'EMPTY'  | 'CS03902FB03'(!)        = ''              | ''                 | 'CS03902FB03'           |'R0402'| '(R0402-0201)'                 | '39'      | '1%'    | '1/16W'  | 'IO'       | 'RES CHIP 39 1/16W +-1%(0402)DAL_AEC'              | 'CHIPR0402'    | ''          | ''            | '20160706'
 '42.2'       | '1%'      | '1/16W'  | '0402LF'  | 'CHIP'   | 'CS04222FB04'(!)        = ''              | ''                 | 'CS04222FB04'           |'R0402'| '(R0402-0201)'                 | '42.2'    | '1%'    | '1/16W'  | 'DISCRETE' | 'RES CHIP 42.2 1/16W +-1%(0402)DAL_AEC'            | 'CHIPR0402'    | ''          | ''            | '20160706'
 '42.2'       | '1%'      | '1/16W'  | '0402LF'  | 'EMPTY'  | 'CS04222FB04'(!)        = ''              | ''                 | 'CS04222FB04'           |'R0402'| '(R0402-0201)'                 | '42.2'    | '1%'    | '1/16W'  | 'IO'       | 'RES CHIP 42.2 1/16W +-1%(0402)DAL_AEC'            | 'CHIPR0402'    | ''          | ''            | '20160706'
 '43'         | '1%'      | '1/16W'  | '0402LF'  | 'CHIP'   | 'CS04302FB02'(!)        = ''              | ''                 | 'CS04302FB02'           |'R0402'| '(R0402-0201)'                 | '43'      | '1%'    | '1/16W'  | 'DISCRETE' | 'RES CHIP 43 1/16W +-1%(0402)DAL_AEC'              | 'CHIPR0402'    | ''          | ''            | '20160706'
 '43'         | '1%'      | '1/16W'  | '0402LF'  | 'EMPTY'  | 'CS04302FB02'(!)        = ''              | ''                 | 'CS04302FB02'           |'R0402'| '(R0402-0201)'                 | '43'      | '1%'    | '1/16W'  | 'IO'       | 'RES CHIP 43 1/16W +-1%(0402)DAL_AEC'              | 'CHIPR0402'    | ''          | ''            | '20160706'
 '64.9'       | '1%'      | '1/16W'  | '0402LF'  | 'CHIP'   | 'CS06492FB04'(!)        = ''              | ''                 | 'CS06492FB04'           |'R0402'| '(R0402-0201)'                 | '64.9'    | '1%'    | '1/16W'  | 'DISCRETE' | 'RES CHIP 64.9 1/16W +-1%(0402)DAL_AEC'            | 'CHIPR0402'    | ''          | ''            | '20160706'
 '64.9'       | '1%'      | '1/16W'  | '0402LF'  | 'EMPTY'  | 'CS06492FB04'(!)        = ''              | ''                 | 'CS06492FB04'           |'R0402'| '(R0402-0201)'                 | '64.9'    | '1%'    | '1/16W'  | 'IO'       | 'RES CHIP 64.9 1/16W +-1%(0402)DAL_AEC'            | 'CHIPR0402'    | ''          | ''            | '20160706'
 '75'         | '1%'      | '1/16W'  | '0402LF'  | 'CHIP'   | 'CS07502FB06'(!)        = ''              | ''                 | 'CS07502FB06'           |'R0402'| '(R0402-0201)'                 | '75'      | '1%'    | '1/16W'  | 'DISCRETE' | 'RES CHIP 75 1/16W +-1%(0402)DAL_AEC'              | 'CHIPR0402'    | ''          | ''            | '20160706'
 '75'         | '1%'      | '1/16W'  | '0402LF'  | 'EMPTY'  | 'CS07502FB06'(!)        = ''              | ''                 | 'CS07502FB06'           |'R0402'| '(R0402-0201)'                 | '75'      | '1%'    | '1/16W'  | 'IO'       | 'RES CHIP 75 1/16W +-1%(0402)DAL_AEC'              | 'CHIPR0402'    | ''          | ''            | '20160706'
 '90.9'       | '1%'      | '1/16W'  | '0402LF'  | 'CHIP'   | 'CS09092FB05'(!)        = ''              | ''                 | 'CS09092FB05'           |'R0402'| '(R0402-0201)'                 | '90.9'    | '1%'    | '1/16W'  | 'DISCRETE' | 'RES CHIP 90.9 1/16W +-1%(0402)DAL_AEC'            | 'CHIPR0402'    | ''          | ''            | '20160706'
 '90.9'       | '1%'      | '1/16W'  | '0402LF'  | 'EMPTY'  | 'CS09092FB05'(!)        = ''              | ''                 | 'CS09092FB05'           |'R0402'| '(R0402-0201)'                 | '90.9'    | '1%'    | '1/16W'  | 'IO'       | 'RES CHIP 90.9 1/16W +-1%(0402)DAL_AEC'            | 'CHIPR0402'    | ''          | ''            | '20160706'
 '1'          | '1%'      | '1/16W'  | '0402LF'  | 'CHIP'   | 'CS-1002FB10'(!)        = 'Non-Preferred' | 'End of Life'      | 'CS-1002FB10'           |'R0402_EOL'| '(R0402-0201)'                 | '1'       | '1%'    | '1/16W'  | 'DISCRETE' | 'RES CHIP 1 1/16W +-1%(0402) DAL_AEC'              | 'CHIPR0402'    | ''          | ''            | '20160706'
 '1'          | '1%'      | '1/16W'  | '0402LF'  | 'EMPTY'  | 'CS-1002FB10'(!)        = 'Non-Preferred' | 'End of Life'      | 'CS-1002FB10'           |'R0402_EOL'| '(R0402-0201)'                 | '1'       | '1%'    | '1/16W'  | 'IO'       | 'RES CHIP 1 1/16W +-1%(0402) DAL_AEC'              | 'CHIPR0402'    | ''          | ''            | '20160706'
 '100'        | '1%'      | '1/16W'  | '0402LF'  | 'CHIP'   | 'CS11002FB12'(!)        = ''              | ''                 | 'CS11002FB12'           |'R0402'| '(R0402-0201)'                 | '100'     | '1%'    | '1/16W'  | 'DISCRETE' | 'RES CHIP 100 1/16W +-1%(0402) DAL_AEC'            | 'CHIPR0402'    | ''          | ''            | '20160706'
 '100'        | '1%'      | '1/16W'  | '0402LF'  | 'EMPTY'  | 'CS11002FB12'(!)        = ''              | ''                 | 'CS11002FB12'           |'R0402'| '(R0402-0201)'                 | '100'     | '1%'    | '1/16W'  | 'IO'       | 'RES CHIP 100 1/16W +-1%(0402) DAL_AEC'            | 'CHIPR0402'    | ''          | ''            | '20160706'
 '113'        | '1%'      | '1/16W'  | '0402LF'  | 'CHIP'   | 'CS11132FB05'(!)        = ''              | ''                 | 'CS11132FB05'           |'R0402'| '(R0402-0201)'                 | '113'     | '1%'    | '1/16W'  | 'DISCRETE' | 'RES CHIP 113 1/16W +-1%(0402)DAL_AEC'             | 'CHIPR0402'    | ''          | ''            | '20160706'
 '113'        | '1%'      | '1/16W'  | '0402LF'  | 'EMPTY'  | 'CS11132FB05'(!)        = ''              | ''                 | 'CS11132FB05'           |'R0402'| '(R0402-0201)'                 | '113'     | '1%'    | '1/16W'  | 'IO'       | 'RES CHIP 113 1/16W +-1%(0402)DAL_AEC'             | 'CHIPR0402'    | ''          | ''            | '20160706'
 '120'        | '1%'      | '1/16W'  | '0402LF'  | 'CHIP'   | 'CS11202FB05'(!)        = ''              | ''                 | 'CS11202FB05'           |'R0402'| '(R0402-0201)'                 | '120'     | '1%'    | '1/16W'  | 'DISCRETE' | 'RES CHIP 120 1/16W +-1%(0402)DAL_AEC'             | 'CHIPR0402'    | ''          | ''            | '20160706'
 '120'        | '1%'      | '1/16W'  | '0402LF'  | 'EMPTY'  | 'CS11202FB05'(!)        = ''              | ''                 | 'CS11202FB05'           |'R0402'| '(R0402-0201)'                 | '120'     | '1%'    | '1/16W'  | 'IO'       | 'RES CHIP 120 1/16W +-1%(0402)DAL_AEC'             | 'CHIPR0402'    | ''          | ''            | '20160706'
 '137'        | '1%'      | '1/16W'  | '0402LF'  | 'CHIP'   | 'CS11372FB02'(!)        = ''              | ''                 | 'CS11372FB02'           |'R0402'| '(R0402-0201)'                 | '137'     | '1%'    | '1/16W'  | 'DISCRETE' | 'RES CHIP 137 1/16W +1%(0402)DAL_AEC'              | 'CHIPR0402'    | ''          | ''            | '20160706'
 '137'        | '1%'      | '1/16W'  | '0402LF'  | 'EMPTY'  | 'CS11372FB02'(!)        = ''              | ''                 | 'CS11372FB02'           |'R0402'| '(R0402-0201)'                 | '137'     | '1%'    | '1/16W'  | 'IO'       | 'RES CHIP 137 1/16W +1%(0402)DAL_AEC'              | 'CHIPR0402'    | ''          | ''            | '20160706'
 '150'        | '1%'      | '1/16W'  | '0402LF'  | 'CHIP'   | 'CS11502FB09'(!)        = ''              | ''                 | 'CS11502FB09'           |'R0402'| '(R0402-0201)'                 | '150'     | '1%'    | '1/16W'  | 'DISCRETE' | 'RES CHIP 150 1/16W +-1%(0402)DAL_AEC'             | 'CHIPR0402'    | ''          | ''            | '20160706'
 '150'        | '1%'      | '1/16W'  | '0402LF'  | 'EMPTY'  | 'CS11502FB09'(!)        = ''              | ''                 | 'CS11502FB09'           |'R0402'| '(R0402-0201)'                 | '150'     | '1%'    | '1/16W'  | 'IO'       | 'RES CHIP 150 1/16W +-1%(0402)DAL_AEC'             | 'CHIPR0402'    | ''          | ''            | '20160706'
 '169'        | '1%'      | '1/16W'  | '0402LF'  | 'CHIP'   | 'CS11692FB03'(!)        = ''              | ''                 | 'CS11692FB03'           |'R0402'| '(R0402-0201)'                 | '169'     | '1%'    | '1/16W'  | 'DISCRETE' | 'RES CHIP 169 1/16W +-1%(0402)DAL_AEC'             | 'CHIPR0402'    | ''          | ''            | '20160706'
 '169'        | '1%'      | '1/16W'  | '0402LF'  | 'EMPTY'  | 'CS11692FB03'(!)        = ''              | ''                 | 'CS11692FB03'           |'R0402'| '(R0402-0201)'                 | '169'     | '1%'    | '1/16W'  | 'IO'       | 'RES CHIP 169 1/16W +-1%(0402)DAL_AEC'             | 'CHIPR0402'    | ''          | ''            | '20160706'
 '200'        | '1%'      | '1/16W'  | '0402LF'  | 'CHIP'   | 'CS12002FB13'(!)        = ''              | ''                 | 'CS12002FB13'           |'R0402'| '(R0402-0201)'                 | '200'     | '1%'    | '1/16W'  | 'DISCRETE' | 'RES CHIP 200 1/16W +-1%(0402)DAL_AEC'             | 'CHIPR0402'    | ''          | ''            | '20160706'
 '200'        | '1%'      | '1/16W'  | '0402LF'  | 'EMPTY'  | 'CS12002FB13'(!)        = ''              | ''                 | 'CS12002FB13'           |'R0402'| '(R0402-0201)'                 | '200'     | '1%'    | '1/16W'  | 'IO'       | 'RES CHIP 200 1/16W +-1%(0402)DAL_AEC'             | 'CHIPR0402'    | ''          | ''            | '20160706'
 '220'        | '1%'      | '1/16W'  | '0402LF'  | 'CHIP'   | 'CS12202FB02'(!)        = ''              | ''                 | 'CS12202FB02'           |'R0402'| '(R0402-0201)'                 | '220'     | '1%'    | '1/16W'  | 'DISCRETE' | 'RES CHIP 220 1/16W +-1%(0402)DAL_AEC'             | 'CHIPR0402'    | ''          | ''            | '20160706'
 '220'        | '1%'      | '1/16W'  | '0402LF'  | 'EMPTY'  | 'CS12202FB02'(!)        = ''              | ''                 | 'CS12202FB02'           |'R0402'| '(R0402-0201)'                 | '220'     | '1%'    | '1/16W'  | 'IO'       | 'RES CHIP 220 1/16W +-1%(0402)DAL_AEC'             | 'CHIPR0402'    | ''          | ''            | '20160706'
 '240'        | '1%'      | '1/16W'  | '0402LF'  | 'CHIP'   | 'CS12402FB04'(!)        = ''              | ''                 | 'CS12402FB04'           |'R0402'| '(R0402-0201)'                 | '240'     | '1%'    | '1/16W'  | 'DISCRETE' | 'RES CHIP 240 1/16W +-1%(0402)DAL_AEC'             | 'CHIPR0402'    | ''          | ''            | '20160706'
 '240'        | '1%'      | '1/16W'  | '0402LF'  | 'EMPTY'  | 'CS12402FB04'(!)        = ''              | ''                 | 'CS12402FB04'           |'R0402'| '(R0402-0201)'                 | '240'     | '1%'    | '1/16W'  | 'IO'       | 'RES CHIP 240 1/16W +-1%(0402)DAL_AEC'             | 'CHIPR0402'    | ''          | ''            | '20160706'
 '330'        | '1%'      | '1/16W'  | '0402LF'  | 'CHIP'   | 'CS13302FB03'(!)        = ''              | ''                 | 'CS13302FB03'           |'R0402'| '(R0402-0201)'                 | '330'     | '1%'    | '1/16W'  | 'DISCRETE' | 'RES CHIP 330 1/16W +-1%(0402)DAL_AEC'             | 'CHIPR0402'    | ''          | ''            | '20160706'
 '330'        | '1%'      | '1/16W'  | '0402LF'  | 'EMPTY'  | 'CS13302FB03'(!)        = ''              | ''                 | 'CS13302FB03'           |'R0402'| '(R0402-0201)'                 | '330'     | '1%'    | '1/16W'  | 'IO'       | 'RES CHIP 330 1/16W +-1%(0402)DAL_AEC'             | 'CHIPR0402'    | ''          | ''            | '20160706'
 '332'        | '1%'      | '1/16W'  | '0402LF'  | 'CHIP'   | 'CS13322FB07'(!)        = ''              | ''                 | 'CS13322FB07'           |'R0402'| '(R0402-0201)'                 | '332'     | '1%'    | '1/16W'  | 'DISCRETE' | 'RES CHIP 332 1/16W +-1%(0402)DAL_AEC'             | 'CHIPR0402'    | ''          | ''            | '20160706'
 '332'        | '1%'      | '1/16W'  | '0402LF'  | 'EMPTY'  | 'CS13322FB07'(!)        = ''              | ''                 | 'CS13322FB07'           |'R0402'| '(R0402-0201)'                 | '332'     | '1%'    | '1/16W'  | 'IO'       | 'RES CHIP 332 1/16W +-1%(0402)DAL_AEC'             | 'CHIPR0402'    | ''          | ''            | '20160706'
 '348'        | '1%'      | '1/16W'  | '0402LF'  | 'CHIP'   | 'CS13482FB05'(!)        = ''              | ''                 | 'CS13482FB05'           |'R0402'| '(R0402-0201)'                 | '348'     | '1%'    | '1/16W'  | 'DISCRETE' | 'RES CHIP 348 1/16W +-1%(0402)DAL_AEC'             | 'CHIPR0402'    | ''          | ''            | '20160706'
 '348'        | '1%'      | '1/16W'  | '0402LF'  | 'EMPTY'  | 'CS13482FB05'(!)        = ''              | ''                 | 'CS13482FB05'           |'R0402'| '(R0402-0201)'                 | '348'     | '1%'    | '1/16W'  | 'IO'       | 'RES CHIP 348 1/16W +-1%(0402)DAL_AEC'             | 'CHIPR0402'    | ''          | ''            | '20160706'
 '412'        | '1%'      | '1/16W'  | '0402LF'  | 'CHIP'   | 'CS14122FB03'(!)        = ''              | ''                 | 'CS14122FB03'           |'R0402'| '(R0402-0201)'                 | '412'     | '1%'    | '1/16W'  | 'DISCRETE' | 'RES CHIP 412 1/16W +-1%(0402)DAL_AEC'             | 'CHIPR0402'    | ''          | ''            | '20160706'
 '412'        | '1%'      | '1/16W'  | '0402LF'  | 'EMPTY'  | 'CS14122FB03'(!)        = ''              | ''                 | 'CS14122FB03'           |'R0402'| '(R0402-0201)'                 | '412'     | '1%'    | '1/16W'  | 'IO'       | 'RES CHIP 412 1/16W +-1%(0402)DAL_AEC'             | 'CHIPR0402'    | ''          | ''            | '20160706'
 '475'        | '1%'      | '1/16W'  | '0402LF'  | 'CHIP'   | 'CS14752FB10'(!)        = ''              | ''                 | 'CS14752FB10'           |'R0402'| '(R0402-0201)'                 | '475'     | '1%'    | '1/16W'  | 'DISCRETE' | 'RES CHIP 475 1/16W +-1%(0402)DAL_AEC'             | 'CHIPR0402'    | ''          | ''            | '20160711'
 '475'        | '1%'      | '1/16W'  | '0402LF'  | 'EMPTY'  | 'CS14752FB10'(!)        = ''              | ''                 | 'CS14752FB10'           |'R0402'| '(R0402-0201)'                 | '475'     | '1%'    | '1/16W'  | 'IO'       | 'RES CHIP 475 1/16W +-1%(0402)DAL_AEC'             | 'CHIPR0402'    | ''          | ''            | '20160711'
 '511'        | '1%'      | '1/16W'  | '0402LF'  | 'CHIP'   | 'CS15112FB06'(!)        = ''              | ''                 | 'CS15112FB06'           |'R0402'| '(R0402-0201)'                 | '511'     | '1%'    | '1/16W'  | 'DISCRETE' | 'RES CHIP 511 1/16W +-1%(0402)DAL_AEC'             | 'CHIPR0402'    | ''          | ''            | '20160711'
 '511'        | '1%'      | '1/16W'  | '0402LF'  | 'EMPTY'  | 'CS15112FB06'(!)        = ''              | ''                 | 'CS15112FB06'           |'R0402'| '(R0402-0201)'                 | '511'     | '1%'    | '1/16W'  | 'IO'       | 'RES CHIP 511 1/16W +-1%(0402)DAL_AEC'             | 'CHIPR0402'    | ''          | ''            | '20160711'
 '845'        | '1%'      | '1/16W'  | '0402LF'  | 'CHIP'   | 'CS18452FB04'(!)        = ''              | ''                 | 'CS18452FB04'           |'R0402'| '(R0402-0201)'                 | '845'     | '1%'    | '1/16W'  | 'DISCRETE' | 'RES CHIP 845 1/16W +-1%(0402)DAL_AEC'             | 'CHIPR0402'    | ''          | ''            | '20160713'
 '845'        | '1%'      | '1/16W'  | '0402LF'  | 'EMPTY'  | 'CS18452FB04'(!)        = ''              | ''                 | 'CS18452FB04'           |'R0402'| '(R0402-0201)'                 | '845'     | '1%'    | '1/16W'  | 'IO'       | 'RES CHIP 845 1/16W +-1%(0402)DAL_AEC'             | 'CHIPR0402'    | ''          | ''            | '20160713'
 '2'          | '1%'      | '1/16W'  | '0402LF'  | 'CHIP'   | 'CS-2002FB04'(!)        = 'End of Design' | 'Comp-Approve'     | 'CS-2002FB04'           |'R0402'| '(R0402-0201)'                 | '2'       | '1%'    | '1/16W'  | 'DISCRETE' | 'RES CHIP 2 1/16W +-1%(0402)DAL_AEC'               | 'CHIPR0402'    | ''          | ''            | '20160713'
 '2'          | '1%'      | '1/16W'  | '0402LF'  | 'EMPTY'  | 'CS-2002FB04'(!)        = 'End of Design' | 'Comp-Approve'     | 'CS-2002FB04'           |'R0402'| '(R0402-0201)'                 | '2'       | '1%'    | '1/16W'  | 'IO'       | 'RES CHIP 2 1/16W +-1%(0402)DAL_AEC'               | 'CHIPR0402'    | ''          | ''            | '20160713'
 '2.2K'       | '1%'      | '1/16W'  | '0402LF'  | 'CHIP'   | 'CS22202FB03'(!)        = ''              | ''                 | 'CS22202FB03'           |'R0402'| '(R0402-0201)'                 | '2.2K'    | '1%'    | '1/16W'  | 'DISCRETE' | 'RES CHIP 2.2K 1/16W +-1%(0402)DAL_AEC'            | 'CHIPR0402'    | ''          | ''            | '20160713'
 '2.2K'       | '1%'      | '1/16W'  | '0402LF'  | 'EMPTY'  | 'CS22202FB03'(!)        = ''              | ''                 | 'CS22202FB03'           |'R0402'| '(R0402-0201)'                 | '2.2K'    | '1%'    | '1/16W'  | 'IO'       | 'RES CHIP 2.2K 1/16W +-1%(0402)DAL_AEC'            | 'CHIPR0402'    | ''          | ''            | '20160713'
 '2.21K'      | '1%'      | '1/16W'  | '0402LF'  | 'CHIP'   | 'CS22212FB08'(!)        = ''              | ''                 | 'CS22212FB08'           |'R0402'| '(R0402-0201)'                 | '2.21K'   | '1%'    | '1/16W'  | 'DISCRETE' | 'RES CHIP 2.21K 1/16W +-1%(0402)DAL_AEC'           | 'CHIPR0402'    | ''          | ''            | '20160713'
 '2.21K'      | '1%'      | '1/16W'  | '0402LF'  | 'EMPTY'  | 'CS22212FB08'(!)        = ''              | ''                 | 'CS22212FB08'           |'R0402'| '(R0402-0201)'                 | '2.21K'   | '1%'    | '1/16W'  | 'IO'       | 'RES CHIP 2.21K 1/16W +-1%(0402)DAL_AEC'           | 'CHIPR0402'    | ''          | ''            | '20160713'
 '49.9'       | '1%'      | '1/10W'  | '0603LF'  | 'CHIP'   | 'CS04993F908'(!)        = ''              | ''                 | 'CS04993F908'           |'R0603'| '(SMR0603AW)'                  | '49.9'    | '1%'    | '1/10W'  | 'DISCRETE' | 'RES CHIP 49.9 1/10W +-1%(0603)DAL_AEC'            | 'CHIPR0603'    | ''          | ''            | '20160713'
 '49.9'       | '1%'      | '1/10W'  | '0603LF'  | 'EMPTY'  | 'CS04993F908'(!)        = ''              | ''                 | 'CS04993F908'           |'R0603'| '(SMR0603AW)'                  | '49.9'    | '1%'    | '1/10W'  | 'IO'       | 'RES CHIP 49.9 1/10W +-1%(0603)DAL_AEC'            | 'CHIPR0603'    | ''          | ''            | '20160713'
 '0.0002'     | '1%'      | '9W'     | '3921LF'  | 'CHIP'   | 'CS0000KFY00'(!)        = ''              | ''                 | 'CS0000KFY00'           |'R3921'| '(SMR3921AW)'                  | '0.0002'  | '1%'    | '9W'     | 'DISCRETE' | 'RES CHIP 0.0002 9W +-1%(3921)DAL_AEC'             | 'CHIPR3921'    | ''          | ''            | '20160725'
 '0.0002'     | '1%'      | '9W'     | '3921LF'  | 'EMPTY'  | 'CS0000KFY00'(!)        = ''              | ''                 | 'CS0000KFY00'           |'R3921'| '(SMR3921AW)'                  | '0.0002'  | '1%'    | '9W'     | 'IO'       | 'RES CHIP 0.0002 9W +-1%(3921)DAL_AEC'             | 'CHIPR3921'    | ''          | ''            | '20160725'
 '1K'         | '1%'      | '1/16W'  | '0402LF'  | 'CHIP'   | 'CS21002FB13'(!)        = ''              | ''                 | 'CS21002FB13'           |'R0402'| '(R0402-0201)'                 | '1K'      | '1%'    | '1/16W'  | 'DISCRETE' | 'RES CHIP 1K 1/16W +-1%(0402)DAL_AEC'              | 'CHIPR0402'    | ''          | ''            | '20160725'
 '1K'         | '1%'      | '1/16W'  | '0402LF'  | 'EMPTY'  | 'CS21002FB13'(!)        = ''              | ''                 | 'CS21002FB13'           |'R0402'| '(R0402-0201)'                 | '1K'      | '1%'    | '1/16W'  | 'IO'       | 'RES CHIP 1K 1/16W +-1%(0402)DAL_AEC'              | 'CHIPR0402'    | ''          | ''            | '20160725'
 '2.55K'      | '1%'      | '1/16W'  | '0402LF'  | 'CHIP'   | 'CS22552FB03'(!)        = ''              | ''                 | 'CS22552FB03'           |'R0402'| '(R0402-0201)'                 | '2.55K'   | '1%'    | '1/16W'  | 'DISCRETE' | 'RES CHIP 2.55K 1/16W +-1%(0402)DAL_AEC'           | 'CHIPR0402'    | ''          | ''            | '20160725'
 '2.55K'      | '1%'      | '1/16W'  | '0402LF'  | 'EMPTY'  | 'CS22552FB03'(!)        = ''              | ''                 | 'CS22552FB03'           |'R0402'| '(R0402-0201)'                 | '2.55K'   | '1%'    | '1/16W'  | 'IO'       | 'RES CHIP 2.55K 1/16W +-1%(0402)DAL_AEC'           | 'CHIPR0402'    | ''          | ''            | '20160725'
 '3.01K'      | '1%'      | '1/16W'  | '0402LF'  | 'CHIP'   | 'CS23012FB10'(!)        = ''              | ''                 | 'CS23012FB10'           |'R0402'| '(R0402-0201)'                 | '3.01K'   | '1%'    | '1/16W'  | 'DISCRETE' | 'RES CHIP 3.01K 1/16W +-1%(0402)DAL_AEC'           | 'CHIPR0402'    | ''          | ''            | '20160725'
 '3.01K'      | '1%'      | '1/16W'  | '0402LF'  | 'EMPTY'  | 'CS23012FB10'(!)        = ''              | ''                 | 'CS23012FB10'           |'R0402'| '(R0402-0201)'                 | '3.01K'   | '1%'    | '1/16W'  | 'IO'       | 'RES CHIP 3.01K 1/16W +-1%(0402)DAL_AEC'           | 'CHIPR0402'    | ''          | ''            | '20160725'
 '3.3K'       | '1%'      | '1/16W'  | '0402LF'  | 'CHIP'   | 'CS23302FB03'(!)        = ''              | ''                 | 'CS23302FB03'           |'R0402'| '(R0402-0201)'                 | '3.3K'    | '1%'    | '1/16W'  | 'DISCRETE' | 'RES CHIP 3.3K 1/16W +-1%(0402)DAL_AEC'            | 'CHIPR0402'    | ''          | ''            | '20160725'
 '3.3K'       | '1%'      | '1/16W'  | '0402LF'  | 'EMPTY'  | 'CS23302FB03'(!)        = ''              | ''                 | 'CS23302FB03'           |'R0402'| '(R0402-0201)'                 | '3.3K'    | '1%'    | '1/16W'  | 'IO'       | 'RES CHIP 3.3K 1/16W +-1%(0402)DAL_AEC'            | 'CHIPR0402'    | ''          | ''            | '20160725'
 '3.32K'      | '1%'      | '1/16W'  | '0402LF'  | 'CHIP'   | 'CS23322FB07'(!)        = ''              | ''                 | 'CS23322FB07'           |'R0402'| '(R0402-0201)'                 | '3.32K'   | '1%'    | '1/16W'  | 'DISCRETE' | 'RES CHIP 3.32K 1/16W +-1% (0402)DAL_AEC'          | 'CHIPR0402'    | ''          | ''            | '20160725'
 '3.32K'      | '1%'      | '1/16W'  | '0402LF'  | 'EMPTY'  | 'CS23322FB07'(!)        = ''              | ''                 | 'CS23322FB07'           |'R0402'| '(R0402-0201)'                 | '3.32K'   | '1%'    | '1/16W'  | 'IO'       | 'RES CHIP 3.32K 1/16W +-1% (0402)DAL_AEC'          | 'CHIPR0402'    | ''          | ''            | '20160725'
 '3.4K'       | '1%'      | '1/16W'  | '0402LF'  | 'CHIP'   | 'CS23402FB03'(!)        = ''              | ''                 | 'CS23402FB03'           |'R0402'| '(R0402-0201)'                 | '3.4K'    | '1%'    | '1/16W'  | 'DISCRETE' | 'RES CHIP 3.4K 1/16W +-1%(0402)DAL_AEC'            | 'CHIPR0402'    | ''          | ''            | '20160725'
 '3.4K'       | '1%'      | '1/16W'  | '0402LF'  | 'EMPTY'  | 'CS23402FB03'(!)        = ''              | ''                 | 'CS23402FB03'           |'R0402'| '(R0402-0201)'                 | '3.4K'    | '1%'    | '1/16W'  | 'IO'       | 'RES CHIP 3.4K 1/16W +-1%(0402)DAL_AEC'            | 'CHIPR0402'    | ''          | ''            | '20160725'
 '3.57K'      | '1%'      | '1/16W'  | '0402LF'  | 'CHIP'   | 'CS23572FB07'(!)        = ''              | ''                 | 'CS23572FB07'           |'R0402'| '(R0402-0201)'                 | '3.57K'   | '1%'    | '1/16W'  | 'DISCRETE' | 'RES CHIP 3.57K 1/16W +-1%(0402)DAL_AEC'           | 'CHIPR0402'    | ''          | ''            | '20160725'
 '3.57K'      | '1%'      | '1/16W'  | '0402LF'  | 'EMPTY'  | 'CS23572FB07'(!)        = ''              | ''                 | 'CS23572FB07'           |'R0402'| '(R0402-0201)'                 | '3.57K'   | '1%'    | '1/16W'  | 'IO'       | 'RES CHIP 3.57K 1/16W +-1%(0402)DAL_AEC'           | 'CHIPR0402'    | ''          | ''            | '20160725'
 '4.02K'      | '1%'      | '1/16W'  | '0402LF'  | 'CHIP'   | 'CS24022FB07'(!)        = ''              | ''                 | 'CS24022FB07'           |'R0402'| '(R0402-0201)'                 | '4.02K'   | '1%'    | '1/16W'  | 'DISCRETE' | 'RES CHIP 4.02K 1/16W +-1%(0402)DAL_AEC'           | 'CHIPR0402'    | ''          | ''            | '20160725'
 '4.02K'      | '1%'      | '1/16W'  | '0402LF'  | 'EMPTY'  | 'CS24022FB07'(!)        = ''              | ''                 | 'CS24022FB07'           |'R0402'| '(R0402-0201)'                 | '4.02K'   | '1%'    | '1/16W'  | 'IO'       | 'RES CHIP 4.02K 1/16W +-1%(0402)DAL_AEC'           | 'CHIPR0402'    | ''          | ''            | '20160725'
 '4.12K'      | '1%'      | '1/16W'  | '0402LF'  | 'CHIP'   | 'CS24122FB03'(!)        = ''              | ''                 | 'CS24122FB03'           |'R0402'| '(R0402-0201)'                 | '4.12K'   | '1%'    | '1/16W'  | 'DISCRETE' | 'RES CHIP 4.12K 1/16W +-1%(0402)DAL_AEC'           | 'CHIPR0402'    | ''          | ''            | '20160725'
 '4.12K'      | '1%'      | '1/16W'  | '0402LF'  | 'EMPTY'  | 'CS24122FB03'(!)        = ''              | ''                 | 'CS24122FB03'           |'R0402'| '(R0402-0201)'                 | '4.12K'   | '1%'    | '1/16W'  | 'IO'       | 'RES CHIP 4.12K 1/16W +-1%(0402)DAL_AEC'           | 'CHIPR0402'    | ''          | ''            | '20160725'
 '1.1K'       | '1%'      | '1/16W'  | '0402LF'  | 'CHIP'   | 'CS21102FB06'(!)        = ''              | ''                 | 'CS21102FB06'           |'R0402'| '(R0402-0201)'                 | '1.1K'    | '1%'    | '1/16W'  | 'DISCRETE' | 'RES CHIP 1.1K 1/16W +1% (0402)DAL_AEC'            | 'CHIPR0402'    | ''          | ''            | '20160725'
 '1.1K'       | '1%'      | '1/16W'  | '0402LF'  | 'EMPTY'  | 'CS21102FB06'(!)        = ''              | ''                 | 'CS21102FB06'           |'R0402'| '(R0402-0201)'                 | '1.1K'    | '1%'    | '1/16W'  | 'IO'       | 'RES CHIP 1.1K 1/16W +1% (0402)DAL_AEC'            | 'CHIPR0402'    | ''          | ''            | '20160725'
 '51.1'       | '1%'      | '1/20W'  | '0201LF'  | 'CHIP'   | 'CS05111FE00'(!)        = ''              | ''                 | 'CS05111FE00'           |'R0201'| '(SMR0201AW)'                  | '51.1'    | '1%'    | '1/20W'  | 'DISCRETE' | 'RES CHIP 51.1 1/20W +-1%(0201)'                   | 'CHIPR0201'    | ''          | ''            | '20160725'
 '51.1'       | '1%'      | '1/20W'  | '0201LF'  | 'EMPTY'  | 'CS05111FE00'(!)        = ''              | ''                 | 'CS05111FE00'           |'R0201'| '(SMR0201AW)'                  | '51.1'    | '1%'    | '1/20W'  | 'IO'       | 'RES CHIP 51.1 1/20W +-1%(0201)'                   | 'CHIPR0201'    | ''          | ''            | '20160725'
 '1.5K'       | '1%'      | '1/16W'  | '0402LF'  | 'CHIP'   | 'CS21502FB09'(!)        = ''              | ''                 | 'CS21502FB09'           |'R0402'| '(R0402-0201)'                 | '1.5K'    | '1%'    | '1/16W'  | 'DISCRETE' | 'RES CHIP 1.5K 1/16W +1% (0402)DAL_AEC'            | 'CHIPR0402'    | ''          | ''            | '20160727'
 '1.5K'       | '1%'      | '1/16W'  | '0402LF'  | 'EMPTY'  | 'CS21502FB09'(!)        = ''              | ''                 | 'CS21502FB09'           |'R0402'| '(R0402-0201)'                 | '1.5K'    | '1%'    | '1/16W'  | 'IO'       | 'RES CHIP 1.5K 1/16W +1% (0402)DAL_AEC'            | 'CHIPR0402'    | ''          | ''            | '20160727'
 '1.69K'      | '1%'      | '1/16W'  | '0402LF'  | 'CHIP'   | 'CS21692FB03'(!)        = ''              | ''                 | 'CS21692FB03'           |'R0402'| '(R0402-0201)'                 | '1.69K'   | '1%'    | '1/16W'  | 'DISCRETE' | 'RES CHIP 1.69K 1/16W +-1%(0402)DAL_AEC'           | 'CHIPR0402'    | ''          | ''            | '20160727'
 '1.69K'      | '1%'      | '1/16W'  | '0402LF'  | 'EMPTY'  | 'CS21692FB03'(!)        = ''              | ''                 | 'CS21692FB03'           |'R0402'| '(R0402-0201)'                 | '1.69K'   | '1%'    | '1/16W'  | 'IO'       | 'RES CHIP 1.69K 1/16W +-1%(0402)DAL_AEC'           | 'CHIPR0402'    | ''          | ''            | '20160727'
 '1.8K'       | '1%'      | '1/16W'  | '0402LF'  | 'CHIP'   | 'CS21802FB04'(!)        = ''              | ''                 | 'CS21802FB04'           |'R0402'| '(R0402-0201)'                 | '1.8K'    | '1%'    | '1/16W'  | 'DISCRETE' | 'RES CHIP 1.8K 1/16W +-1%(0402) DAL_AEC'           | 'CHIPR0402'    | ''          | ''            | '20160727'
 '1.8K'       | '1%'      | '1/16W'  | '0402LF'  | 'EMPTY'  | 'CS21802FB04'(!)        = ''              | ''                 | 'CS21802FB04'           |'R0402'| '(R0402-0201)'                 | '1.8K'    | '1%'    | '1/16W'  | 'IO'       | 'RES CHIP 1.8K 1/16W +-1%(0402) DAL_AEC'           | 'CHIPR0402'    | ''          | ''            | '20160727'
 '2K'         | '1%'      | '1/16W'  | '0402LF'  | 'CHIP'   | 'CS22002FB12'(!)        = ''              | ''                 | 'CS22002FB12'           |'R0402'| '(R0402-0201)'                 | '2K'      | '1%'    | '1/16W'  | 'DISCRETE' | 'RES CHIP 2K 1/16W +-1%(0402)DAL_AEC'              | 'CHIPR0402'    | ''          | ''            | '20160727'
 '2K'         | '1%'      | '1/16W'  | '0402LF'  | 'EMPTY'  | 'CS22002FB12'(!)        = ''              | ''                 | 'CS22002FB12'           |'R0402'| '(R0402-0201)'                 | '2K'      | '1%'    | '1/16W'  | 'IO'       | 'RES CHIP 2K 1/16W +-1%(0402)DAL_AEC'              | 'CHIPR0402'    | ''          | ''            | '20160727'
 '2.2'        | '1%'      | '1/16W'  | '0402LF'  | 'CHIP'   | 'CS-2202FB03'(!)        = 'End of Design' | 'Comp-Approve'     | 'CS-2202FB03'           |'R0402'| '(R0402-0201)'                 | '2.2'     | '1%'    | '1/16W'  | 'DISCRETE' | 'RES CHIP 2.2 1/16W +-1%(0402)DAL_AEC'             | 'CHIPR0402'    | ''          | ''            | '20160727'
 '2.2'        | '1%'      | '1/16W'  | '0402LF'  | 'EMPTY'  | 'CS-2202FB03'(!)        = 'End of Design' | 'Comp-Approve'     | 'CS-2202FB03'           |'R0402'| '(R0402-0201)'                 | '2.2'     | '1%'    | '1/16W'  | 'IO'       | 'RES CHIP 2.2 1/16W +-1%(0402)DAL_AEC'             | 'CHIPR0402'    | ''          | ''            | '20160727'
 '4.75K'      | '1%'      | '1/16W'  | '0402LF'  | 'CHIP'   | 'CS24752FB06'(!)        = ''              | ''                 | 'CS24752FB06'           |'R0402'| '(R0402-0201)'                 | '4.75K'   | '1%'    | '1/16W'  | 'DISCRETE' | 'RES CHIP 4.75K 1/16W +-1%(0402)DAL_AEC'           | 'CHIPR0402'    | ''          | ''            | '20160727'
 '4.75K'      | '1%'      | '1/16W'  | '0402LF'  | 'EMPTY'  | 'CS24752FB06'(!)        = ''              | ''                 | 'CS24752FB06'           |'R0402'| '(R0402-0201)'                 | '4.75K'   | '1%'    | '1/16W'  | 'IO'       | 'RES CHIP 4.75K 1/16W +-1%(0402)DAL_AEC'           | 'CHIPR0402'    | ''          | ''            | '20160727'
 '4.87K'      | '1%'      | '1/16W'  | '0402LF'  | 'CHIP'   | 'CS24872FB03'(!)        = ''              | ''                 | 'CS24872FB03'           |'R0402'| '(R0402-0201)'                 | '4.87K'   | '1%'    | '1/16W'  | 'DISCRETE' | 'RES CHIP 4.87K 1/16W+-1%(0402)DAL_AEC'            | 'CHIPR0402'    | ''          | ''            | '20160727'
 '4.87K'      | '1%'      | '1/16W'  | '0402LF'  | 'EMPTY'  | 'CS24872FB03'(!)        = ''              | ''                 | 'CS24872FB03'           |'R0402'| '(R0402-0201)'                 | '4.87K'   | '1%'    | '1/16W'  | 'IO'       | 'RES CHIP 4.87K 1/16W+-1%(0402)DAL_AEC'            | 'CHIPR0402'    | ''          | ''            | '20160727'
 '4.99K'      | '1%'      | '1/16W'  | '0402LF'  | 'CHIP'   | 'CS24992FB09'(!)        = ''              | ''                 | 'CS24992FB09'           |'R0402'| '(R0402-0201)'                 | '4.99K'   | '1%'    | '1/16W'  | 'DISCRETE' | 'RES CHIP 4.99K 1/16W +-1%(0402)DAL_AEC'           | 'CHIPR0402'    | ''          | ''            | '20160727'
 '4.99K'      | '1%'      | '1/16W'  | '0402LF'  | 'EMPTY'  | 'CS24992FB09'(!)        = ''              | ''                 | 'CS24992FB09'           |'R0402'| '(R0402-0201)'                 | '4.99K'   | '1%'    | '1/16W'  | 'IO'       | 'RES CHIP 4.99K 1/16W +-1%(0402)DAL_AEC'           | 'CHIPR0402'    | ''          | ''            | '20160727'
 '5.76K'      | '1%'      | '1/16W'  | '0402LF'  | 'CHIP'   | 'CS25762FB05'(!)        = ''              | ''                 | 'CS25762FB05'           |'R0402'| '(R0402-0201)'                 | '5.76K'   | '1%'    | '1/16W'  | 'DISCRETE' | 'RES CHIP 5.76K 1/16W +-1%(0402)DAL_AEC'           | 'CHIPR0402'    | ''          | ''            | '20160727'
 '5.76K'      | '1%'      | '1/16W'  | '0402LF'  | 'EMPTY'  | 'CS25762FB05'(!)        = ''              | ''                 | 'CS25762FB05'           |'R0402'| '(R0402-0201)'                 | '5.76K'   | '1%'    | '1/16W'  | 'IO'       | 'RES CHIP 5.76K 1/16W +-1%(0402)DAL_AEC'           | 'CHIPR0402'    | ''          | ''            | '20160727'
 '6.81K'      | '1%'      | '1/16W'  | '0402LF'  | 'CHIP'   | 'CS26812FB07'(!)        = ''              | ''                 | 'CS26812FB07'           |'R0402'| '(R0402-0201)'                 | '6.81K'   | '1%'    | '1/16W'  | 'DISCRETE' | 'RES CHIP 6.81K 1/16W +-1%(0402)DAL_AEC'           | 'CHIPR0402'    | ''          | ''            | '20160727'
 '6.81K'      | '1%'      | '1/16W'  | '0402LF'  | 'EMPTY'  | 'CS26812FB07'(!)        = ''              | ''                 | 'CS26812FB07'           |'R0402'| '(R0402-0201)'                 | '6.81K'   | '1%'    | '1/16W'  | 'IO'       | 'RES CHIP 6.81K 1/16W +-1%(0402)DAL_AEC'           | 'CHIPR0402'    | ''          | ''            | '20160727'
 '6.98K'      | '1%'      | '1/16W'  | '0402LF'  | 'CHIP'   | 'CS26982FB05'(!)        = ''              | ''                 | 'CS26982FB05'           |'R0402'| '(R0402-0201)'                 | '6.98K'   | '1%'    | '1/16W'  | 'DISCRETE' | 'RES CHIP 6.98K 1/16W +-1% (0402)DAL_AEC'          | 'CHIPR0402'    | ''          | ''            | '20160727'
 '6.98K'      | '1%'      | '1/16W'  | '0402LF'  | 'EMPTY'  | 'CS26982FB05'(!)        = ''              | ''                 | 'CS26982FB05'           |'R0402'| '(R0402-0201)'                 | '6.98K'   | '1%'    | '1/16W'  | 'IO'       | 'RES CHIP 6.98K 1/16W +-1% (0402)DAL_AEC'          | 'CHIPR0402'    | ''          | ''            | '20160727'
 '8.25K'      | '1%'      | '1/16W'  | '0402LF'  | 'CHIP'   | 'CS28252FB05'(!)        = ''              | ''                 | 'CS28252FB05'           |'R0402'| '(R0402-0201)'                 | '8.25K'   | '1%'    | '1/16W'  | 'DISCRETE' | 'RES CHIP 8.25K 1/16W+-1%(0402)DAL_AEC'            | 'CHIPR0402'    | ''          | ''            | '20160727'
 '8.25K'      | '1%'      | '1/16W'  | '0402LF'  | 'EMPTY'  | 'CS28252FB05'(!)        = ''              | ''                 | 'CS28252FB05'           |'R0402'| '(R0402-0201)'                 | '8.25K'   | '1%'    | '1/16W'  | 'IO'       | 'RES CHIP 8.25K 1/16W+-1%(0402)DAL_AEC'            | 'CHIPR0402'    | ''          | ''            | '20160727'
 '10K'        | '1%'      | '1/16W'  | '0402LF'  | 'CHIP'   | 'CS31002FB14'(!)        = ''              | ''                 | 'CS31002FB14'           |'R0402'| '(R0402-0201)'                 | '10K'     | '1%'    | '1/16W'  | 'DISCRETE' | 'RES CHIP 10K 1/16W +-1%(0402)DAL_AEC'             | 'CHIPR0402'    | ''          | ''            | '20160727'
 '10K'        | '1%'      | '1/16W'  | '0402LF'  | 'EMPTY'  | 'CS31002FB14'(!)        = ''              | ''                 | 'CS31002FB14'           |'R0402'| '(R0402-0201)'                 | '10K'     | '1%'    | '1/16W'  | 'IO'       | 'RES CHIP 10K 1/16W +-1%(0402)DAL_AEC'             | 'CHIPR0402'    | ''          | ''            | '20160727'
 '11K'        | '1%'      | '1/16W'  | '0402LF'  | 'CHIP'   | 'CS31102FB07'(!)        = ''              | ''                 | 'CS31102FB07'           |'R0402'| '(R0402-0201)'                 | '11K'     | '1%'    | '1/16W'  | 'DISCRETE' | 'RES CHIP 11K 1/16W +-1% (0402)DAL_AEC'            | 'CHIPR0402'    | ''          | ''            | '20160727'
 '11K'        | '1%'      | '1/16W'  | '0402LF'  | 'EMPTY'  | 'CS31102FB07'(!)        = ''              | ''                 | 'CS31102FB07'           |'R0402'| '(R0402-0201)'                 | '11K'     | '1%'    | '1/16W'  | 'IO'       | 'RES CHIP 11K 1/16W +-1% (0402)DAL_AEC'            | 'CHIPR0402'    | ''          | ''            | '20160727'
 '12K'        | '1%'      | '1/16W'  | '0402LF'  | 'CHIP'   | 'CS31202FB06'(!)        = ''              | ''                 | 'CS31202FB06'           |'R0402'| '(R0402-0201)'                 | '12K'     | '1%'    | '1/16W'  | 'DISCRETE' | 'RES CHIP 12K 1/16W +-1%(0402)DAL_AEC'             | 'CHIPR0402'    | ''          | ''            | '20160727'
 '12K'        | '1%'      | '1/16W'  | '0402LF'  | 'EMPTY'  | 'CS31202FB06'(!)        = ''              | ''                 | 'CS31202FB06'           |'R0402'| '(R0402-0201)'                 | '12K'     | '1%'    | '1/16W'  | 'IO'       | 'RES CHIP 12K 1/16W +-1%(0402)DAL_AEC'             | 'CHIPR0402'    | ''          | ''            | '20160727'
 '12.1K'      | '1%'      | '1/16W'  | '0402LF'  | 'CHIP'   | 'CS31212FB07'(!)        = ''              | ''                 | 'CS31212FB07'           |'R0402'| '(R0402-0201)'                 | '12.1K'   | '1%'    | '1/16W'  | 'DISCRETE' | 'RES CHIP 12.1K 1/16W +1%(0402)DAL_AEC'            | 'CHIPR0402'    | ''          | ''            | '20160727'
 '12.1K'      | '1%'      | '1/16W'  | '0402LF'  | 'EMPTY'  | 'CS31212FB07'(!)        = ''              | ''                 | 'CS31212FB07'           |'R0402'| '(R0402-0201)'                 | '12.1K'   | '1%'    | '1/16W'  | 'IO'       | 'RES CHIP 12.1K 1/16W +1%(0402)DAL_AEC'            | 'CHIPR0402'    | ''          | ''            | '20160727'
 '13.7K'      | '1%'      | '1/16W'  | '0402LF'  | 'CHIP'   | 'CS31372FB04'(!)        = ''              | ''                 | 'CS31372FB04'           |'R0402'| '(R0402-0201)'                 | '13.7K'   | '1%'    | '1/16W'  | 'DISCRETE' | 'RES CHIP 13.7K 1/16W +-1%(0402)DAL_AEC'           | 'CHIPR0402'    | ''          | ''            | '20160727'
 '13.7K'      | '1%'      | '1/16W'  | '0402LF'  | 'EMPTY'  | 'CS31372FB04'(!)        = ''              | ''                 | 'CS31372FB04'           |'R0402'| '(R0402-0201)'                 | '13.7K'   | '1%'    | '1/16W'  | 'IO'       | 'RES CHIP 13.7K 1/16W +-1%(0402)DAL_AEC'           | 'CHIPR0402'    | ''          | ''            | '20160727'
 '15K'        | '1%'      | '1/16W'  | '0402LF'  | 'CHIP'   | 'CS31502FB07'(!)        = ''              | ''                 | 'CS31502FB07'           |'R0402'| '(R0402-0201)'                 | '15K'     | '1%'    | '1/16W'  | 'DISCRETE' | 'RES CHIP 15K 1/16W +-1%(0402)DAL_AEC'             | 'CHIPR0402'    | ''          | ''            | '20160727'
 '15K'        | '1%'      | '1/16W'  | '0402LF'  | 'EMPTY'  | 'CS31502FB07'(!)        = ''              | ''                 | 'CS31502FB07'           |'R0402'| '(R0402-0201)'                 | '15K'     | '1%'    | '1/16W'  | 'IO'       | 'RES CHIP 15K 1/16W +-1%(0402)DAL_AEC'             | 'CHIPR0402'    | ''          | ''            | '20160727'
 '15.4K'      | '1%'      | '1/16W'  | '0402LF'  | 'CHIP'   | 'CS31542FB03'(!)        = ''              | ''                 | 'CS31542FB03'           |'R0402'| '(R0402-0201)'                 | '15.4K'   | '1%'    | '1/16W'  | 'DISCRETE' | 'RES CHIP 15.4K 1/16W +1%(0402)DAL_AEC'            | 'CHIPR0402'    | ''          | ''            | '20160727'
 '15.4K'      | '1%'      | '1/16W'  | '0402LF'  | 'EMPTY'  | 'CS31542FB03'(!)        = ''              | ''                 | 'CS31542FB03'           |'R0402'| '(R0402-0201)'                 | '15.4K'   | '1%'    | '1/16W'  | 'IO'       | 'RES CHIP 15.4K 1/16W +1%(0402)DAL_AEC'            | 'CHIPR0402'    | ''          | ''            | '20160727'
 '15.8K'      | '1%'      | '1/16W'  | '0402LF'  | 'CHIP'   | 'CS31582FB05'(!)        = ''              | ''                 | 'CS31582FB05'           |'R0402'| '(R0402-0201)'                 | '15.8K'   | '1%'    | '1/16W'  | 'DISCRETE' | 'RES CHIP 15.8K 1/16W +-1% (0402)DAL_AEC'          | 'CHIPR0402'    | ''          | ''            | '20160727'
 '15.8K'      | '1%'      | '1/16W'  | '0402LF'  | 'EMPTY'  | 'CS31582FB05'(!)        = ''              | ''                 | 'CS31582FB05'           |'R0402'| '(R0402-0201)'                 | '15.8K'   | '1%'    | '1/16W'  | 'IO'       | 'RES CHIP 15.8K 1/16W +-1% (0402)DAL_AEC'          | 'CHIPR0402'    | ''          | ''            | '20160727'
 '16K'        | '1%'      | '1/16W'  | '0402LF'  | 'CHIP'   | 'CS31602FB03'(!)        = ''              | ''                 | 'CS31602FB03'           |'R0402'| '(R0402-0201)'                 | '16K'     | '1%'    | '1/16W'  | 'DISCRETE' | 'RES CHIP 16K 1/16W +-1%(0402)DAL_AEC'             | 'CHIPR0402'    | ''          | ''            | '20160727'
 '16K'        | '1%'      | '1/16W'  | '0402LF'  | 'EMPTY'  | 'CS31602FB03'(!)        = ''              | ''                 | 'CS31602FB03'           |'R0402'| '(R0402-0201)'                 | '16K'     | '1%'    | '1/16W'  | 'IO'       | 'RES CHIP 16K 1/16W +-1%(0402)DAL_AEC'             | 'CHIPR0402'    | ''          | ''            | '20160727'
 '20K'        | '1%'      | '1/16W'  | '0402LF'  | 'CHIP'   | 'CS32002FB13'(!)        = ''              | ''                 | 'CS32002FB13'           |'R0402'| '(R0402-0201)'                 | '20K'     | '1%'    | '1/16W'  | 'DISCRETE' | 'RES CHIP 20K 1/16W +-1%(0402)DAL_AEC'             | 'CHIPR0402'    | ''          | ''            | '20160727'
 '20K'        | '1%'      | '1/16W'  | '0402LF'  | 'EMPTY'  | 'CS32002FB13'(!)        = ''              | ''                 | 'CS32002FB13'           |'R0402'| '(R0402-0201)'                 | '20K'     | '1%'    | '1/16W'  | 'IO'       | 'RES CHIP 20K 1/16W +-1%(0402)DAL_AEC'             | 'CHIPR0402'    | ''          | ''            | '20160727'
 '21K'        | '1%'      | '1/16W'  | '0402LF'  | 'CHIP'   | 'CS32102FB04'(!)        = ''              | ''                 | 'CS32102FB04'           |'R0402'| '(R0402-0201)'                 | '21K'     | '1%'    | '1/16W'  | 'DISCRETE' | 'RES CHIP 21K 1/16W +-1%(0402)DAL_AEC'             | 'CHIPR0402'    | ''          | ''            | '20160727'
 '21K'        | '1%'      | '1/16W'  | '0402LF'  | 'EMPTY'  | 'CS32102FB04'(!)        = ''              | ''                 | 'CS32102FB04'           |'R0402'| '(R0402-0201)'                 | '21K'     | '1%'    | '1/16W'  | 'IO'       | 'RES CHIP 21K 1/16W +-1%(0402)DAL_AEC'             | 'CHIPR0402'    | ''          | ''            | '20160727'
 '22.1K'      | '1%'      | '1/16W'  | '0402LF'  | 'CHIP'   | 'CS32212FB03'(!)        = ''              | ''                 | 'CS32212FB03'           |'R0402'| '(R0402-0201)'                 | '22.1K'   | '1%'    | '1/16W'  | 'DISCRETE' | 'RES CHIP 22.1K 1/16W +-1%(0402)DAL_AEC'           | 'CHIPR0402'    | ''          | ''            | '20160727'
 '22.1K'      | '1%'      | '1/16W'  | '0402LF'  | 'EMPTY'  | 'CS32212FB03'(!)        = ''              | ''                 | 'CS32212FB03'           |'R0402'| '(R0402-0201)'                 | '22.1K'   | '1%'    | '1/16W'  | 'IO'       | 'RES CHIP 22.1K 1/16W +-1%(0402)DAL_AEC'           | 'CHIPR0402'    | ''          | ''            | '20160727'
 '3.3'        | '1%'      | '1/16W'  | '0402LF'  | 'CHIP'   | 'CS-3302FB03'(!)        = ''              | ''                 | 'CS-3302FB03'           |'R0402'| '(R0402-0201)'                 | '3.3'     | '1%'    | '1/16W'  | 'DISCRETE' | 'RES CHIP 3.3 1/16W +-1%(0402)DAL_AEC'             | 'CHIPR0402'    | ''          | ''            | '20160727'
 '3.3'        | '1%'      | '1/16W'  | '0402LF'  | 'EMPTY'  | 'CS-3302FB03'(!)        = ''              | ''                 | 'CS-3302FB03'           |'R0402'| '(R0402-0201)'                 | '3.3'     | '1%'    | '1/16W'  | 'IO'       | 'RES CHIP 3.3 1/16W +-1%(0402)DAL_AEC'             | 'CHIPR0402'    | ''          | ''            | '20160727'
 '237'        | '1%'      | '1/16W'  | '0402LF'  | 'CHIP'   | 'CS12372FB00'(!)        = 'End of Design' | 'Comp-Approve'     | 'CS12372FB00'           |'R0402'| '(R0402-0201)'                 | '237'     | '1%'    | '1/16W'  | 'DISCRETE' | 'RES CHIP 237 1/16W +-1%(0402)'                    | 'CHIPR0402'    | ''          | ''            | '20160727'
 '237'        | '1%'      | '1/16W'  | '0402LF'  | 'EMPTY'  | 'CS12372FB00'(!)        = 'End of Design' | 'Comp-Approve'     | 'CS12372FB00'           |'R0402'| '(R0402-0201)'                 | '237'     | '1%'    | '1/16W'  | 'IO'       | 'RES CHIP 237 1/16W +-1%(0402)'                    | 'CHIPR0402'    | ''          | ''            | '20160727'
 '31.6K'      | '1%'      | '1/16W'  | '0402LF'  | 'CHIP'   | 'CS33162FB03'(!)        = ''              | ''                 | 'CS33162FB03'           |'R0402'| '(R0402-0201)'                 | '31.6K'   | '1%'    | '1/16W'  | 'DISCRETE' | 'RES CHIP 31.6K 1/16W +1%(0402)DAL_AEC'            | 'CHIPR0402'    | ''          | ''            | '20160802'
 '31.6K'      | '1%'      | '1/16W'  | '0402LF'  | 'EMPTY'  | 'CS33162FB03'(!)        = ''              | ''                 | 'CS33162FB03'           |'R0402'| '(R0402-0201)'                 | '31.6K'   | '1%'    | '1/16W'  | 'IO'       | 'RES CHIP 31.6K 1/16W +1%(0402)DAL_AEC'            | 'CHIPR0402'    | ''          | ''            | '20160802'
 '27K'        | '1%'      | '1/16W'  | '0402LF'  | 'CHIP'   | 'CS32702FB02'(!)        = ''              | ''                 | 'CS32702FB02'           |'R0402'| '(R0402-0201)'                 | '27K'     | '1%'    | '1/16W'  | 'DISCRETE' | 'RES CHIP 27K 1/16W +-1%(0402)DAL_AEC'             | 'CHIPR0402'    | ''          | ''            | '20160802'
 '27K'        | '1%'      | '1/16W'  | '0402LF'  | 'EMPTY'  | 'CS32702FB02'(!)        = ''              | ''                 | 'CS32702FB02'           |'R0402'| '(R0402-0201)'                 | '27K'     | '1%'    | '1/16W'  | 'IO'       | 'RES CHIP 27K 1/16W +-1%(0402)DAL_AEC'             | 'CHIPR0402'    | ''          | ''            | '20160802'
 '27.4K'      | '1%'      | '1/16W'  | '0402LF'  | 'CHIP'   | 'CS32742FB05'(!)        = ''              | ''                 | 'CS32742FB05'           |'R0402'| '(R0402-0201)'                 | '27.4K'   | '1%'    | '1/16W'  | 'DISCRETE' | 'RES CHIP 27.4K 1/16W +-1%(0402)DAL_AEC'           | 'CHIPR0402'    | ''          | ''            | '20160802'
 '27.4K'      | '1%'      | '1/16W'  | '0402LF'  | 'EMPTY'  | 'CS32742FB05'(!)        = ''              | ''                 | 'CS32742FB05'           |'R0402'| '(R0402-0201)'                 | '27.4K'   | '1%'    | '1/16W'  | 'IO'       | 'RES CHIP 27.4K 1/16W +-1%(0402)DAL_AEC'           | 'CHIPR0402'    | ''          | ''            | '20160802'
 '25.5K'      | '1%'      | '1/16W'  | '0402LF'  | 'CHIP'   | 'CS32552FB05'(!)        = ''              | ''                 | 'CS32552FB05'           |'R0402'| '(R0402-0201)'                 | '25.5K'   | '1%'    | '1/16W'  | 'DISCRETE' | 'RES CHIP 25.5K 1/16W +-1%(0402)DAL_AEC'           | 'CHIPR0402'    | ''          | ''            | '20160802'
 '25.5K'      | '1%'      | '1/16W'  | '0402LF'  | 'EMPTY'  | 'CS32552FB05'(!)        = ''              | ''                 | 'CS32552FB05'           |'R0402'| '(R0402-0201)'                 | '25.5K'   | '1%'    | '1/16W'  | 'IO'       | 'RES CHIP 25.5K 1/16W +-1%(0402)DAL_AEC'           | 'CHIPR0402'    | ''          | ''            | '20160802'
 '41.2K'      | '1%'      | '1/16W'  | '0402LF'  | 'CHIP'   | 'CS34122FB02'(!)        = ''              | ''                 | 'CS34122FB02'           |'R0402'| '(R0402-0201)'                 | '41.2K'   | '1%'    | '1/16W'  | 'DISCRETE' | 'RES CHIP 41.2K 1/16W +-1%(0402)DAL_AEC'           | 'CHIPR0402'    | ''          | ''            | '20160802'
 '41.2K'      | '1%'      | '1/16W'  | '0402LF'  | 'EMPTY'  | 'CS34122FB02'(!)        = ''              | ''                 | 'CS34122FB02'           |'R0402'| '(R0402-0201)'                 | '41.2K'   | '1%'    | '1/16W'  | 'IO'       | 'RES CHIP 41.2K 1/16W +-1%(0402)DAL_AEC'           | 'CHIPR0402'    | ''          | ''            | '20160802'
 '37.4K'      | '1%'      | '1/16W'  | '0402LF'  | 'CHIP'   | 'CS33742FB07'(!)        = ''              | ''                 | 'CS33742FB07'           |'R0402'| '(R0402-0201)'                 | '37.4K'   | '1%'    | '1/16W'  | 'DISCRETE' | 'RES CHIP 37.4K 1/16W +-1% (0402)DAL_AEC'          | 'CHIPR0402'    | ''          | ''            | '20160802'
 '37.4K'      | '1%'      | '1/16W'  | '0402LF'  | 'EMPTY'  | 'CS33742FB07'(!)        = ''              | ''                 | 'CS33742FB07'           |'R0402'| '(R0402-0201)'                 | '37.4K'   | '1%'    | '1/16W'  | 'IO'       | 'RES CHIP 37.4K 1/16W +-1% (0402)DAL_AEC'          | 'CHIPR0402'    | ''          | ''            | '20160802'
 '34K'        | '1%'      | '1/16W'  | '0402LF'  | 'CHIP'   | 'CS33402FB04'(!)        = ''              | ''                 | 'CS33402FB04'           |'R0402'| '(R0402-0201)'                 | '34K'     | '1%'    | '1/16W'  | 'DISCRETE' | 'RES CHIP 34K 1/16W +-1%(0402)DAL_AEC'             | 'CHIPR0402'    | ''          | ''            | '20160802'
 '34K'        | '1%'      | '1/16W'  | '0402LF'  | 'EMPTY'  | 'CS33402FB04'(!)        = ''              | ''                 | 'CS33402FB04'           |'R0402'| '(R0402-0201)'                 | '34K'     | '1%'    | '1/16W'  | 'IO'       | 'RES CHIP 34K 1/16W +-1%(0402)DAL_AEC'             | 'CHIPR0402'    | ''          | ''            | '20160802'
 '34.8K'      | '1%'      | '1/16W'  | '0402LF'  | 'CHIP'   | 'CS33482FB02'(!)        = ''              | ''                 | 'CS33482FB02'           |'R0402'| '(R0402-0201)'                 | '34.8K'   | '1%'    | '1/16W'  | 'DISCRETE' | 'RES CHIP 34.8K 1/16W +-1% (0402)DAL_AEC'          | 'CHIPR0402'    | ''          | ''            | '20160803'
 '34.8K'      | '1%'      | '1/16W'  | '0402LF'  | 'EMPTY'  | 'CS33482FB02'(!)        = ''              | ''                 | 'CS33482FB02'           |'R0402'| '(R0402-0201)'                 | '34.8K'   | '1%'    | '1/16W'  | 'IO'       | 'RES CHIP 34.8K 1/16W +-1% (0402)DAL_AEC'          | 'CHIPR0402'    | ''          | ''            | '20160803'
 '47K'        | '1%'      | '1/16W'  | '0402LF'  | 'CHIP'   | 'CS34702FB04'(!)        = ''              | ''                 | 'CS34702FB04'           |'R0402'| '(R0402-0201)'                 | '47K'     | '1%'    | '1/16W'  | 'DISCRETE' | 'RES CHIP 47K 1/16W +-1%(0402)DAL_AEC'             | 'CHIPR0402'    | ''          | ''            | '20160803'
 '47K'        | '1%'      | '1/16W'  | '0402LF'  | 'EMPTY'  | 'CS34702FB04'(!)        = ''              | ''                 | 'CS34702FB04'           |'R0402'| '(R0402-0201)'                 | '47K'     | '1%'    | '1/16W'  | 'IO'       | 'RES CHIP 47K 1/16W +-1%(0402)DAL_AEC'             | 'CHIPR0402'    | ''          | ''            | '20160803'
 '45.3K'      | '1%'      | '1/16W'  | '0402LF'  | 'CHIP'   | 'CS34532FB06'(!)        = ''              | ''                 | 'CS34532FB06'           |'R0402'| '(R0402-0201)'                 | '45.3K'   | '1%'    | '1/16W'  | 'DISCRETE' | 'RES CHIP 45.3K 1/16W +-1% (0402)DAL_AEC'          | 'CHIPR0402'    | ''          | ''            | '20160803'
 '45.3K'      | '1%'      | '1/16W'  | '0402LF'  | 'EMPTY'  | 'CS34532FB06'(!)        = ''              | ''                 | 'CS34532FB06'           |'R0402'| '(R0402-0201)'                 | '45.3K'   | '1%'    | '1/16W'  | 'IO'       | 'RES CHIP 45.3K 1/16W +-1% (0402)DAL_AEC'          | 'CHIPR0402'    | ''          | ''            | '20160803'
 '64.9K'      | '1%'      | '1/16W'  | '0402LF'  | 'CHIP'   | 'CS36492FB04'(!)        = ''              | ''                 | 'CS36492FB04'           |'R0402'| '(R0402-0201)'                 | '64.9K'   | '1%'    | '1/16W'  | 'DISCRETE' | 'RES CHIP 64.9K 1/16W +1%(0402)DAL_AEC'            | 'CHIPR0402'    | ''          | ''            | '20160803'
 '64.9K'      | '1%'      | '1/16W'  | '0402LF'  | 'EMPTY'  | 'CS36492FB04'(!)        = ''              | ''                 | 'CS36492FB04'           |'R0402'| '(R0402-0201)'                 | '64.9K'   | '1%'    | '1/16W'  | 'IO'       | 'RES CHIP 64.9K 1/16W +1%(0402)DAL_AEC'            | 'CHIPR0402'    | ''          | ''            | '20160803'
 '60.4K'      | '1%'      | '1/16W'  | '0402LF'  | 'CHIP'   | 'CS36042FB05'(!)        = ''              | ''                 | 'CS36042FB05'           |'R0402'| '(R0402-0201)'                 | '60.4K'   | '1%'    | '1/16W'  | 'DISCRETE' | 'RES CHIP 60.4K 1/16W +-1%(0402)DAL_AEC'           | 'CHIPR0402'    | ''          | ''            | '20160803'
 '60.4K'      | '1%'      | '1/16W'  | '0402LF'  | 'EMPTY'  | 'CS36042FB05'(!)        = ''              | ''                 | 'CS36042FB05'           |'R0402'| '(R0402-0201)'                 | '60.4K'   | '1%'    | '1/16W'  | 'IO'       | 'RES CHIP 60.4K 1/16W +-1%(0402)DAL_AEC'           | 'CHIPR0402'    | ''          | ''            | '20160803'
 '53.6K'      | '1%'      | '1/16W'  | '0402LF'  | 'CHIP'   | 'CS35362FB04'(!)        = ''              | ''                 | 'CS35362FB04'           |'R0402'| '(R0402-0201)'                 | '53.6K'   | '1%'    | '1/16W'  | 'DISCRETE' | 'RES CHIP 53.6K 1/16W +1%(0402)DAL_AEC'            | 'CHIPR0402'    | ''          | ''            | '20160803'
 '53.6K'      | '1%'      | '1/16W'  | '0402LF'  | 'EMPTY'  | 'CS35362FB04'(!)        = ''              | ''                 | 'CS35362FB04'           |'R0402'| '(R0402-0201)'                 | '53.6K'   | '1%'    | '1/16W'  | 'IO'       | 'RES CHIP 53.6K 1/16W +1%(0402)DAL_AEC'            | 'CHIPR0402'    | ''          | ''            | '20160803'
 '56.2K'      | '1%'      | '1/16W'  | '0402LF'  | 'CHIP'   | 'CS35622FB04'(!)        = ''              | ''                 | 'CS35622FB04'           |'R0402'| '(R0402-0201)'                 | '56.2K'   | '1%'    | '1/16W'  | 'DISCRETE' | 'RES CHIP 56.2K 1/16W +-1% (0402)DAL_AEC'          | 'CHIPR0402'    | ''          | ''            | '20160803'
 '56.2K'      | '1%'      | '1/16W'  | '0402LF'  | 'EMPTY'  | 'CS35622FB04'(!)        = ''              | ''                 | 'CS35622FB04'           |'R0402'| '(R0402-0201)'                 | '56.2K'   | '1%'    | '1/16W'  | 'IO'       | 'RES CHIP 56.2K 1/16W +-1% (0402)DAL_AEC'          | 'CHIPR0402'    | ''          | ''            | '20160803'
 '49.9K'      | '1%'      | '1/16W'  | '0402LF'  | 'CHIP'   | 'CS34992FB07'(!)        = ''              | ''                 | 'CS34992FB07'           |'R0402'| '(R0402-0201)'                 | '49.9K'   | '1%'    | '1/16W'  | 'DISCRETE' | 'RES CHIP 49.9K 1/16W +-1%(0402)DAL_AEC'           | 'CHIPR0402'    | ''          | ''            | '20160803'
 '49.9K'      | '1%'      | '1/16W'  | '0402LF'  | 'EMPTY'  | 'CS34992FB07'(!)        = ''              | ''                 | 'CS34992FB07'           |'R0402'| '(R0402-0201)'                 | '49.9K'   | '1%'    | '1/16W'  | 'IO'       | 'RES CHIP 49.9K 1/16W +-1%(0402)DAL_AEC'           | 'CHIPR0402'    | ''          | ''            | '20160803'
 '68K'        | '1%'      | '1/16W'  | '0402LF'  | 'CHIP'   | 'CS36802FB03'(!)        = ''              | ''                 | 'CS36802FB03'           |'R0402'| '(R0402-0201)'                 | '68K'     | '1%'    | '1/16W'  | 'DISCRETE' | 'RES CHIP 68K 1/16W +1%(0402)DAL_AEC'              | 'CHIPR0402'    | ''          | ''            | '20160803'
 '68K'        | '1%'      | '1/16W'  | '0402LF'  | 'EMPTY'  | 'CS36802FB03'(!)        = ''              | ''                 | 'CS36802FB03'           |'R0402'| '(R0402-0201)'                 | '68K'     | '1%'    | '1/16W'  | 'IO'       | 'RES CHIP 68K 1/16W +1%(0402)DAL_AEC'              | 'CHIPR0402'    | ''          | ''            | '20160803'
 '66.5K'      | '1%'      | '1/16W'  | '0402LF'  | 'CHIP'   | 'CS36652FB02'(!)        = ''              | ''                 | 'CS36652FB02'           |'R0402'| '(R0402-0201)'                 | '66.5K'   | '1%'    | '1/16W'  | 'DISCRETE' | 'RES CHIP 66.5K 1/16W +-1%(0402)DAL_AEC'           | 'CHIPR0402'    | ''          | ''            | '20160803'
 '66.5K'      | '1%'      | '1/16W'  | '0402LF'  | 'EMPTY'  | 'CS36652FB02'(!)        = ''              | ''                 | 'CS36652FB02'           |'R0402'| '(R0402-0201)'                 | '66.5K'   | '1%'    | '1/16W'  | 'IO'       | 'RES CHIP 66.5K 1/16W +-1%(0402)DAL_AEC'           | 'CHIPR0402'    | ''          | ''            | '20160803'
 '82K'        | '1%'      | '1/16W'  | '0402LF'  | 'CHIP'   | 'CS38202FB00'(!)        = ''              | ''                 | 'CS38202FB00'           |'R0402'| '(R0402-0201)'                 | '82K'     | '1%'    | '1/16W'  | 'DISCRETE' | 'RES CHIP 82K 1/16W +1%(0402)DAL_AEC'              | 'CHIPR0402'    | ''          | ''            | '20160803'
 '82K'        | '1%'      | '1/16W'  | '0402LF'  | 'EMPTY'  | 'CS38202FB00'(!)        = ''              | ''                 | 'CS38202FB00'           |'R0402'| '(R0402-0201)'                 | '82K'     | '1%'    | '1/16W'  | 'IO'       | 'RES CHIP 82K 1/16W +1%(0402)DAL_AEC'              | 'CHIPR0402'    | ''          | ''            | '20160803'
 '86.6K'      | '1%'      | '1/16W'  | '0402LF'  | 'CHIP'   | 'CS38662FB03'(!)        = ''              | ''                 | 'CS38662FB03'           |'R0402'| '(R0402-0201)'                 | '86.6K'   | '1%'    | '1/16W'  | 'DISCRETE' | 'RES CHIP 86.6K 1/16W +-1%(0402)DAL_AEC'           | 'CHIPR0402'    | ''          | ''            | '20160803'
 '86.6K'      | '1%'      | '1/16W'  | '0402LF'  | 'EMPTY'  | 'CS38662FB03'(!)        = ''              | ''                 | 'CS38662FB03'           |'R0402'| '(R0402-0201)'                 | '86.6K'   | '1%'    | '1/16W'  | 'IO'       | 'RES CHIP 86.6K 1/16W +-1%(0402)DAL_AEC'           | 'CHIPR0402'    | ''          | ''            | '20160803'
 '75K'        | '1%'      | '1/16W'  | '0402LF'  | 'CHIP'   | 'CS37502FB06'(!)        = ''              | ''                 | 'CS37502FB06'           |'R0402'| '(R0402-0201)'                 | '75K'     | '1%'    | '1/16W'  | 'DISCRETE' | 'RES CHIP 75K 1/16W +-1%(0402)DAL_AEC'             | 'CHIPR0402'    | ''          | ''            | '20160803'
 '75K'        | '1%'      | '1/16W'  | '0402LF'  | 'EMPTY'  | 'CS37502FB06'(!)        = ''              | ''                 | 'CS37502FB06'           |'R0402'| '(R0402-0201)'                 | '75K'     | '1%'    | '1/16W'  | 'IO'       | 'RES CHIP 75K 1/16W +-1%(0402)DAL_AEC'             | 'CHIPR0402'    | ''          | ''            | '20160803'
 '80.6K'      | '1%'      | '1/16W'  | '0402LF'  | 'CHIP'   | 'CS38062FB07'(!)        = ''              | ''                 | 'CS38062FB07'           |'R0402'| '(R0402-0201)'                 | '80.6K'   | '1%'    | '1/16W'  | 'DISCRETE' | 'RES CHIP 80.6K 1/16W +-1% (0402)DAL_AEC'          | 'CHIPR0402'    | ''          | ''            | '20160803'
 '80.6K'      | '1%'      | '1/16W'  | '0402LF'  | 'EMPTY'  | 'CS38062FB07'(!)        = ''              | ''                 | 'CS38062FB07'           |'R0402'| '(R0402-0201)'                 | '80.6K'   | '1%'    | '1/16W'  | 'IO'       | 'RES CHIP 80.6K 1/16W +-1% (0402)DAL_AEC'          | 'CHIPR0402'    | ''          | ''            | '20160803'
 '69.8K'      | '1%'      | '1/16W'  | '0402LF'  | 'CHIP'   | 'CS36982FB05'(!)        = ''              | ''                 | 'CS36982FB05'           |'R0402'| '(R0402-0201)'                 | '69.8K'   | '1%'    | '1/16W'  | 'DISCRETE' | 'RES CHIP 69.8K 1/16W +-1% (0402)DAL_AEC'          | 'CHIPR0402'    | ''          | ''            | '20160803'
 '69.8K'      | '1%'      | '1/16W'  | '0402LF'  | 'EMPTY'  | 'CS36982FB05'(!)        = ''              | ''                 | 'CS36982FB05'           |'R0402'| '(R0402-0201)'                 | '69.8K'   | '1%'    | '1/16W'  | 'IO'       | 'RES CHIP 69.8K 1/16W +-1% (0402)DAL_AEC'          | 'CHIPR0402'    | ''          | ''            | '20160803'
 '100K'       | '1%'      | '1/16W'  | '0402LF'  | 'CHIP'   | 'CS41002FB17'(!)        = ''              | ''                 | 'CS41002FB17'           |'R0402'| '(R0402-0201)'                 | '100K'    | '1%'    | '1/16W'  | 'DISCRETE' | 'RES CHIP 100K 1/16W +-1%(0402) DAL_AEC'           | 'CHIPR0402'    | ''          | ''            | '20160803'
 '100K'       | '1%'      | '1/16W'  | '0402LF'  | 'EMPTY'  | 'CS41002FB17'(!)        = ''              | ''                 | 'CS41002FB17'           |'R0402'| '(R0402-0201)'                 | '100K'    | '1%'    | '1/16W'  | 'IO'       | 'RES CHIP 100K 1/16W +-1%(0402) DAL_AEC'           | 'CHIPR0402'    | ''          | ''            | '20160803'
 '107K'       | '1%'      | '1/16W'  | '0402LF'  | 'CHIP'   | 'CS41072FB01'(!)        = ''              | ''                 | 'CS41072FB01'           |'R0402'| '(R0402-0201)'                 | '107K'    | '1%'    | '1/16W'  | 'DISCRETE' | 'RES CHIP 107K 1/16W +1%(0402)DAL_AEC'             | 'CHIPR0402'    | ''          | ''            | '20160805'
 '107K'       | '1%'      | '1/16W'  | '0402LF'  | 'EMPTY'  | 'CS41072FB01'(!)        = ''              | ''                 | 'CS41072FB01'           |'R0402'| '(R0402-0201)'                 | '107K'    | '1%'    | '1/16W'  | 'IO'       | 'RES CHIP 107K 1/16W +1%(0402)DAL_AEC'             | 'CHIPR0402'    | ''          | ''            | '20160805'
 '150K'       | '1%'      | '1/16W'  | '0402LF'  | 'CHIP'   | 'CS41502FB06'(!)        = ''              | ''                 | 'CS41502FB06'           |'R0402'| '(R0402-0201)'                 | '150K'    | '1%'    | '1/16W'  | 'DISCRETE' | 'RES CHIP 150K 1/16W +-1%(0402)DAL_AEC'            | 'CHIPR0402'    | ''          | ''            | '20160805'
 '150K'       | '1%'      | '1/16W'  | '0402LF'  | 'EMPTY'  | 'CS41502FB06'(!)        = ''              | ''                 | 'CS41502FB06'           |'R0402'| '(R0402-0201)'                 | '150K'    | '1%'    | '1/16W'  | 'IO'       | 'RES CHIP 150K 1/16W +-1%(0402)DAL_AEC'            | 'CHIPR0402'    | ''          | ''            | '20160805'
 '147K'       | '1%'      | '1/16W'  | '0402LF'  | 'CHIP'   | 'CS41472FB05'(!)        = ''              | ''                 | 'CS41472FB05'           |'R0402'| '(R0402-0201)'                 | '147K'    | '1%'    | '1/16W'  | 'DISCRETE' | 'RES CHIP 147K 1/16W +-1%(0402)DAL_AEC'            | 'CHIPR0402'    | ''          | ''            | '20160805'
 '147K'       | '1%'      | '1/16W'  | '0402LF'  | 'EMPTY'  | 'CS41472FB05'(!)        = ''              | ''                 | 'CS41472FB05'           |'R0402'| '(R0402-0201)'                 | '147K'    | '1%'    | '1/16W'  | 'IO'       | 'RES CHIP 147K 1/16W +-1%(0402)DAL_AEC'            | 'CHIPR0402'    | ''          | ''            | '20160805'
 '143K'       | '1%'      | '1/16W'  | '0402LF'  | 'CHIP'   | 'CS41432FB03'(!)        = ''              | ''                 | 'CS41432FB03'           |'R0402'| '(R0402-0201)'                 | '143K'    | '1%'    | '1/16W'  | 'DISCRETE' | 'RES CHIP 143K 1/16W +-1%(0402)DAL_AEC'            | 'CHIPR0402'    | ''          | ''            | '20160805'
 '143K'       | '1%'      | '1/16W'  | '0402LF'  | 'EMPTY'  | 'CS41432FB03'(!)        = ''              | ''                 | 'CS41432FB03'           |'R0402'| '(R0402-0201)'                 | '143K'    | '1%'    | '1/16W'  | 'IO'       | 'RES CHIP 143K 1/16W +-1%(0402)DAL_AEC'            | 'CHIPR0402'    | ''          | ''            | '20160805'
 '115K'       | '1%'      | '1/16W'  | '0402LF'  | 'CHIP'   | 'CS41152FB02'(!)        = ''              | ''                 | 'CS41152FB02'           |'R0402'| '(R0402-0201)'                 | '115K'    | '1%'    | '1/16W'  | 'DISCRETE' | 'RES CHIP 115K 1/16W +-1%(0402)DAL_AEC'            | 'CHIPR0402'    | ''          | ''            | '20160805'
 '115K'       | '1%'      | '1/16W'  | '0402LF'  | 'EMPTY'  | 'CS41152FB02'(!)        = ''              | ''                 | 'CS41152FB02'           |'R0402'| '(R0402-0201)'                 | '115K'    | '1%'    | '1/16W'  | 'IO'       | 'RES CHIP 115K 1/16W +-1%(0402)DAL_AEC'            | 'CHIPR0402'    | ''          | ''            | '20160805'
 '118K'       | '1%'      | '1/16W'  | '0402LF'  | 'CHIP'   | 'CS41182FB03'(!)        = ''              | ''                 | 'CS41182FB03'           |'R0402'| '(R0402-0201)'                 | '118K'    | '1%'    | '1/16W'  | 'DISCRETE' | 'RES CHIP 118K 1/16W +-1%(0402)DAL_AEC'            | 'CHIPR0402'    | ''          | ''            | '20160805'
 '118K'       | '1%'      | '1/16W'  | '0402LF'  | 'EMPTY'  | 'CS41182FB03'(!)        = ''              | ''                 | 'CS41182FB03'           |'R0402'| '(R0402-0201)'                 | '118K'    | '1%'    | '1/16W'  | 'IO'       | 'RES CHIP 118K 1/16W +-1%(0402)DAL_AEC'            | 'CHIPR0402'    | ''          | ''            | '20160805'
 '120K'       | '1%'      | '1/16W'  | '0402LF'  | 'CHIP'   | 'CS41202FB02'(!)        = ''              | ''                 | 'CS41202FB02'           |'R0402'| '(R0402-0201)'                 | '120K'    | '1%'    | '1/16W'  | 'DISCRETE' | 'RES CHIP 120K 1/16W +-1%( 0402)DAL_AEC'           | 'CHIPR0402'    | ''          | ''            | '20160805'
 '120K'       | '1%'      | '1/16W'  | '0402LF'  | 'EMPTY'  | 'CS41202FB02'(!)        = ''              | ''                 | 'CS41202FB02'           |'R0402'| '(R0402-0201)'                 | '120K'    | '1%'    | '1/16W'  | 'IO'       | 'RES CHIP 120K 1/16W +-1%( 0402)DAL_AEC'           | 'CHIPR0402'    | ''          | ''            | '20160805'
 '133K'       | '1%'      | '1/16W'  | '0402LF'  | 'CHIP'   | 'CS41332FB03'(!)        = ''              | ''                 | 'CS41332FB03'           |'R0402'| '(R0402-0201)'                 | '133K'    | '1%'    | '1/16W'  | 'DISCRETE' | 'RES CHIP 133K 1/16W +-1%(0402)DAL_AEC'            | 'CHIPR0402'    | ''          | ''            | '20160805'
 '133K'       | '1%'      | '1/16W'  | '0402LF'  | 'EMPTY'  | 'CS41332FB03'(!)        = ''              | ''                 | 'CS41332FB03'           |'R0402'| '(R0402-0201)'                 | '133K'    | '1%'    | '1/16W'  | 'IO'       | 'RES CHIP 133K 1/16W +-1%(0402)DAL_AEC'            | 'CHIPR0402'    | ''          | ''            | '20160805'
 '154K'       | '1%'      | '1/16W'  | '0402LF'  | 'CHIP'   | 'CS41542FB07'(!)        = ''              | ''                 | 'CS41542FB07'           |'R0402'| '(R0402-0201)'                 | '154K'    | '1%'    | '1/16W'  | 'DISCRETE' | 'RES CHIP 154K 1/16W +-1%(0402)DAL_AEC'            | 'CHIPR0402'    | ''          | ''            | '20160805'
 '154K'       | '1%'      | '1/16W'  | '0402LF'  | 'EMPTY'  | 'CS41542FB07'(!)        = ''              | ''                 | 'CS41542FB07'           |'R0402'| '(R0402-0201)'                 | '154K'    | '1%'    | '1/16W'  | 'IO'       | 'RES CHIP 154K 1/16W +-1%(0402)DAL_AEC'            | 'CHIPR0402'    | ''          | ''            | '20160805'
 '162K'       | '1%'      | '1/16W'  | '0402LF'  | 'CHIP'   | 'CS41622FB04'(!)        = ''              | ''                 | 'CS41622FB04'           |'R0402'| '(R0402-0201)'                 | '162K'    | '1%'    | '1/16W'  | 'DISCRETE' | 'RES CHIP 162K 1/16W +-1% (0402)DAL_AEC'           | 'CHIPR0402'    | ''          | ''            | '20160805'
 '162K'       | '1%'      | '1/16W'  | '0402LF'  | 'EMPTY'  | 'CS41622FB04'(!)        = ''              | ''                 | 'CS41622FB04'           |'R0402'| '(R0402-0201)'                 | '162K'    | '1%'    | '1/16W'  | 'IO'       | 'RES CHIP 162K 1/16W +-1% (0402)DAL_AEC'           | 'CHIPR0402'    | ''          | ''            | '20160805'
 '200K'       | '1%'      | '1/16W'  | '0402LF'  | 'CHIP'   | 'CS42002FB11'(!)        = ''              | ''                 | 'CS42002FB11'           |'R0402'| '(R0402-0201)'                 | '200K'    | '1%'    | '1/16W'  | 'DISCRETE' | 'RES CHIP 200K 1/16W +-1%(0402)DAL_AEC'            | 'CHIPR0402'    | ''          | ''            | '20160805'
 '200K'       | '1%'      | '1/16W'  | '0402LF'  | 'EMPTY'  | 'CS42002FB11'(!)        = ''              | ''                 | 'CS42002FB11'           |'R0402'| '(R0402-0201)'                 | '200K'    | '1%'    | '1/16W'  | 'IO'       | 'RES CHIP 200K 1/16W +-1%(0402)DAL_AEC'            | 'CHIPR0402'    | ''          | ''            | '20160805'
 '255K'       | '1%'      | '1/16W'  | '0402LF'  | 'CHIP'   | 'CS42552FB04'(!)        = ''              | ''                 | 'CS42552FB04'           |'R0402'| '(R0402-0201)'                 | '255K'    | '1%'    | '1/16W'  | 'DISCRETE' | 'RES CHIP 255K 1/16W +-1%(0402)DAL_AEC'            | 'CHIPR0402'    | ''          | ''            | '20160805'
 '255K'       | '1%'      | '1/16W'  | '0402LF'  | 'EMPTY'  | 'CS42552FB04'(!)        = ''              | ''                 | 'CS42552FB04'           |'R0402'| '(R0402-0201)'                 | '255K'    | '1%'    | '1/16W'  | 'IO'       | 'RES CHIP 255K 1/16W +-1%(0402)DAL_AEC'            | 'CHIPR0402'    | ''          | ''            | '20160805'
 '20M'        | '5%'      | '1/16W'  | '0402LF'  | 'CHIP'   | 'CS62002JB18'(!)        = ''              | ''                 | 'CS62002JB18'           |'R0402'| '(R0402-0201)'                 | '20M'     | '5%'    | '1/16W'  | 'DISCRETE' | 'RES CHIP 20M 1/16W +-5%(0402)'                    | 'CHIPR0402'    | ''          | ''            | '20160808'
 '20M'        | '5%'      | '1/16W'  | '0402LF'  | 'EMPTY'  | 'CS62002JB18'(!)        = ''              | ''                 | 'CS62002JB18'           |'R0402'| '(R0402-0201)'                 | '20M'     | '5%'    | '1/16W'  | 'IO'       | 'RES CHIP 20M 1/16W +-5%(0402)'                    | 'CHIPR0402'    | ''          | ''            | '20160808'
 '24'         | '1%'      | '1/16W'  | '0402LF'  | 'CHIP'   | 'CS02402FB00'(!)        = 'End of Design' | 'Comp-Approve'     | 'CS02402FB00'           |'R0402'| '(R0402-0201)'                 | '24'      | '1%'    | '1/16W'  | 'DISCRETE' | 'RES CHIP 24 1/16W +-1%(0402)DAL_AEC'              | 'CHIPR0402'    | ''          | ''            | '20160808'
 '24'         | '1%'      | '1/16W'  | '0402LF'  | 'EMPTY'  | 'CS02402FB00'(!)        = 'End of Design' | 'Comp-Approve'     | 'CS02402FB00'           |'R0402'| '(R0402-0201)'                 | '24'      | '1%'    | '1/16W'  | 'IO'       | 'RES CHIP 24 1/16W +-1%(0402)DAL_AEC'              | 'CHIPR0402'    | ''          | ''            | '20160808'
 '280K'       | '1%'      | '1/16W'  | '0402LF'  | 'CHIP'   | 'CS42802FB04'(!)        = ''              | ''                 | 'CS42802FB04'           |'R0402'| '(R0402-0201)'                 | '280K'    | '1%'    | '1/16W'  | 'DISCRETE' | 'RES CHIP 280K 1/16W +-1%(0402)DAL_AEC'            | 'CHIPR0402'    | ''          | ''            | '20160809'
 '280K'       | '1%'      | '1/16W'  | '0402LF'  | 'EMPTY'  | 'CS42802FB04'(!)        = ''              | ''                 | 'CS42802FB04'           |'R0402'| '(R0402-0201)'                 | '280K'    | '1%'    | '1/16W'  | 'IO'       | 'RES CHIP 280K 1/16W +-1%(0402)DAL_AEC'            | 'CHIPR0402'    | ''          | ''            | '20160809'
 '348K'       | '1%'      | '1/16W'  | '0402LF'  | 'CHIP'   | 'CS43482FB03'(!)        = ''              | ''                 | 'CS43482FB03'           |'R0402'| '(R0402-0201)'                 | '348K'    | '1%'    | '1/16W'  | 'DISCRETE' | 'RES CHIP 348K 1/16W +-1%( 0402)DAL_AEC'           | 'CHIPR0402'    | ''          | ''            | '20160809'
 '348K'       | '1%'      | '1/16W'  | '0402LF'  | 'EMPTY'  | 'CS43482FB03'(!)        = ''              | ''                 | 'CS43482FB03'           |'R0402'| '(R0402-0201)'                 | '348K'    | '1%'    | '1/16W'  | 'IO'       | 'RES CHIP 348K 1/16W +-1%( 0402)DAL_AEC'           | 'CHIPR0402'    | ''          | ''            | '20160809'
 '475K'       | '1%'      | '1/16W'  | '0402LF'  | 'CHIP'   | 'CS44752FB04'(!)        = ''              | ''                 | 'CS44752FB04'           |'R0402'| '(R0402-0201)'                 | '475K'    | '1%'    | '1/16W'  | 'DISCRETE' | 'RES CHIP 475K 1/16W +-1%(0402)DAL_AEC'            | 'CHIPR0402'    | ''          | ''            | '20160809'
 '475K'       | '1%'      | '1/16W'  | '0402LF'  | 'EMPTY'  | 'CS44752FB04'(!)        = ''              | ''                 | 'CS44752FB04'           |'R0402'| '(R0402-0201)'                 | '475K'    | '1%'    | '1/16W'  | 'IO'       | 'RES CHIP 475K 1/16W +-1%(0402)DAL_AEC'            | 'CHIPR0402'    | ''          | ''            | '20160809'
 '499K'       | '1%'      | '1/16W'  | '0402LF'  | 'CHIP'   | 'CS44992FB02'(!)        = ''              | ''                 | 'CS44992FB02'           |'R0402'| '(R0402-0201)'                 | '499K'    | '1%'    | '1/16W'  | 'DISCRETE' | 'RES CHIP 499K 1/16W +1% (0402)DAL_AEC'            | 'CHIPR0402'    | ''          | ''            | '20160809'
 '499K'       | '1%'      | '1/16W'  | '0402LF'  | 'EMPTY'  | 'CS44992FB02'(!)        = ''              | ''                 | 'CS44992FB02'           |'R0402'| '(R0402-0201)'                 | '499K'    | '1%'    | '1/16W'  | 'IO'       | 'RES CHIP 499K 1/16W +1% (0402)DAL_AEC'            | 'CHIPR0402'    | ''          | ''            | '20160809'
 '681K'       | '1%'      | '1/16W'  | '0402LF'  | 'CHIP'   | 'CS46812FB04'(!)        = ''              | ''                 | 'CS46812FB04'           |'R0402'| '(R0402-0201)'                 | '681K'    | '1%'    | '1/16W'  | 'DISCRETE' | 'RES CHIP 681K 1/16W +-1%(0402)DAL_AEC'            | 'CHIPR0402'    | ''          | ''            | '20160809'
 '681K'       | '1%'      | '1/16W'  | '0402LF'  | 'EMPTY'  | 'CS46812FB04'(!)        = ''              | ''                 | 'CS46812FB04'           |'R0402'| '(R0402-0201)'                 | '681K'    | '1%'    | '1/16W'  | 'IO'       | 'RES CHIP 681K 1/16W +-1%(0402)DAL_AEC'            | 'CHIPR0402'    | ''          | ''            | '20160809'
 '1M'         | '1%'      | '1/16W'  | '0402LF'  | 'CHIP'   | 'CS51002FB07'(!)        = ''              | ''                 | 'CS51002FB07'           |'R0402'| '(R0402-0201)'                 | '1M'      | '1%'    | '1/16W'  | 'DISCRETE' | 'RES CHIP 1M 1/16W +-1%(0402)DAL_AEC'              | 'CHIPR0402'    | ''          | ''            | '20160809'
 '1M'         | '1%'      | '1/16W'  | '0402LF'  | 'EMPTY'  | 'CS51002FB07'(!)        = ''              | ''                 | 'CS51002FB07'           |'R0402'| '(R0402-0201)'                 | '1M'      | '1%'    | '1/16W'  | 'IO'       | 'RES CHIP 1M 1/16W +-1%(0402)DAL_AEC'              | 'CHIPR0402'    | ''          | ''            | '20160809'
 '1.69M'      | '1%'      | '1/16W'  | '0402LF'  | 'CHIP'   | 'CS51692FB02'(!)        = ''              | ''                 | 'CS51692FB02'           |'R0402'| '(R0402-0201)'                 | '1.69M'   | '1%'    | '1/16W'  | 'DISCRETE' | 'RES CHIP 1.69M,1/16W +-1%(0402)DAL_AEC'           | 'CHIPR0402'    | ''          | ''            | '20160809'
 '1.69M'      | '1%'      | '1/16W'  | '0402LF'  | 'EMPTY'  | 'CS51692FB02'(!)        = ''              | ''                 | 'CS51692FB02'           |'R0402'| '(R0402-0201)'                 | '1.69M'   | '1%'    | '1/16W'  | 'IO'       | 'RES CHIP 1.69M,1/16W +-1%(0402)DAL_AEC'           | 'CHIPR0402'    | ''          | ''            | '20160809'
 '10M'        | '1%'      | '1/16W'  | '0402LF'  | 'CHIP'   | 'CS61002FB01'(!)        = ''              | ''                 | 'CS61002FB01'           |'R0402'| '(R0402-0201)'                 | '10M'     | '1%'    | '1/16W'  | 'DISCRETE' | 'RES CHIP 10M 1/16W +-1%(0402)DAL_AEC'             | 'CHIPR0402'    | ''          | ''            | '20160809'
 '10M'        | '1%'      | '1/16W'  | '0402LF'  | 'EMPTY'  | 'CS61002FB01'(!)        = ''              | ''                 | 'CS61002FB01'           |'R0402'| '(R0402-0201)'                 | '10M'     | '1%'    | '1/16W'  | 'IO'       | 'RES CHIP 10M 1/16W +-1%(0402)DAL_AEC'             | 'CHIPR0402'    | ''          | ''            | '20160809'
 '100K'       | '0.1%'    | '1/8W'   | '0805LF'  | 'CHIP'   | 'CS41004BA00'(!)        = ''              | ''                 | 'CS41004BA00'           |'R0805'| '(SMR0805AW)'                  | '100K'    | '0.1%'  | '1/8W'   | 'DISCRETE' | 'RES CHIP 100K 1/8W +-0.1%(0805)AEC'               | 'CHIPR0805'    | ''          | ''            | '20160818'
 '100K'       | '0.1%'    | '1/8W'   | '0805LF'  | 'EMPTY'  | 'CS41004BA00'(!)        = ''              | ''                 | 'CS41004BA00'           |'R0805'| '(SMR0805AW)'                  | '100K'    | '0.1%'  | '1/8W'   | 'IO'       | 'RES CHIP 100K 1/8W +-0.1%(0805)AEC'               | 'CHIPR0805'    | ''          | ''            | '20160818'
 '165K'       | '1%'      | '1/16W'  | '0402LF'  | 'CHIP'   | 'CS41652FB14'(!)        = 'End of Design' | 'Comp-Approve'     | 'CS41652FB14'           |'R0402'| '(R0402-0201)'                 | '165K'    | '1%'    | '1/16W'  | 'DISCRETE' | 'RES CHIP 165K 1/16W +-1%(0402)'                   | 'CHIPR0402'    | ''          | ''            | '20140618'
 '165K'       | '1%'      | '1/16W'  | '0402LF'  | 'EMPTY'  | 'CS41652FB14'(!)        = 'End of Design' | 'Comp-Approve'     | 'CS41652FB14'           |'R0402'| '(R0402-0201)'                 | '165K'    | '1%'    | '1/16W'  | 'IO'       | 'RES CHIP 165K 1/16W +-1%(0402)'                   | 'CHIPR0402'    | ''          | ''            | '20140618'
 '0.0005'     | '1%'      | '1W'     | '2512LF'  | 'CHIP'   | 'CS00008FR04'(!)        = ''              | ''                 | 'CS00008FR04'           |'R2512A'| '(SMR2512AW)'                  | '0.0005'  | '1%'    | '1W'     | 'DISCRETE' | 'RES CHIP 0.0005 1W +-1%(2512)DAL_AEC'             | 'CHIPR2512'    | ''          | ''            | '20160822'
 '0.0005'     | '1%'      | '1W'     | '2512LF'  | 'EMPTY'  | 'CS00008FR04'(!)        = ''              | ''                 | 'CS00008FR04'           |'R2512A'| '(SMR2512AW)'                  | '0.0005'  | '1%'    | '1W'     | 'IO'       | 'RES CHIP 0.0005 1W +-1%(2512)DAL_AEC'             | 'CHIPR2512'    | ''          | ''            | '20160822'
 '0.001'      | '1%'      | '1W'     | '2512LF'  | 'CHIP'   | 'CS+0018FR06'(!)        = ''              | ''                 | 'CS+0018FR06'           |'R2512A'| '(SMR2512AW)'                  | '0.001'   | '1%'    | '1W'     | 'DISCRETE' | 'RES CHIP 0.001 1W +-1%(2512)DAL_AEC'              | 'CHIPR2512'    | ''          | ''            | '20160822'
 '0.001'      | '1%'      | '1W'     | '2512LF'  | 'EMPTY'  | 'CS+0018FR06'(!)        = ''              | ''                 | 'CS+0018FR06'           |'R2512A'| '(SMR2512AW)'                  | '0.001'   | '1%'    | '1W'     | 'IO'       | 'RES CHIP 0.001 1W +-1%(2512)DAL_AEC'              | 'CHIPR2512'    | ''          | ''            | '20160822'
 '0.001'      | '1%'      | '3W'     | '2512LF'  | 'CHIP'   | 'CS+001DFR04'(!)        = ''              | ''                 | 'CS+001DFR04'           |'R2512A'| '(SMR2512AW)'                  | '0.001'   | '1%'    | '3W'     | 'DISCRETE' | 'RES CHIP 0.001 3W +-1%(2512)DAL_AEC'              | 'CHIPR2512'    | ''          | ''            | '20160822'
 '0.001'      | '1%'      | '3W'     | '2512LF'  | 'EMPTY'  | 'CS+001DFR04'(!)        = ''              | ''                 | 'CS+001DFR04'           |'R2512A'| '(SMR2512AW)'                  | '0.001'   | '1%'    | '3W'     | 'IO'       | 'RES CHIP 0.001 3W +-1%(2512)DAL_AEC'              | 'CHIPR2512'    | ''          | ''            | '20160822'
 '1'          | '1%'      | '1W'     | '2512LF'  | 'CHIP'   | 'CS-1008FR01'(!)        = ''              | ''                 | 'CS-1008FR01'           |'R2512XN'| '(SMR2512AW)'                  | '1'       | '1%'    | '1W'     | 'DISCRETE' | 'RES CHIP 1 1W +-1%(2512) DAL_AEC'                 | 'CHIPR2512'    | ''          | ''            | '20160822'
 '1'          | '1%'      | '1W'     | '2512LF'  | 'EMPTY'  | 'CS-1008FR01'(!)        = ''              | ''                 | 'CS-1008FR01'           |'R2512XN'| '(SMR2512AW)'                  | '1'       | '1%'    | '1W'     | 'IO'       | 'RES CHIP 1 1W +-1%(2512) DAL_AEC'                 | 'CHIPR2512'    | ''          | ''            | '20160822'
 '1K'         | '1%'      | '1/16W'  | '0402LF'  | 'CHIP'   | 'SP_CS21002FB24_1'(!)   = 'End of Design' | 'Comp-Approve'     | 'CS21002FB24'           |'R0402_SMDC25_SM30'| '(R0402-0201)'                 | '1K'      | '1%'    | '1/16W'  | 'DISCRETE' | 'RES CHIP 1K 1/16W +-1% (0402)_FOR AMD CIRCLE PAD' | 'CHIPR0402'    | ''          | ''            | '20160824'
 '1K'         | '1%'      | '1/16W'  | '0402LF'  | 'EMPTY'  | 'SP_CS21002FB24_1'(!)   = 'End of Design' | 'Comp-Approve'     | 'CS21002FB24'           |'R0402_SMDC25_SM30'| '(R0402-0201)'                 | '1K'      | '1%'    | '1/16W'  | 'IO'       | 'RES CHIP 1K 1/16W +-1% (0402)_FOR AMD CIRCLE PAD' | 'CHIPR0402'    | ''          | ''            | '20160824'
 '59K'        | '1%'      | '1/16W'  | '0402LF'  | 'CHIP'   | 'CS35902FB11'(!)        = 'End of Design' | 'Comp-Approve'     | 'CS35902FB11'           |'R0402'| '(R0402-0201)'                 | '59K'     | '1%'    | '1/16W'  | 'DISCRETE' | 'RESISTOR CHIP 59K 1/16W +-1%(0402)EP'             | 'CHIPR0402'    | ''          | ''            | '20120710'
 '59K'        | '1%'      | '1/16W'  | '0402LF'  | 'EMPTY'  | 'CS35902FB11'(!)        = 'End of Design' | 'Comp-Approve'     | 'CS35902FB11'           |'R0402'| '(R0402-0201)'                 | '59K'     | '1%'    | '1/16W'  | 'IO'       | 'RESISTOR CHIP 59K 1/16W +-1%(0402)EP'             | 'CHIPR0402'    | ''          | ''            | '20120710'
 '2.2'        | '1%'      | '1/4W'   | '1206LF'  | 'CHIP'   | 'CS-2206F202'(!)        = ''              | ''                 | 'CS-2206F202'           |'R1206XC'| '(SMR1206AW)'                  | '2.2'     | '1%'    | '1/4W'   | 'DISCRETE' | 'RES CHIP 2.2 1/4W +-1%(1206)DAL_AEC'              | 'CHIPR1206'    | ''          | ''            | '20160920'
 '2.2'        | '1%'      | '1/4W'   | '1206LF'  | 'EMPTY'  | 'CS-2206F202'(!)        = ''              | ''                 | 'CS-2206F202'           |'R1206XC'| '(SMR1206AW)'                  | '2.2'     | '1%'    | '1/4W'   | 'IO'       | 'RES CHIP 2.2 1/4W +-1%(1206)DAL_AEC'              | 'CHIPR1206'    | ''          | ''            | '20160920'
 '221'        | '1%'      | '1/16W'  | '0402LF'  | 'CHIP'   | 'CS12212FB05'(!)        = ''              | ''                 | 'CS12212FB05'           |'R0402'| '(R0402-0201)'                 | '221'     | '1%'    | '1/16W'  | 'DISCRETE' | 'RES CHIP 221 1/16W +-1%(0402)DAL_AEC'             | 'CHIPR0402'    | ''          | ''            | '20160929'
 '221'        | '1%'      | '1/16W'  | '0402LF'  | 'EMPTY'  | 'CS12212FB05'(!)        = ''              | ''                 | 'CS12212FB05'           |'R0402'| '(R0402-0201)'                 | '221'     | '1%'    | '1/16W'  | 'IO'       | 'RES CHIP 221 1/16W +-1%(0402)DAL_AEC'             | 'CHIPR0402'    | ''          | ''            | '20160929'
 '0.001'      | '1%'      | '2W'     | '2512LF'  | 'CHIP'   | 'CS+001AFR03'(!)        = ''              | ''                 | 'CS+001AFR03'           |'R2512XG'| '(SMR2512AW)'                  | '0.001'   | '1%'    | '2W'     | 'DISCRETE' | 'RES CHIP 0.001 2W +-1%(2512)'                     | 'CHIPR2512'    | ''          | ''            | '20161007'
 '0.001'      | '1%'      | '2W'     | '2512LF'  | 'EMPTY'  | 'CS+001AFR03'(!)        = ''              | ''                 | 'CS+001AFR03'           |'R2512XG'| '(SMR2512AW)'                  | '0.001'   | '1%'    | '2W'     | 'IO'       | 'RES CHIP 0.001 2W +-1%(2512)'                     | 'CHIPR2512'    | ''          | ''            | '20161007'
 '309K'       | '1%'      | '1/8W'   | '0805LF'  | 'CHIP'   | 'CS43094FA00'(!)        = ''              | ''                 | 'CS43094FA00'           |'R0805'| '(SMR0805AW)'                  | '309K'    | '1%'    | '1/8W'   | 'DISCRETE' | 'RES CHIP 309K 1/8W +-1%(0805)'                    | 'CHIPR0805'    | ''          | ''            | '20161013'
 '309K'       | '1%'      | '1/8W'   | '0805LF'  | 'EMPTY'  | 'CS43094FA00'(!)        = ''              | ''                 | 'CS43094FA00'           |'R0805'| '(SMR0805AW)'                  | '309K'    | '1%'    | '1/8W'   | 'IO'       | 'RES CHIP 309K 1/8W +-1%(0805)'                    | 'CHIPR0805'    | ''          | ''            | '20161013'
 '374K'       | '1%'      | '1/8W'   | '0805LF'  | 'CHIP'   | 'CS43744FA00'(!)        = ''              | ''                 | 'CS43744FA00'           |'R0805'| '(SMR0805AW)'                  | '374K'    | '1%'    | '1/8W'   | 'DISCRETE' | 'RES CHIP 374K 1/8W +-1%(0805)'                    | 'CHIPR0805'    | ''          | ''            | '20161013'
 '374K'       | '1%'      | '1/8W'   | '0805LF'  | 'EMPTY'  | 'CS43744FA00'(!)        = ''              | ''                 | 'CS43744FA00'           |'R0805'| '(SMR0805AW)'                  | '374K'    | '1%'    | '1/8W'   | 'IO'       | 'RES CHIP 374K 1/8W +-1%(0805)'                    | 'CHIPR0805'    | ''          | ''            | '20161013'
 '1.5M'       | '1%'      | '1/16W'  | '0402LF'  | 'CHIP'   | 'CS51502FB02'(!)        = ''              | ''                 | 'CS51502FB02'           |'R0402'| '(R0402-0201)'                 | '1.5M'    | '1%'    | '1/16W'  | 'DISCRETE' | 'RES CHIP 1.5M 1/16W +-1%(0402)DAL_AEC'            | 'CHIPR0402'    | ''          | ''            | '20161017'
 '1.5M'       | '1%'      | '1/16W'  | '0402LF'  | 'EMPTY'  | 'CS51502FB02'(!)        = ''              | ''                 | 'CS51502FB02'           |'R0402'| '(R0402-0201)'                 | '1.5M'    | '1%'    | '1/16W'  | 'IO'       | 'RES CHIP 1.5M 1/16W +-1%(0402)DAL_AEC'            | 'CHIPR0402'    | ''          | ''            | '20161017'
 '562K'       | '1%'      | '1/16W'  | '0402LF'  | 'CHIP'   | 'CS45622FB02'(!)        = ''              | ''                 | 'CS45622FB02'           |'R0402'| '(R0402-0201)'                 | '562K'    | '1%'    | '1/16W'  | 'DISCRETE' | 'RES CHIP 562K 1/16W +-1%(0402)DAL_AEC'            | 'CHIPR0402'    | ''          | ''            | '20161017'
 '562K'       | '1%'      | '1/16W'  | '0402LF'  | 'EMPTY'  | 'CS45622FB02'(!)        = ''              | ''                 | 'CS45622FB02'           |'R0402'| '(R0402-0201)'                 | '562K'    | '1%'    | '1/16W'  | 'IO'       | 'RES CHIP 562K 1/16W +-1%(0402)DAL_AEC'            | 'CHIPR0402'    | ''          | ''            | '20161017'
 '267K'       | '1%'      | '1/16W'  | '0402LF'  | 'CHIP'   | 'CS42672FB02'(!)        = ''              | ''                 | 'CS42672FB02'           |'R0402'| '(R0402-0201)'                 | '267K'    | '1%'    | '1/16W'  | 'DISCRETE' | 'RES CHIP 267K 1/16W +-1%(0402)DAL_AEC'            | 'CHIPR0402'    | ''          | ''            | '20161017'
 '267K'       | '1%'      | '1/16W'  | '0402LF'  | 'EMPTY'  | 'CS42672FB02'(!)        = ''              | ''                 | 'CS42672FB02'           |'R0402'| '(R0402-0201)'                 | '267K'    | '1%'    | '1/16W'  | 'IO'       | 'RES CHIP 267K 1/16W +-1%(0402)DAL_AEC'            | 'CHIPR0402'    | ''          | ''            | '20161017'
 '29.4K'      | '1%'      | '1/16W'  | '0402LF'  | 'CHIP'   | 'CS32942FB04'(!)        = ''              | ''                 | 'CS32942FB04'           |'R0402'| '(R0402-0201)'                 | '29.4K'   | '1%'    | '1/16W'  | 'DISCRETE' | 'RES CHIP 29.4K 1/16W +-1%(0402)DAL_AEC'           | 'CHIPR0402'    | ''          | ''            | '20161017'
 '29.4K'      | '1%'      | '1/16W'  | '0402LF'  | 'EMPTY'  | 'CS32942FB04'(!)        = ''              | ''                 | 'CS32942FB04'           |'R0402'| '(R0402-0201)'                 | '29.4K'   | '1%'    | '1/16W'  | 'IO'       | 'RES CHIP 29.4K 1/16W +-1%(0402)DAL_AEC'           | 'CHIPR0402'    | ''          | ''            | '20161017'
 '3K'         | '1%'      | '1/16W'  | '0402LF'  | 'CHIP'   | 'CS23002FB04'(!)        = ''              | ''                 | 'CS23002FB04'           |'R0402'| '(R0402-0201)'                 | '3K'      | '1%'    | '1/16W'  | 'DISCRETE' | 'RES CHIP 3K 1/16W +-1%(0402)DAL_AEC'              | 'CHIPR0402'    | ''          | ''            | '20161017'
 '3K'         | '1%'      | '1/16W'  | '0402LF'  | 'EMPTY'  | 'CS23002FB04'(!)        = ''              | ''                 | 'CS23002FB04'           |'R0402'| '(R0402-0201)'                 | '3K'      | '1%'    | '1/16W'  | 'IO'       | 'RES CHIP 3K 1/16W +-1%(0402)DAL_AEC'              | 'CHIPR0402'    | ''          | ''            | '20161017'
 '442K'       | '1%'      | '1/16W'  | '0402LF'  | 'CHIP'   | 'CS44422FB00'(!)        = 'End of Design' | 'Comp-Approve'     | 'CS44422FB00'           |'R0402'| '(R0402-0201)'                 | '442K'    | '1%'    | '1/16W'  | 'DISCRETE' | 'RES CHIP 442K 1/16W +-1%(0402)'                   | 'CHIPR0402'    | ''          | ''            | '20161104'
 '442K'       | '1%'      | '1/16W'  | '0402LF'  | 'EMPTY'  | 'CS44422FB00'(!)        = 'End of Design' | 'Comp-Approve'     | 'CS44422FB00'           |'R0402'| '(R0402-0201)'                 | '442K'    | '1%'    | '1/16W'  | 'IO'       | 'RES CHIP 442K 1/16W +-1%(0402)'                   | 'CHIPR0402'    | ''          | ''            | '20161104'
 '182'        | '1%'      | '1/16W'  | '0402LF'  | 'CHIP'   | 'CS11822FB21'(!)        = 'End of Design' | 'Comp-Approve'     | 'CS11822FB21'           |'R0402'| '(R0402-0201)'                 | '182'     | '1%'    | '1/16W'  | 'DISCRETE' | 'RES CHIP 182 1/16W +-1%(0402)'                    | 'CHIPR0402'    | ''          | ''            | '20161110'
 '182'        | '1%'      | '1/16W'  | '0402LF'  | 'EMPTY'  | 'CS11822FB21'(!)        = 'End of Design' | 'Comp-Approve'     | 'CS11822FB21'           |'R0402'| '(R0402-0201)'                 | '182'     | '1%'    | '1/16W'  | 'IO'       | 'RES CHIP 182 1/16W +-1%(0402)'                    | 'CHIPR0402'    | ''          | ''            | '20161110'
 '332'        | '1%'      | '1/16W'  | '0402LF'  | 'CHIP'   | 'CS13322FB01'(!)        = ''              | ''                 | 'CS13322FB01'           |'R0402'| '(R0402-0201)'                 | '332'     | '1%'    | '1/16W'  | 'DISCRETE' | 'RES CHIP 332 1/16W +-1%(0402)'                    | 'CHIPR0402'    | ''          | ''            | '20161114'
 '332'        | '1%'      | '1/16W'  | '0402LF'  | 'EMPTY'  | 'CS13322FB01'(!)        = ''              | ''                 | 'CS13322FB01'           |'R0402'| '(R0402-0201)'                 | '332'     | '1%'    | '1/16W'  | 'IO'       | 'RES CHIP 332 1/16W +-1%(0402)'                    | 'CHIPR0402'    | ''          | ''            | '20161114'
 '0.001'      | '1%'      | '1W'     | '1206LF'  | 'CHIP'   | 'CS+0018F200'(!)        = ''              | ''                 | 'CS+0018F200'           |'R1206XA'| '(SMR1206AW)'                  | '0.001'   | '1%'    | '1W'     | 'DISCRETE' | 'RES CHIP 0.001 1W +-1%(1206)'                     | 'CHIPR1206'    | ''          | ''            | '20161118'
 '0.001'      | '1%'      | '1W'     | '1206LF'  | 'EMPTY'  | 'CS+0018F200'(!)        = ''              | ''                 | 'CS+0018F200'           |'R1206XA'| '(SMR1206AW)'                  | '0.001'   | '1%'    | '1W'     | 'IO'       | 'RES CHIP 0.001 1W +-1%(1206)'                     | 'CHIPR1206'    | ''          | ''            | '20161118'
 '75'         | '1%'      | '1/8W'   | '0402LF'  | 'CHIP'   | 'CS07504FB00'(!)        = ''              | ''                 | 'CS07504FB00'           |'R0402'| '(R0402-0201)'                 | '75'      | '1%'    | '1/8W'   | 'DISCRETE' | 'RES CHIP 75 1/8W +-1%(0402)'                      | 'CHIPR0402'    | ''          | ''            | '20161128'
 '75'         | '1%'      | '1/8W'   | '0402LF'  | 'EMPTY'  | 'CS07504FB00'(!)        = ''              | ''                 | 'CS07504FB00'           |'R0402'| '(R0402-0201)'                 | '75'      | '1%'    | '1/8W'   | 'IO'       | 'RES CHIP 75 1/8W +-1%(0402)'                      | 'CHIPR0402'    | ''          | ''            | '20161128'
 '56.2K'      | '0.1%'    | '1/16W'  | '0402LF'  | 'CHIP'   | 'CS35622BB00'(!)        = ''              | ''                 | 'CS35622BB00'           |'R0402'| '(R0402-0201)'                 | '56.2K'   | '0.1%'  | '1/16W'  | 'DISCRETE' | 'RES CHIP 56.2K 1/16W +-0.1%(0402)'                | 'CHIPR0402'    | ''          | ''            | '20161128'
 '56.2K'      | '0.1%'    | '1/16W'  | '0402LF'  | 'EMPTY'  | 'CS35622BB00'(!)        = ''              | ''                 | 'CS35622BB00'           |'R0402'| '(R0402-0201)'                 | '56.2K'   | '0.1%'  | '1/16W'  | 'IO'       | 'RES CHIP 56.2K 1/16W +-0.1%(0402)'                | 'CHIPR0402'    | ''          | ''            | '20161128'
 '1M'         | '1%'      | '1/4W'   | '1206LF'  | 'CHIP'   | 'CS51006F200'(!)        = ''              | ''                 | 'CS51006F200'           |'R1206XF'| '(SMR1206AW)'                  | '1M'      | '1%'    | '1/4W'   | 'DISCRETE' | 'RES CHIP 1M 1/4W +-1%(1206)'                      | 'CHIPR1206'    | ''          | ''            | '20170207'
 '1M'         | '1%'      | '1/4W'   | '1206LF'  | 'EMPTY'  | 'CS51006F200'(!)        = ''              | ''                 | 'CS51006F200'           |'R1206XF'| '(SMR1206AW)'                  | '1M'      | '1%'    | '1/4W'   | 'IO'       | 'RES CHIP 1M 1/4W +-1%(1206)'                      | 'CHIPR1206'    | ''          | ''            | '20170207'
 '0.01'       | '1%'      | '1/2W'   | '1206LF'  | 'CHIP'   | 'CS+0107F211'(!)        = ''              | ''                 | 'CS+0107F211'           |'R1206XG'| '(SMR1206AW)'                  | '0.01'    | '1%'    | '1/2W'   | 'DISCRETE' | 'RES CHIP 0.01 1/2W +-1%(1206)'                    | 'CHIPR1206'    | ''          | ''            | '20170213'
 '0.01'       | '1%'      | '1/2W'   | '1206LF'  | 'EMPTY'  | 'CS+0107F211'(!)        = ''              | ''                 | 'CS+0107F211'           |'R1206XG'| '(SMR1206AW)'                  | '0.01'    | '1%'    | '1/2W'   | 'IO'       | 'RES CHIP 0.01 1/2W +-1%(1206)'                    | 'CHIPR1206'    | ''          | ''            | '20170213'
 '0.01'       | '1%'      | '1W'     | '3720LF'  | 'CHIP'   | 'CS+0108FL09'(!)        = ''              | ''                 | 'CS+0108FL09'           |'R3720XA'| '(SMR3720AW)'                  | '0.01'    | '1%'    | '1W'     | 'DISCRETE' | 'RESISTOR CHIP 0.01 1W +-1%(3720)'                 | 'CHIP3720'     | ''          | ''            | '20170216'
 '0.01'       | '1%'      | '1W'     | '3720LF'  | 'EMPTY'  | 'CS+0108FL09'(!)        = ''              | ''                 | 'CS+0108FL09'           |'R3720XA'| '(SMR3720AW)'                  | '0.01'    | '1%'    | '1W'     | 'IO'       | 'RESISTOR CHIP 0.01 1W +-1%(3720)'                 | 'CHIP3720'     | ''          | ''            | '20170216'
 '160'        | '5%'      | '1/16W'  | '0402LF'  | 'CHIP'   | 'CS11602JB02'(!)        = 'End of Design' | 'Comp-Approve'     | 'CS11602JB02'           |'R0402'| '(R0402-0201)'                 | '160'     | '5%'    | '1/16W'  | 'DISCRETE' | 'RES CHIP 160 1/16W +-5%(0402)'                    | 'CHIPR0402'    | ''          | ''            | '20170216'
 '160'        | '5%'      | '1/16W'  | '0402LF'  | 'EMPTY'  | 'CS11602JB02'(!)        = 'End of Design' | 'Comp-Approve'     | 'CS11602JB02'           |'R0402'| '(R0402-0201)'                 | '160'     | '5%'    | '1/16W'  | 'IO'       | 'RES CHIP 160 1/16W +-5%(0402)'                    | 'CHIPR0402'    | ''          | ''            | '20170216'
 '16.5'       | '1%'      | '1/16W'  | '0402LF'  | 'CHIP'   | 'CS01652FB00'(!)        = 'End of Design' | 'Comp-Approve'     | 'CS01652FB00'           |'R0402'| '(R0402-0201)'                 | '16.5'    | '1%'    | '1/16W'  | 'DISCRETE' | 'RES CHIP 16.5 1/16W +-1%(0402)'                   | 'CHIPR0402'    | ''          | ''            | '20170412'
 '16.5'       | '1%'      | '1/16W'  | '0402LF'  | 'EMPTY'  | 'CS01652FB00'(!)        = 'End of Design' | 'Comp-Approve'     | 'CS01652FB00'           |'R0402'| '(R0402-0201)'                 | '16.5'    | '1%'    | '1/16W'  | 'IO'       | 'RES CHIP 16.5 1/16W +-1%(0402)'                   | 'CHIPR0402'    | ''          | ''            | '20170412'
 '10'         | '5%'      | '1/16W'  | '0402LF'  | 'CHIP'   | 'CS01002JB06'(!)        = ''              | 'End of Life'      | 'CS01002JB06'           |'R0402_EOL'| '(R0402-0201)'                 | '10'      | '5%'    | '1/16W'  | 'DISCRETE' | 'RES CHIP 10 1/16W +-5%(0402)'                     | 'CHIPR0402'    | ''          | ''            | '20170504'
 '10'         | '5%'      | '1/16W'  | '0402LF'  | 'EMPTY'  | 'CS01002JB06'(!)        = ''              | 'End of Life'      | 'CS01002JB06'           |'R0402_EOL'| '(R0402-0201)'                 | '10'      | '5%'    | '1/16W'  | 'IO'       | 'RES CHIP 10 1/16W +-5%(0402)'                     | 'CHIPR0402'    | ''          | ''            | '20170504'
 '6.34K'      | '1%'      | '1/16W'  | '0402LF'  | 'CHIP'   | 'CS26342FB04'(!)        = ''              | ''                 | 'CS26342FB04'           |'R0402'| '(R0402-0201)'                 | '6.34K'   | '1%'    | '1/16W'  | 'DISCRETE' | 'RES CHIP 6.34K 1/16W +-1%(0402)DAL_AEC'           | 'CHIPR0402'    | ''          | ''            | '20170524'
 '6.34K'      | '1%'      | '1/16W'  | '0402LF'  | 'EMPTY'  | 'CS26342FB04'(!)        = ''              | ''                 | 'CS26342FB04'           |'R0402'| '(R0402-0201)'                 | '6.34K'   | '1%'    | '1/16W'  | 'IO'       | 'RES CHIP 6.34K 1/16W +-1%(0402)DAL_AEC'           | 'CHIPR0402'    | ''          | ''            | '20170524'
 '49.9'       | '1%'      | '1/16W'  | '0402LF'  | 'CHIP'   | 'CS04992FB11'(!)        = ''              | ''                 | 'CS04992FB11'           |'R0402'| '(R0402-0201)'                 | '49.9'    | '1%'    | '1/16W'  | 'DISCRETE' | 'RES CHIP 49.9 1/16W +-1% (0402)DAL_AEC'           | 'CHIPR0402'    | ''          | ''            | '20170524'
 '49.9'       | '1%'      | '1/16W'  | '0402LF'  | 'EMPTY'  | 'CS04992FB11'(!)        = ''              | ''                 | 'CS04992FB11'           |'R0402'| '(R0402-0201)'                 | '49.9'    | '1%'    | '1/16W'  | 'IO'       | 'RES CHIP 49.9 1/16W +-1% (0402)DAL_AEC'           | 'CHIPR0402'    | ''          | ''            | '20170524'
 '0.020'      | '1%'      | '3W'     | '2512LF'  | 'CHIP'   | 'CS+020DFR00'(!)        = ''              | ''                 | 'CS+020DFR00'           |'R2512XL'| '(SMR2512AW)'                  | '0.020'   | '1%'    | '3W'     | 'DISCRETE' | 'RES CHIP 0.020 3W +-1%(2512)'                     | 'CHIPR2512'    | ''          | ''            | '20170524'
 '0.020'      | '1%'      | '3W'     | '2512LF'  | 'EMPTY'  | 'CS+020DFR00'(!)        = ''              | ''                 | 'CS+020DFR00'           |'R2512XL'| '(SMR2512AW)'                  | '0.020'   | '1%'    | '3W'     | 'IO'       | 'RES CHIP 0.020 3W +-1%(2512)'                     | 'CHIPR2512'    | ''          | ''            | '20170524'
 '15'         | '5%'      | '1W'     | '2512LF'  | 'CHIP'   | 'CS01508JR00'(!)        = ''              | ''                 | 'CS01508JR00'           |'R2512XK'| '(SMR2512AW)'                  | '15'      | '5%'    | '1W'     | 'DISCRETE' | 'RES CHIP 15,5%,1W(2512)'                          | 'CHIPR2512'    | ''          | ''            | '20170524'
 '15'         | '5%'      | '1W'     | '2512LF'  | 'EMPTY'  | 'CS01508JR00'(!)        = ''              | ''                 | 'CS01508JR00'           |'R2512XK'| '(SMR2512AW)'                  | '15'      | '5%'    | '1W'     | 'IO'       | 'RES CHIP 15,5%,1W(2512)'                          | 'CHIPR2512'    | ''          | ''            | '20170524'
 '1.3M'       | '1%'      | '1/10W'  | '0603LF'  | 'CHIP'   | 'CS51303F901'(!)        = ''              | ''                 | 'CS51303F901'           |'R0603'| '(SMR0603AW)'                  | '1.3M'    | '1%'    | '1/10W'  | 'DISCRETE' | 'RES CHIP 1.3M 1/10W +-1%(0603)'                   | 'CHIPR0603'    | ''          | ''            | '20170602'
 '1.3M'       | '1%'      | '1/10W'  | '0603LF'  | 'EMPTY'  | 'CS51303F901'(!)        = ''              | ''                 | 'CS51303F901'           |'R0603'| '(SMR0603AW)'                  | '1.3M'    | '1%'    | '1/10W'  | 'IO'       | 'RES CHIP 1.3M 1/10W +-1%(0603)'                   | 'CHIPR0603'    | ''          | ''            | '20170602'
 '0'          | ''        | '1/8W'   | '0805LF'  | 'CHIP'   | 'CS00004TA03'(!)        = ''              | ''                 | 'CS00004TA03'           |'R0805'| '(SMR0805AW)'                  | '0'       | ''      | '1/8W'   | 'DISCRETE' | 'RES CHIP 0 1/8W (0805) DAL_AEC'                   | 'CHIPR0805'    | ''          | ''            | '20170606'
 '0'          | ''        | '1/8W'   | '0805LF'  | 'EMPTY'  | 'CS00004TA03'(!)        = ''              | ''                 | 'CS00004TA03'           |'R0805'| '(SMR0805AW)'                  | '0'       | ''      | '1/8W'   | 'IO'       | 'RES CHIP 0 1/8W (0805) DAL_AEC'                   | 'CHIPR0805'    | ''          | ''            | '20170606'
 '1'          | '1%'      | '1/4W'   | '1206LF'  | 'CHIP'   | 'CS-1006F201'(!)        = ''              | ''                 | 'CS-1006F201'           |'R1206XC'| '(SMRR1206AW)'                 | '1'       | '1%'    | '1/4W'   | 'DISCRETE' | 'RES CHIP 1 1/4W +-1%(1206)DAL_AEC'                | 'CHIPR1206'    | ''          | ''            | '20170606'
 '1'          | '1%'      | '1/4W'   | '1206LF'  | 'EMPTY'  | 'CS-1006F201'(!)        = ''              | ''                 | 'CS-1006F201'           |'R1206XC'| '(SMRR1206AW)'                 | '1'       | '1%'    | '1/4W'   | 'IO'       | 'RES CHIP 1 1/4W +-1%(1206)DAL_AEC'                | 'CHIPR1206'    | ''          | ''            | '20170606'
 '1K'         | '1%'      | '1/8W'   | '0805LF'  | 'CHIP'   | 'CS21004FA03'(!)        = ''              | ''                 | 'CS21004FA03'           |'R0805'| '(SMR0805AW)'                  | '1K'      | '1%'    | '1/8W'   | 'DISCRETE' | 'RES CHIP 1K 1/8W +-1%(0805)DAL_AEC'               | 'CHIPR0805'    | ''          | ''            | '20170606'
 '1K'         | '1%'      | '1/8W'   | '0805LF'  | 'EMPTY'  | 'CS21004FA03'(!)        = ''              | ''                 | 'CS21004FA03'           |'R0805'| '(SMR0805AW)'                  | '1K'      | '1%'    | '1/8W'   | 'IO'       | 'RES CHIP 1K 1/8W +-1%(0805)DAL_AEC'               | 'CHIPR0805'    | ''          | ''            | '20170606'
 '2.2'        | '1%'      | '1/8W'   | '0805LF'  | 'CHIP'   | 'CS-2204FA04'(!)        = ''              | ''                 | 'CS-2204FA04'           |'R0805'| '(SMR0805AW)'                  | '2.2'     | '1%'    | '1/8W'   | 'DISCRETE' | 'RES CHIP 2.2 1/8W +-1%(0805)DAL_AEC'              | 'CHIPR0805'    | ''          | ''            | '20170606'
 '2.2'        | '1%'      | '1/8W'   | '0805LF'  | 'EMPTY'  | 'CS-2204FA04'(!)        = ''              | ''                 | 'CS-2204FA04'           |'R0805'| '(SMR0805AW)'                  | '2.2'     | '1%'    | '1/8W'   | 'IO'       | 'RES CHIP 2.2 1/8W +-1%(0805)DAL_AEC'              | 'CHIPR0805'    | ''          | ''            | '20170606'
 '0.0005'     | '1%'      | '3W'     | '2512LF'  | 'CHIP'   | 'CS0000DFR05'(!)        = ''              | ''                 | 'CS0000DFR05'           |'R2512XO'| '(SMR2512AW)'                  | '0.0005'  | '1%'    | '3W'     | 'DISCRETE' | 'RES CHIP 0.0005 3W +-1%(2512)CYN'                 | 'CHIPR2512'    | ''          | ''            | '20170607'
 '0.0005'     | '1%'      | '3W'     | '2512LF'  | 'EMPTY'  | 'CS0000DFR05'(!)        = ''              | ''                 | 'CS0000DFR05'           |'R2512XO'| '(SMR2512AW)'                  | '0.0005'  | '1%'    | '3W'     | 'IO'       | 'RES CHIP 0.0005 3W +-1%(2512)CYN'                 | 'CHIPR2512'    | ''          | ''            | '20170607'
 '7.5K'       | '1%'      | '1/8W'   | '0805LF'  | 'CHIP'   | 'CS27504FA00'(!)        = ''              | ''                 | 'CS27504FA00'           |'R0805'| '(SMR0805AW)'                  | '7.5K'    | '1%'    | '1/8W'   | 'DISCRETE' | 'RES CHIP 7.5K 1/8W +-1% (0805)'                   | 'CHIPR0805'    | ''          | ''            | '20170706'
 '7.5K'       | '1%'      | '1/8W'   | '0805LF'  | 'EMPTY'  | 'CS27504FA00'(!)        = ''              | ''                 | 'CS27504FA00'           |'R0805'| '(SMR0805AW)'                  | '7.5K'    | '1%'    | '1/8W'   | 'IO'       | 'RES CHIP 7.5K 1/8W +-1% (0805)'                   | 'CHIPR0805'    | ''          | ''            | '20170706'
 '1'          | '5%'      | '1/8W'   | '0805LF'  | 'CHIP'   | 'CS-1004JA37'(!)        = ''              | ''                 | 'CS-1004JA37'           |'R0805'| '(SMR0805AW)'                  | '1'       | '5%'    | '1/8W'   | 'DISCRETE' | 'RES CHIP 1 1/8W+-5%(0805)'                        | 'CHIPR0805'    | ''          | ''            | '20170711'
 '1'          | '5%'      | '1/8W'   | '0805LF'  | 'EMPTY'  | 'CS-1004JA37'(!)        = ''              | ''                 | 'CS-1004JA37'           |'R0805'| '(SMR0805AW)'                  | '1'       | '5%'    | '1/8W'   | 'IO'       | 'RES CHIP 1 1/8W+-5%(0805)'                        | 'CHIPR0805'    | ''          | ''            | '20170711'
 '3.9'        | '5%'      | '1/4W'   | '1206LF'  | 'CHIP'   | 'CS-3906J209'(!)        = ''              | ''                 | 'CS-3906J209'           |'R1206XI'| '(SMRR1206AW)'                 | '3.9'     | '5%'    | '1/4W'   | 'DISCRETE' | 'RES CHIP 3.9 1/4W +-5%(1206)'                     | 'CHIPR1206'    | ''          | ''            | '20170711'
 '3.9'        | '5%'      | '1/4W'   | '1206LF'  | 'EMPTY'  | 'CS-3906J209'(!)        = ''              | ''                 | 'CS-3906J209'           |'R1206XI'| '(SMRR1206AW)'                 | '3.9'     | '5%'    | '1/4W'   | 'IO'       | 'RES CHIP 3.9 1/4W +-5%(1206)'                     | 'CHIPR1206'    | ''          | ''            | '20170711'
 '665'        | '1%'      | '1/8W'   | '0805LF'  | 'CHIP'   | 'CS16654FA08'(!)        = ''              | ''                 | 'CS16654FA08'           |'R0805'| '(SMR0805AW)'                  | '665'     | '1%'    | '1/8W'   | 'DISCRETE' | 'RES CHIP 665 1/8W +-1%(0805)'                     | 'CHIPR0805'    | ''          | ''            | '20170711'
 '665'        | '1%'      | '1/8W'   | '0805LF'  | 'EMPTY'  | 'CS16654FA08'(!)        = ''              | ''                 | 'CS16654FA08'           |'R0805'| '(SMR0805AW)'                  | '665'     | '1%'    | '1/8W'   | 'IO'       | 'RES CHIP 665 1/8W +-1%(0805)'                     | 'CHIPR0805'    | ''          | ''            | '20170711'
 '1'          | '1%'      | '1/16W'  | '0402LF'  | 'CHIP'   | 'CS-1002FB11'(!)        = ''              | ''                 | 'CS-1002FB11'           |'R0402'| '(R0402-0201)'                 | '1'       | '1%'    | '1/16W'  | 'DISCRETE' | 'RES CHIP 1 1/16W +-1%(0402)DAL_AEC'               | 'CHIPR0402'    | ''          | ''            | '20170711'
 '1'          | '1%'      | '1/16W'  | '0402LF'  | 'EMPTY'  | 'CS-1002FB11'(!)        = ''              | ''                 | 'CS-1002FB11'           |'R0402'| '(R0402-0201)'                 | '1'       | '1%'    | '1/16W'  | 'IO'       | 'RES CHIP 1 1/16W +-1%(0402)DAL_AEC'               | 'CHIPR0402'    | ''          | ''            | '20170711'
 '1K'         | '0.1%'    | '1/16W'  | '0402LF'  | 'CHIP'   | 'CS21002BB07'(!)        = ''              | ''                 | 'CS21002BB07'           |'R0402'| '(R0402-0201)'                 | '1K'      | '0.1%'  | '1/16W'  | 'DISCRETE' | 'RES CHIP 1K 1/16W +-0.1%(0402)DAL_AEC'            | 'CHIPR0402'    | ''          | ''            | '20170711'
 '1K'         | '0.1%'    | '1/16W'  | '0402LF'  | 'EMPTY'  | 'CS21002BB07'(!)        = ''              | ''                 | 'CS21002BB07'           |'R0402'| '(R0402-0201)'                 | '1K'      | '0.1%'  | '1/16W'  | 'IO'       | 'RES CHIP 1K 1/16W +-0.1%(0402)DAL_AEC'            | 'CHIPR0402'    | ''          | ''            | '20170711'
 '4.7K'       | '1%'      | '1/16W'  | '0402LF'  | 'CHIP'   | 'CS24702FB07'(!)        = ''              | ''                 | 'CS24702FB07'           |'R0402'| '(R0402-0201)'                 | '4.7K'    | '1%'    | '1/16W'  | 'DISCRETE' | 'RES CHIP 4.7K 1/16W +-1%(0402)DAL_AEC'            | 'CHIPR0402'    | ''          | ''            | '20170712'
 '4.7K'       | '1%'      | '1/16W'  | '0402LF'  | 'EMPTY'  | 'CS24702FB07'(!)        = ''              | ''                 | 'CS24702FB07'           |'R0402'| '(R0402-0201)'                 | '4.7K'    | '1%'    | '1/16W'  | 'IO'       | 'RES CHIP 4.7K 1/16W +-1%(0402)DAL_AEC'            | 'CHIPR0402'    | ''          | ''            | '20170712'
 '20K'        | '0.1%'    | '1/16W'  | '0402LF'  | 'CHIP'   | 'CS32002BB04'(!)        = ''              | ''                 | 'CS32002BB04'           |'R0402'| '(R0402-0201)'                 | '20K'     | '0.1%'  | '1/16W'  | 'DISCRETE' | 'RES CHIP 20K 1/16W +-0.1%(0402)DAL_AEC'           | 'CHIPR0402'    | ''          | ''            | '20170712'
 '20K'        | '0.1%'    | '1/16W'  | '0402LF'  | 'EMPTY'  | 'CS32002BB04'(!)        = ''              | ''                 | 'CS32002BB04'           |'R0402'| '(R0402-0201)'                 | '20K'     | '0.1%'  | '1/16W'  | 'IO'       | 'RES CHIP 20K 1/16W +-0.1%(0402)DAL_AEC'           | 'CHIPR0402'    | ''          | ''            | '20170712'
 '26.7K'      | '0.1%'    | '1/16W'  | '0402LF'  | 'CHIP'   | 'CS32672BB02'(!)        = ''              | ''                 | 'CS32672BB02'           |'R0402'| '(R0402-0201)'                 | '26.7K'   | '0.1%'  | '1/16W'  | 'DISCRETE' | 'RES CHIP 26.7K 1/16W +-0.1%(0402)DAL_AEC'         | 'CHIPR0402'    | ''          | ''            | '20170712'
 '26.7K'      | '0.1%'    | '1/16W'  | '0402LF'  | 'EMPTY'  | 'CS32672BB02'(!)        = ''              | ''                 | 'CS32672BB02'           |'R0402'| '(R0402-0201)'                 | '26.7K'   | '0.1%'  | '1/16W'  | 'IO'       | 'RES CHIP 26.7K 1/16W +-0.1%(0402)DAL_AEC'         | 'CHIPR0402'    | ''          | ''            | '20170712'
 '118K'       | '0.1%'    | '1/16W'  | '0402LF'  | 'CHIP'   | 'CS41182BB01'(!)        = ''              | ''                 | 'CS41182BB01'           |'R0402'| '(R0402-0201)'                 | '118K'    | '0.1%'  | '1/16W'  | 'DISCRETE' | 'RES CHIP 118K 1/16W +-0.1% (0402)DAL_AEC'         | 'CHIPR0402'    | ''          | ''            | '20170712'
 '118K'       | '0.1%'    | '1/16W'  | '0402LF'  | 'EMPTY'  | 'CS41182BB01'(!)        = ''              | ''                 | 'CS41182BB01'           |'R0402'| '(R0402-0201)'                 | '118K'    | '0.1%'  | '1/16W'  | 'IO'       | 'RES CHIP 118K 1/16W +-0.1% (0402)DAL_AEC'         | 'CHIPR0402'    | ''          | ''            | '20170712'
 '133K'       | '0.1%'    | '1/16W'  | '0402LF'  | 'CHIP'   | 'CS41332BB01'(!)        = ''              | ''                 | 'CS41332BB01'           |'R0402'| '(R0402-0201)'                 | '133K'    | '0.1%'  | '1/16W'  | 'DISCRETE' | 'RES CHIP 133K 1/16W +-0.1%(0402)DAL_AEC'          | 'CHIPR0402'    | ''          | ''            | '20170712'
 '133K'       | '0.1%'    | '1/16W'  | '0402LF'  | 'EMPTY'  | 'CS41332BB01'(!)        = ''              | ''                 | 'CS41332BB01'           |'R0402'| '(R0402-0201)'                 | '133K'    | '0.1%'  | '1/16W'  | 'IO'       | 'RES CHIP 133K 1/16W +-0.1%(0402)DAL_AEC'          | 'CHIPR0402'    | ''          | ''            | '20170712'
 '147K'       | '0.1%'    | '1/16W'  | '0402LF'  | 'CHIP'   | 'CS41472BB01'(!)        = 'End of Design' | 'Comp-Release Qty' | 'CS41472BB01'           |'R0402'| '(R0402-0201)'                 | '147K'    | '0.1%'  | '1/16W'  | 'DISCRETE' | 'RES CHIP 147K 1/16W +-0.1% (0402)DAL_AEC'         | 'CHIPR0402'    | ''          | ''            | '20170712'
 '147K'       | '0.1%'    | '1/16W'  | '0402LF'  | 'EMPTY'  | 'CS41472BB01'(!)        = 'End of Design' | 'Comp-Release Qty' | 'CS41472BB01'           |'R0402'| '(R0402-0201)'                 | '147K'    | '0.1%'  | '1/16W'  | 'IO'       | 'RES CHIP 147K 1/16W +-0.1% (0402)DAL_AEC'         | 'CHIPR0402'    | ''          | ''            | '20170712'
 '511K'       | '1%'      | '1/16W'  | '0402LF'  | 'CHIP'   | 'CS45112FB04'(!)        = ''              | ''                 | 'CS45112FB04'           |'R0402'| '(R0402-0201)'                 | '511K'    | '1%'    | '1/16W'  | 'DISCRETE' | 'RES CHIP 511K 1/16W +-1%(0402)DAL_AEC'            | 'CHIPR0402'    | ''          | ''            | '20170712'
 '511K'       | '1%'      | '1/16W'  | '0402LF'  | 'EMPTY'  | 'CS45112FB04'(!)        = ''              | ''                 | 'CS45112FB04'           |'R0402'| '(R0402-0201)'                 | '511K'    | '1%'    | '1/16W'  | 'IO'       | 'RES CHIP 511K 1/16W +-1%(0402)DAL_AEC'            | 'CHIPR0402'    | ''          | ''            | '20170712'
 '26.1K'      | '1%'      | '1/16W'  | '0402LF'  | 'CHIP'   | 'CS32612FB03'(!)        = ''              | ''                 | 'CS32612FB03'           |'R0402'| '(R0402-0201)'                 | '26.1K'   | '1%'    | '1/16W'  | 'DISCRETE' | 'RES CHIP 26.1K 1/16W +-1%(0402)DAL_AEC'           | 'CHIPR0402'    | ''          | ''            | '20170713'
 '26.1K'      | '1%'      | '1/16W'  | '0402LF'  | 'EMPTY'  | 'CS32612FB03'(!)        = ''              | ''                 | 'CS32612FB03'           |'R0402'| '(R0402-0201)'                 | '26.1K'   | '1%'    | '1/16W'  | 'IO'       | 'RES CHIP 26.1K 1/16W +-1%(0402)DAL_AEC'           | 'CHIPR0402'    | ''          | ''            | '20170713'
 '3.74K'      | '1%'      | '1/16W'  | '0402LF'  | 'CHIP'   | 'CS23742FB04'(!)        = ''              | ''                 | 'CS23742FB04'           |'R0402'| '(R0402-0201)'                 | '3.74K'   | '1%'    | '1/16W'  | 'DISCRETE' | 'RES CHIP 3.74K 1/16W +-1%(0402)DAL_AEC'           | 'CHIPR0402'    | ''          | ''            | '20170713'
 '3.74K'      | '1%'      | '1/16W'  | '0402LF'  | 'EMPTY'  | 'CS23742FB04'(!)        = ''              | ''                 | 'CS23742FB04'           |'R0402'| '(R0402-0201)'                 | '3.74K'   | '1%'    | '1/16W'  | 'IO'       | 'RES CHIP 3.74K 1/16W +-1%(0402)DAL_AEC'           | 'CHIPR0402'    | ''          | ''            | '20170713'
 '0'          | ''        | '1/10W'  | '0603LF'  | 'CHIP'   | 'CS00003T901'(!)        = ''              | ''                 | 'CS00003T901'           |'R0603'| '(SMR0603AW)'                  | '0'       | ''      | '1/10W'  | 'DISCRETE' | 'RES CHIP 0 1/10W (0603)DAL_AEC'                   | 'CHIPR0603'    | ''          | ''            | '20170714'
 '0'          | ''        | '1/10W'  | '0603LF'  | 'EMPTY'  | 'CS00003T901'(!)        = ''              | ''                 | 'CS00003T901'           |'R0603'| '(SMR0603AW)'                  | '0'       | ''      | '1/10W'  | 'IO'       | 'RES CHIP 0 1/10W (0603)DAL_AEC'                   | 'CHIPR0603'    | ''          | ''            | '20170714'
 '1'          | '1%'      | '1/10W'  | '0603LF'  | 'CHIP'   | 'CS-1003F902'(!)        = ''              | ''                 | 'CS-1003F902'           |'R0603'| '(SMR0603AW)'                  | '1'       | '1%'    | '1/10W'  | 'DISCRETE' | 'RES CHIP 1 1/10W +-1%(0603)DAL_AEC'               | 'CHIPR0603'    | ''          | ''            | '20170717'
 '1'          | '1%'      | '1/10W'  | '0603LF'  | 'EMPTY'  | 'CS-1003F902'(!)        = ''              | ''                 | 'CS-1003F902'           |'R0603'| '(SMR0603AW)'                  | '1'       | '1%'    | '1/10W'  | 'IO'       | 'RES CHIP 1 1/10W +-1%(0603)DAL_AEC'               | 'CHIPR0603'    | ''          | ''            | '20170717'
 '330'        | '1%'      | '1/10W'  | '0603LF'  | 'CHIP'   | 'CS13303F901'(!)        = ''              | ''                 | 'CS13303F901'           |'R0603'| '(SMR0603AW)'                  | '330'     | '1%'    | '1/10W'  | 'DISCRETE' | 'RES CHIP 330 1/10W +-1%(0603)DAL_AEC'             | 'CHIPR0603'    | ''          | ''            | '20170717'
 '330'        | '1%'      | '1/10W'  | '0603LF'  | 'EMPTY'  | 'CS13303F901'(!)        = ''              | ''                 | 'CS13303F901'           |'R0603'| '(SMR0603AW)'                  | '330'     | '1%'    | '1/10W'  | 'IO'       | 'RES CHIP 330 1/10W +-1%(0603)DAL_AEC'             | 'CHIPR0603'    | ''          | ''            | '20170717'
 '2.2'        | '1%'      | '1/10W'  | '0603LF'  | 'CHIP'   | 'CS-2203F904'(!)        = ''              | ''                 | 'CS-2203F904'           |'R0603'| '(SMR0603AW)'                  | '2.2'     | '1%'    | '1/10W'  | 'DISCRETE' | 'RES CHIP 2.2 1/10W +-1%(0603)DAL_AEC'             | 'CHIPR0603'    | ''          | ''            | '20170717'
 '2.2'        | '1%'      | '1/10W'  | '0603LF'  | 'EMPTY'  | 'CS-2203F904'(!)        = ''              | ''                 | 'CS-2203F904'           |'R0603'| '(SMR0603AW)'                  | '2.2'     | '1%'    | '1/10W'  | 'IO'       | 'RES CHIP 2.2 1/10W +-1%(0603)DAL_AEC'             | 'CHIPR0603'    | ''          | ''            | '20170717'
 '4.7K'       | '1%'      | '1/10W'  | '0603LF'  | 'CHIP'   | 'CS24703F902'(!)        = ''              | ''                 | 'CS24703F902'           |'R0603'| '(SMR0603AW)'                  | '4.7K'    | '1%'    | '1/10W'  | 'DISCRETE' | 'RES CHIP 4.7K 1/10W +-1%(0603)DAL_AEC'            | 'CHIPR0603'    | ''          | ''            | '20170717'
 '4.7K'       | '1%'      | '1/10W'  | '0603LF'  | 'EMPTY'  | 'CS24703F902'(!)        = ''              | ''                 | 'CS24703F902'           |'R0603'| '(SMR0603AW)'                  | '4.7K'    | '1%'    | '1/10W'  | 'IO'       | 'RES CHIP 4.7K 1/10W +-1%(0603)DAL_AEC'            | 'CHIPR0603'    | ''          | ''            | '20170717'
 '10K'        | '1%'      | '1/10W'  | '0603LF'  | 'CHIP'   | 'CS31003F907'(!)        = ''              | ''                 | 'CS31003F907'           |'R0603'| '(SMR0603AW)'                  | '10K'     | '1%'    | '1/10W'  | 'DISCRETE' | 'RES CHIP 10K 1/10W+1%(0603)DAL_AEC'               | 'CHIPR0603'    | ''          | ''            | '20170717'
 '10K'        | '1%'      | '1/10W'  | '0603LF'  | 'EMPTY'  | 'CS31003F907'(!)        = ''              | ''                 | 'CS31003F907'           |'R0603'| '(SMR0603AW)'                  | '10K'     | '1%'    | '1/10W'  | 'IO'       | 'RES CHIP 10K 1/10W+1%(0603)DAL_AEC'               | 'CHIPR0603'    | ''          | ''            | '20170717'
 '100K'       | '1%'      | '1/10W'  | '0603LF'  | 'CHIP'   | 'CS41003F905'(!)        = ''              | ''                 | 'CS41003F905'           |'R0603'| '(SMR0603AW)'                  | '100K'    | '1%'    | '1/10W'  | 'DISCRETE' | 'RES CHIP 100K 1/10W +-1%(0603) DAL_AEC'           | 'CHIPR0603'    | ''          | ''            | '20170717'
 '100K'       | '1%'      | '1/10W'  | '0603LF'  | 'EMPTY'  | 'CS41003F905'(!)        = ''              | ''                 | 'CS41003F905'           |'R0603'| '(SMR0603AW)'                  | '100K'    | '1%'    | '1/10W'  | 'IO'       | 'RES CHIP 100K 1/10W +-1%(0603) DAL_AEC'           | 'CHIPR0603'    | ''          | ''            | '20170717'
 '200K'       | '0.1%'    | '1/10W'  | '0603LF'  | 'CHIP'   | 'CS42003B904'(!)        = 'Non-Preferred' | 'End of Life'      | 'CS42003B904'           |'R0603_EOL'| '(SMR0603AW)'                  | '200K'    | '0.1%'  | '1/10W'  | 'DISCRETE' | 'RES CHIP 200K 1/10W +-0.1%(0603)DAL_AEC'          | 'CHIPR0603'    | ''          | ''            | '20170717'
 '200K'       | '0.1%'    | '1/10W'  | '0603LF'  | 'EMPTY'  | 'CS42003B904'(!)        = 'Non-Preferred' | 'End of Life'      | 'CS42003B904'           |'R0603_EOL'| '(SMR0603AW)'                  | '200K'    | '0.1%'  | '1/10W'  | 'IO'       | 'RES CHIP 200K 1/10W +-0.1%(0603)DAL_AEC'          | 'CHIPR0603'    | ''          | ''            | '20170717'
 '10M'        | '1%'      | '1/10W'  | '0603LF'  | 'CHIP'   | 'CS61003F903'(!)        = ''              | ''                 | 'CS61003F903'           |'R0603'| '(SMR0603AW)'                  | '10M'     | '1%'    | '1/10W'  | 'DISCRETE' | 'RES CHIP 10M 1/10W +-1%(0603)DAL_AEC'             | 'CHIPR0603'    | ''          | ''            | '20170717'
 '10M'        | '1%'      | '1/10W'  | '0603LF'  | 'EMPTY'  | 'CS61003F903'(!)        = ''              | ''                 | 'CS61003F903'           |'R0603'| '(SMR0603AW)'                  | '10M'     | '1%'    | '1/10W'  | 'IO'       | 'RES CHIP 10M 1/10W +-1%(0603)DAL_AEC'             | 'CHIPR0603'    | ''          | ''            | '20170717'
 '2K'         | '1%'      | '1/20W'  | '0201LF'  | 'CHIP'   | 'CS22001FE15'(!)        = ''              | ''                 | 'CS22001FE15'           |'R0201'| '(SMR0201AW)'                  | '2K'      | '1%'    | '1/20W'  | 'DISCRETE' | 'RES CHIP 2K(1/20W,+-1%,0201)'                     | 'CHIPR0201'    | ''          | ''            | '20170718'
 '2K'         | '1%'      | '1/20W'  | '0201LF'  | 'EMPTY'  | 'CS22001FE15'(!)        = ''              | ''                 | 'CS22001FE15'           |'R0201'| '(SMR0201AW)'                  | '2K'      | '1%'    | '1/20W'  | 'IO'       | 'RES CHIP 2K(1/20W,+-1%,0201)'                     | 'CHIPR0201'    | ''          | ''            | '20170718'
 '412K'       | '1%'      | '1/16W'  | '0402LF'  | 'CHIP'   | 'CS44122FB00'(!)        = 'End of Design' | 'Comp-Approve'     | 'CS44122FB00'           |'R0402'| '(R0402-0201)'                 | '412K'    | '1%'    | '1/16W'  | 'DISCRETE' | 'RES CHIP 412K 1/16W +-1%(0402)'                   | 'CHIPR0402'    | ''          | ''            | '20170718'
 '412K'       | '1%'      | '1/16W'  | '0402LF'  | 'EMPTY'  | 'CS44122FB00'(!)        = 'End of Design' | 'Comp-Approve'     | 'CS44122FB00'           |'R0402'| '(R0402-0201)'                 | '412K'    | '1%'    | '1/16W'  | 'IO'       | 'RES CHIP 412K 1/16W +-1%(0402)'                   | 'CHIPR0402'    | ''          | ''            | '20170718'
 '1'          | '1%'      | '1/2W'   | '1206LF'  | 'CHIP'   | 'CS-1007F200'(!)        = ''              | ''                 | 'CS-1007F200'           |'R1206XJ'| '(SMRR1206AW)'                 | '1'       | '1%'    | '1/2W'   | 'DISCRETE' | 'RES CHIP 1 1/2W +-1%(1206)'                       | 'CHIPR1206'    | ''          | ''            | '20170725'
 '1'          | '1%'      | '1/2W'   | '1206LF'  | 'EMPTY'  | 'CS-1007F200'(!)        = ''              | ''                 | 'CS-1007F200'           |'R1206XJ'| '(SMRR1206AW)'                 | '1'       | '1%'    | '1/2W'   | 'IO'       | 'RES CHIP 1 1/2W +-1%(1206)'                       | 'CHIPR1206'    | ''          | ''            | '20170725'
 '10K'        | '5%'      | '1W'     | '2512LF'  | 'CHIP'   | 'CS31008JR00'(!)        = ''              | ''                 | 'CS31008JR00'           |'R2512XP'| '(SMR2512AW)'                  | '10K'     | '5%'    | '1W'     | 'DISCRETE' | 'RES CHIP 10K 1W +-5%(2512)'                       | 'CHIPR2512'    | ''          | ''            | '20170804'
 '10K'        | '5%'      | '1W'     | '2512LF'  | 'EMPTY'  | 'CS31008JR00'(!)        = ''              | ''                 | 'CS31008JR00'           |'R2512XP'| '(SMR2512AW)'                  | '10K'     | '5%'    | '1W'     | 'IO'       | 'RES CHIP 10K 1W +-5%(2512)'                       | 'CHIPR2512'    | ''          | ''            | '20170804'
 '2.2K'       | '5%'      | '1/8W'   | '0805LF'  | 'CHIP'   | 'CS22204JA38'(!)        = ''              | ''                 | 'CS22204JA38'           |'R0805'| '(SMR0805AW)'                  | '2.2K'    | '5%'    | '1/8W'   | 'DISCRETE' | 'RES CHIP 2.2K 1/8W +-5%(0805)'                    | 'CHIPR0805'    | ''          | ''            | '20170809'
 '2.2K'       | '5%'      | '1/8W'   | '0805LF'  | 'EMPTY'  | 'CS22204JA38'(!)        = ''              | ''                 | 'CS22204JA38'           |'R0805'| '(SMR0805AW)'                  | '2.2K'    | '5%'    | '1/8W'   | 'IO'       | 'RES CHIP 2.2K 1/8W +-5%(0805)'                    | 'CHIPR0805'    | ''          | ''            | '20170809'
 '13.3K'      | '1%'      | '1/10W'  | '0603LF'  | 'CHIP'   | 'CS31333F919'(!)        = ''              | ''                 | 'CS31333F919'           |'R0603'| '(SMR0603AW)'                  | '13.3K'   | '1%'    | '1/10W'  | 'DISCRETE' | 'RES CHIP 13.3K 1/10W +-1%(0603)'                  | 'CHIPR0603'    | ''          | ''            | '20170809'
 '13.3K'      | '1%'      | '1/10W'  | '0603LF'  | 'EMPTY'  | 'CS31333F919'(!)        = ''              | ''                 | 'CS31333F919'           |'R0603'| '(SMR0603AW)'                  | '13.3K'   | '1%'    | '1/10W'  | 'IO'       | 'RES CHIP 13.3K 1/10W +-1%(0603)'                  | 'CHIPR0603'    | ''          | ''            | '20170809'
 '0.47'       | '1%'      | '1/8W'   | '0603LF ' | 'CHIP'   | 'CS+4704F901'(!)        = ''              | ''                 | 'CS+4704F901'           |'R0603'| '(SMR0603AW)'                  | '0.47'    | '1%'    | '1/8W'   | 'DISCRETE' | 'RESISTOR CHIP 0.47 1/8W+-1%(0603) EP'             | 'CHIPR0603'    | ''          | ''            | '20170811'
 '0.47'       | '1%'      | '1/8W'   | '0603LF ' | 'EMPTY'  | 'CS+4704F901'(!)        = ''              | ''                 | 'CS+4704F901'           |'R0603'| '(SMR0603AW)'                  | '0.47'    | '1%'    | '1/8W'   | 'IO'       | 'RESISTOR CHIP 0.47 1/8W+-1%(0603) EP'             | 'CHIPR0603'    | ''          | ''            | '20170811'
 '127K'       | '1%'      | '1/10W'  | '0603LF ' | 'CHIP'   | 'CS41273F915'(!)        = ''              | ''                 | 'CS41273F915'           |'R0603'| '(SMR0603AW)'                  | '127K'    | '1%'    | '1/10W'  | 'DISCRETE' | 'RES CHIP 127K 1/10W +-1%(0603)'                   | 'CHIPR0603'    | ''          | ''            | '20170817'
 '127K'       | '1%'      | '1/10W'  | '0603LF ' | 'EMPTY'  | 'CS41273F915'(!)        = ''              | ''                 | 'CS41273F915'           |'R0603'| '(SMR0603AW)'                  | '127K'    | '1%'    | '1/10W'  | 'IO'       | 'RES CHIP 127K 1/10W +-1%(0603)'                   | 'CHIPR0603'    | ''          | ''            | '20170817'
 '0.5'        | '1%'      | '1/2W'   | '1206LF'  | 'CHIP'   | 'CS+5007F200'(!)        = 'End of Design' | 'Comp-Approve'     | 'CS+5007F200'           |'R1206XI'| '(SMRR1206AW)'                 | '0.5'     | '1%'    | '1/2W'   | 'DISCRETE' | 'RES CHIP 0.5 1/2W +-1%(1206)'                     | 'CHIPR1206'    | ''          | ''            | '20170818'
 '0.5'        | '1%'      | '1/2W'   | '1206LF'  | 'EMPTY'  | 'CS+5007F200'(!)        = 'End of Design' | 'Comp-Approve'     | 'CS+5007F200'           |'R1206XI'| '(SMRR1206AW)'                 | '0.5'     | '1%'    | '1/2W'   | 'IO'       | 'RES CHIP 0.5 1/2W +-1%(1206)'                     | 'CHIPR1206'    | ''          | ''            | '20170818'
 '52.3K'      | '1%'      | '1/8W'   | '0805LF'  | 'CHIP'   | 'CS35234FA00'(!)        = ''              | ''                 | 'CS35234FA00'           |'R0805'| '(SMR0805AW)'                  | '52.3K'   | '1%'    | '1/8W'   | 'DISCRETE' | 'RES CHIP 52.3K 1/8W +-1%(0805)'                   | 'CHIPR0805'    | ''          | ''            | '20170821'
 '52.3K'      | '1%'      | '1/8W'   | '0805LF'  | 'EMPTY'  | 'CS35234FA00'(!)        = ''              | ''                 | 'CS35234FA00'           |'R0805'| '(SMR0805AW)'                  | '52.3K'   | '1%'    | '1/8W'   | 'IO'       | 'RES CHIP 52.3K 1/8W +-1%(0805)'                   | 'CHIPR0805'    | ''          | ''            | '20170821'
 '0.003'      | '1%'      | '2W'     | '2512LF'  | 'CHIP'   | 'CS+003AFR00'(!)        = ''              | ''                 | 'CS+003AFR00'           |'R2512XM'| '(SMR2512AW)'                  | '0.003'   | '1%'    | '2W'     | 'DISCRETE' | 'RES CHIP 0.003 2W +-1%(2512)'                     | 'CHIPR2512'    | ''          | ''            | '20170822'
 '0.003'      | '1%'      | '2W'     | '2512LF'  | 'EMPTY'  | 'CS+003AFR00'(!)        = ''              | ''                 | 'CS+003AFR00'           |'R2512XM'| '(SMR2512AW)'                  | '0.003'   | '1%'    | '2W'     | 'IO'       | 'RES CHIP 0.003 2W +-1%(2512)'                     | 'CHIPR2512'    | ''          | ''            | '20170822'
 '0.004'      | '1%'      | '2W'     | '2512LF'  | 'CHIP'   | 'CS+004AFR00'(!)        = ''              | ''                 | 'CS+004AFR00'           |'R2512XM'| '(SMR2512AW)'                  | '0.004'   | '1%'    | '2W'     | 'DISCRETE' | 'RES CHIP 0.004 2W +-1%(2512)'                     | 'CHIPR2512'    | ''          | ''            | '20170823'
 '0.004'      | '1%'      | '2W'     | '2512LF'  | 'EMPTY'  | 'CS+004AFR00'(!)        = ''              | ''                 | 'CS+004AFR00'           |'R2512XM'| '(SMR2512AW)'                  | '0.004'   | '1%'    | '2W'     | 'IO'       | 'RES CHIP 0.004 2W +-1%(2512)'                     | 'CHIPR2512'    | ''          | ''            | '20170823'
 '178K'       | '1%'      | '1/16W'  | '0402LF'  | 'CHIP'   | 'CS41782FB11'(!)        = 'End of Design' | 'Comp-Approve'     | 'CS41782FB11'           |'R0402'| '(R0402-0201)'                 | '178K'    | '1%'    | '1/16W'  | 'DISCRETE' | 'RES CHIP 178K 1/16W +-1%(0402)'                   | 'CHIP0402'     | ''          | ''            | '20170824'
 '178K'       | '1%'      | '1/16W'  | '0402LF'  | 'EMPTY'  | 'CS41782FB11'(!)        = 'End of Design' | 'Comp-Approve'     | 'CS41782FB11'           |'R0402'| '(R0402-0201)'                 | '178K'    | '1%'    | '1/16W'  | 'IO'       | 'RES CHIP 178K 1/16W +-1%(0402)'                   | 'CHIP0402'     | ''          | ''            | '20170824'
 '4.99'       | '0.1%'    | '2W'     | '2512LF'  | 'CHIP'   | 'CS-499ABR00'(!)        = 'Non-Preferred' | 'End of Life'      | 'CS-499ABR00'           |'R2512XQ_EOL'| '(SMR2512AW)'                  | '4.99'    | '0.1%'  | '2W'     | 'DISCRETE' | 'RES CHIP 4.99 2W  +-0.1%(2512)'                   | 'CHIPR2512'    | ''          | ''            | '20170830'
 '4.99'       | '0.1%'    | '2W'     | '2512LF'  | 'EMPTY'  | 'CS-499ABR00'(!)        = 'Non-Preferred' | 'End of Life'      | 'CS-499ABR00'           |'R2512XQ_EOL'| '(SMR2512AW)'                  | '4.99'    | '0.1%'  | '2W'     | 'IO'       | 'RES CHIP 4.99 2W  +-0.1%(2512)'                   | 'CHIPR2512'    | ''          | ''            | '20170830'
 '1'          | '1%'      | '2W'     | '2512LF'  | 'CHIP'   | 'CS-100AFR00'(!)        = ''              | ''                 | 'CS-100AFR00'           |'R2512XQ'| '(SMR2512AW)'                  | '1'       | '1%'    | '2W'     | 'DISCRETE' | 'RES CHIP 1  2W +-1%(2512)'                        | 'CHIPR2512'    | ''          | ''            | '20170830'
 '1'          | '1%'      | '2W'     | '2512LF'  | 'EMPTY'  | 'CS-100AFR00'(!)        = ''              | ''                 | 'CS-100AFR00'           |'R2512XQ'| '(SMR2512AW)'                  | '1'       | '1%'    | '2W'     | 'IO'       | 'RES CHIP 1  2W +-1%(2512)'                        | 'CHIPR2512'    | ''          | ''            | '20170830'
 '2.2'        | '5%'      | '2W'     | '2512LF'  | 'CHIP'   | 'CS-220AJR00'(!)        = ''              | ''                 | 'CS-220AJR00'           |'R2512XQ'| '(SMR2512AW)'                  | '2.2'     | '5%'    | '2W'     | 'DISCRETE' | 'RES CHIP 2.2 2W  +-5%(2512)'                      | 'CHIPR2512'    | ''          | ''            | '20170830'
 '2.2'        | '5%'      | '2W'     | '2512LF'  | 'EMPTY'  | 'CS-220AJR00'(!)        = ''              | ''                 | 'CS-220AJR00'           |'R2512XQ'| '(SMR2512AW)'                  | '2.2'     | '5%'    | '2W'     | 'IO'       | 'RES CHIP 2.2 2W  +-5%(2512)'                      | 'CHIPR2512'    | ''          | ''            | '20170830'
 '750K'       | '1%'      | '1/16W'  | '0402LF'  | 'CHIP'   | 'CS47502FB06'(!)        = ''              | ''                 | 'CS47502FB06'           |'R0402'| '(R0402-0201)'                 | '750K'    | '1%'    | '1/16W'  | 'DISCRETE' | 'RES CHIP 750K 1/16W +-1%(0402)'                   | 'CHIPR0402'    | ''          | ''            | '20170904'
 '750K'       | '1%'      | '1/16W'  | '0402LF'  | 'EMPTY'  | 'CS47502FB06'(!)        = ''              | ''                 | 'CS47502FB06'           |'R0402'| '(R0402-0201)'                 | '750K'    | '1%'    | '1/16W'  | 'IO'       | 'RES CHIP 750K 1/16W +-1%(0402)'                   | 'CHIPR0402'    | ''          | ''            | '20170904'
 '523K'       | '1%'      | '1/16W'  | '0402LF'  | 'CHIP'   | 'CS45232FB00'(!)        = 'End of Design' | 'Comp-Approve'     | 'CS45232FB00'           |'R0402'| '(R0402-0201)'                 | '523K'    | '1%'    | '1/16W'  | 'DISCRETE' | 'RES CHIP 523K 1/16W +-1%(0402)'                   | 'CHIPR0402'    | ''          | ''            | '20170907'
 '523K'       | '1%'      | '1/16W'  | '0402LF'  | 'EMPTY'  | 'CS45232FB00'(!)        = 'End of Design' | 'Comp-Approve'     | 'CS45232FB00'           |'R0402'| '(R0402-0201)'                 | '523K'    | '1%'    | '1/16W'  | 'IO'       | 'RES CHIP 523K 1/16W +-1%(0402)'                   | 'CHIPR0402'    | ''          | ''            | '20170907'
 '887K'       | '1%'      | '1/16W'  | '0402LF'  | 'CHIP'   | 'CS48872FB10'(!)        = 'End of Design' | 'Comp-Approve'     | 'CS48872FB10'           |'R0402'| '(R0402-0201)'                 | '887K'    | '1%'    | '1/16W'  | 'DISCRETE' | 'RES CHIP 887K 1/16W +-1%(0402)'                   | 'CHIPR0402'    | ''          | ''            | '20170907'
 '887K'       | '1%'      | '1/16W'  | '0402LF'  | 'EMPTY'  | 'CS48872FB10'(!)        = 'End of Design' | 'Comp-Approve'     | 'CS48872FB10'           |'R0402'| '(R0402-0201)'                 | '887K'    | '1%'    | '1/16W'  | 'IO'       | 'RES CHIP 887K 1/16W +-1%(0402)'                   | 'CHIPR0402'    | ''          | ''            | '20170907'
 '280'        | '1%'      | '1/16W'  | '0402LF'  | 'CHIP'   | 'CS12802FB00'(!)        = 'End of Design' | 'Comp-Approve'     | 'CS12802FB00'           |'R0402'| '(R0402-0201)'                 | '280'     | '1%'    | '1/16W'  | 'DISCRETE' | 'RES CHIP 280 1/16W +-1%(0402)'                    | 'CHIPR0402'    | ''          | ''            | '20170922'
 '280'        | '1%'      | '1/16W'  | '0402LF'  | 'EMPTY'  | 'CS12802FB00'(!)        = 'End of Design' | 'Comp-Approve'     | 'CS12802FB00'           |'R0402'| '(R0402-0201)'                 | '280'     | '1%'    | '1/16W'  | 'IO'       | 'RES CHIP 280 1/16W +-1%(0402)'                    | 'CHIPR0402'    | ''          | ''            | '20170922'
 '280'        | '1%'      | '1/16W'  | '0402LF'  | 'CHIP'   | 'CS12802FB08'(!)        = ''              | ''                 | 'CS12802FB08'           |'R0402'| '(R0402-0201)'                 | '280'     | '1%'    | '1/16W'  | 'DISCRETE' | 'RES CHIP 280 1/16W +-1% (0402)'                   | 'CHIPR0402'    | ''          | ''            | '20170922'
 '280'        | '1%'      | '1/16W'  | '0402LF'  | 'EMPTY'  | 'CS12802FB08'(!)        = ''              | ''                 | 'CS12802FB08'           |'R0402'| '(R0402-0201)'                 | '280'     | '1%'    | '1/16W'  | 'IO'       | 'RES CHIP 280 1/16W +-1% (0402)'                   | 'CHIPR0402'    | ''          | ''            | '20170922'
 '464'        | '1%'      | '1/16W'  | '0402LF'  | 'CHIP'   | 'CS14642FB04'(!)        = ''              | ''                 | 'CS14642FB04'           |'R0402'| '(R0402-0201)'                 | '464'     | '1%'    | '1/16W'  | 'DISCRETE' | 'RES CHIP 464 1/16W +-1%(0402)'                    | 'CHIPR0402'    | ''          | ''            | '20170922'
 '464'        | '1%'      | '1/16W'  | '0402LF'  | 'EMPTY'  | 'CS14642FB04'(!)        = ''              | ''                 | 'CS14642FB04'           |'R0402'| '(R0402-0201)'                 | '464'     | '1%'    | '1/16W'  | 'IO'       | 'RES CHIP 464 1/16W +-1%(0402)'                    | 'CHIPR0402'    | ''          | ''            | '20170922'
 '464'        | '1%'      | '1/16W'  | '0402LF'  | 'CHIP'   | 'CS14642FB12'(!)        = 'End of Design' | 'Comp-Approve'     | 'CS14642FB12'           |'R0402'| '(R0402-0201)'                 | '464'     | '1%'    | '1/16W'  | 'DISCRETE' | 'RES CHIP 464 1/16W +-1%(0402)'                    | 'CHIPR0402'    | ''          | ''            | '20170922'
 '464'        | '1%'      | '1/16W'  | '0402LF'  | 'EMPTY'  | 'CS14642FB12'(!)        = 'End of Design' | 'Comp-Approve'     | 'CS14642FB12'           |'R0402'| '(R0402-0201)'                 | '464'     | '1%'    | '1/16W'  | 'IO'       | 'RES CHIP 464 1/16W +-1%(0402)'                    | 'CHIPR0402'    | ''          | ''            | '20170922'
 '2.05K'      | '1%'      | '1/16W'  | '0402LF'  | 'CHIP'   | 'CS22052FB03'(!)        = ''              | ''                 | 'CS22052FB03'           |'R0402'| '(R0402-0201)'                 | '2.05K'   | '1%'    | '1/16W'  | 'DISCRETE' | 'RES CHIP 2.05K 1/16W +-1%(0402)'                  | 'CHIPR0402'    | ''          | ''            | '20170922'
 '2.05K'      | '1%'      | '1/16W'  | '0402LF'  | 'EMPTY'  | 'CS22052FB03'(!)        = ''              | ''                 | 'CS22052FB03'           |'R0402'| '(R0402-0201)'                 | '2.05K'   | '1%'    | '1/16W'  | 'IO'       | 'RES CHIP 2.05K 1/16W +-1%(0402)'                  | 'CHIPR0402'    | ''          | ''            | '20170922'
 '2.05K'      | '1%'      | '1/16W'  | '0402LF'  | 'CHIP'   | 'CS22052FB11'(!)        = 'End of Design' | 'Comp-Approve'     | 'CS22052FB11'           |'R0402'| '(R0402-0201)'                 | '2.05K'   | '1%'    | '1/16W'  | 'DISCRETE' | 'RES CHIP 2.05K 1/16W +-1%(0402)'                  | 'CHIPR0402'    | ''          | ''            | '20170922'
 '2.05K'      | '1%'      | '1/16W'  | '0402LF'  | 'EMPTY'  | 'CS22052FB11'(!)        = 'End of Design' | 'Comp-Approve'     | 'CS22052FB11'           |'R0402'| '(R0402-0201)'                 | '2.05K'   | '1%'    | '1/16W'  | 'IO'       | 'RES CHIP 2.05K 1/16W +-1%(0402)'                  | 'CHIPR0402'    | ''          | ''            | '20170922'
 '750K'       | '1%'      | '1/16W'  | '0402LF'  | 'CHIP'   | 'CS47502FB14'(!)        = 'End of Design' | 'Comp-Approve'     | 'CS47502FB14'           |'R0402'| '(R0402-0201)'                 | '750K'    | '1%'    | '1/16W'  | 'DISCRETE' | 'RES CHIP 750K 1/16W +-1%(0402)'                   | 'CHIPR0402'    | ''          | ''            | '20170925'
 '750K'       | '1%'      | '1/16W'  | '0402LF'  | 'EMPTY'  | 'CS47502FB14'(!)        = 'End of Design' | 'Comp-Approve'     | 'CS47502FB14'           |'R0402'| '(R0402-0201)'                 | '750K'    | '1%'    | '1/16W'  | 'IO'       | 'RES CHIP 750K 1/16W +-1%(0402)'                   | 'CHIPR0402'    | ''          | ''            | '20170925'
 '0.51'       | '1%'      | '1/3W'   | '0805LF'  | 'CHIP'   | 'CS+510CFA00'(!)        = ''              | ''                 | 'CS+510CFA00'           |'R0805'| '(SMR0805AW)'                  | '0.51'    | '1%'    | '1/3W'   | 'DISCRETE' | 'RES CHIP 0.51 1/3W +-1%(0805) YGO_AEC'            | 'CHIPR0805'    | ''          | ''            | '20171006'
 '0.51'       | '1%'      | '1/3W'   | '0805LF'  | 'EMPTY'  | 'CS+510CFA00'(!)        = ''              | ''                 | 'CS+510CFA00'           |'R0805'| '(SMR0805AW)'                  | '0.51'    | '1%'    | '1/3W'   | 'IO'       | 'RES CHIP 0.51 1/3W +-1%(0805) YGO_AEC'            | 'CHIPR0805'    | ''          | ''            | '20171006'
 '47.5'       | '1%'      | '1/16W'  | '0402LF'  | 'CHIP'   | 'CS04752FB19'(!)        = 'End of Design' | 'Comp-Approve'     | 'CS04752FB19'           |'R0402'| '(R0402-0201)'                 | '47.5'    | '1%'    | '1/16W'  | 'DISCRETE' | 'RES CHIP 47.5 1/16W +-1%(0402)'                   | 'CHIPR0402'    | ''          | ''            | '20171018'
 '47.5'       | '1%'      | '1/16W'  | '0402LF'  | 'EMPTY'  | 'CS04752FB19'(!)        = 'End of Design' | 'Comp-Approve'     | 'CS04752FB19'           |'R0402'| '(R0402-0201)'                 | '47.5'    | '1%'    | '1/16W'  | 'IO'       | 'RES CHIP 47.5 1/16W +-1%(0402)'                   | 'CHIPR0402'    | ''          | ''            | '20171018'
 '162'        | '1%'      | '1/20W'  | '0201LF'  | 'CHIP'   | 'CS11621FE00'(!)        = ''              | ''                 | 'CS11621FE00'           |'R0201'| '(SMR0201AW)'                  | '162'     | '1%'    | '1/20W'  | 'DISCRETE' | 'RES CHIP 162 1/20W +-1%(0201)'                    | 'CHIPR0201'    | ''          | ''            | '20171024'
 '162'        | '1%'      | '1/20W'  | '0201LF'  | 'EMPTY'  | 'CS11621FE00'(!)        = ''              | ''                 | 'CS11621FE00'           |'R0201'| '(SMR0201AW)'                  | '162'     | '1%'    | '1/20W'  | 'IO'       | 'RES CHIP 162 1/20W +-1%(0201)'                    | 'CHIPR0201'    | ''          | ''            | '20171024'
 '80.6'       | '1%'      | '1/20W'  | '0201LF'  | 'CHIP'   | 'CS08061FE00'(!)        = ''              | ''                 | 'CS08061FE00'           |'R0201'| '(SMR0201AW)'                  | '80.6'    | '1%'    | '1/20W'  | 'DISCRETE' | 'RES CHIP 80.6  1/20W +-1%(0201)'                  | 'CHIPR0201'    | ''          | ''            | '20171025'
 '80.6'       | '1%'      | '1/20W'  | '0201LF'  | 'EMPTY'  | 'CS08061FE00'(!)        = ''              | ''                 | 'CS08061FE00'           |'R0201'| '(SMR0201AW)'                  | '80.6'    | '1%'    | '1/20W'  | 'IO'       | 'RES CHIP 80.6  1/20W +-1%(0201)'                  | 'CHIPR0201'    | ''          | ''            | '20171025'
 '845K'       | '1%'      | '1/8W'   | '0805LF'  | 'CHIP'   | 'CS48454FA00'(!)        = ''              | ''                 | 'CS48454FA00'           |'R0805'| '(SMR0805AW)'                  | '845K'    | '1%'    | '1/8W'   | 'DISCRETE' | 'RES CHIP 845K 1/8W +-1%(0805)'                    | 'CHIPR0805'    | ''          | ''            | '20171026'
 '845K'       | '1%'      | '1/8W'   | '0805LF'  | 'EMPTY'  | 'CS48454FA00'(!)        = ''              | ''                 | 'CS48454FA00'           |'R0805'| '(SMR0805AW)'                  | '845K'    | '1%'    | '1/8W'   | 'IO'       | 'RES CHIP 845K 1/8W +-1%(0805)'                    | 'CHIPR0805'    | ''          | ''            | '20171026'
 '10'         | '1%'      | '2W'     | '2512LF'  | 'CHIP'   | 'CS0100AFR00'(!)        = ''              | ''                 | 'CS0100AFR00'           |'R2512XR'| '(SMR2512AW)'                  | '10'      | '1%'    | '2W'     | 'DISCRETE' | 'RES CHIP 10 2W +-1%(2512)'                        | 'CHIP2512'     | ''          | ''            | '20171030'
 '10'         | '1%'      | '2W'     | '2512LF'  | 'EMPTY'  | 'CS0100AFR00'(!)        = ''              | ''                 | 'CS0100AFR00'           |'R2512XR'| '(SMR2512AW)'                  | '10'      | '1%'    | '2W'     | 'IO'       | 'RES CHIP 10 2W +-1%(2512)'                        | 'CHIP2512'     | ''          | ''            | '20171030'
 '73.2'       | '1%'      | '1/2W'   | '1210LF'  | 'CHIP'   | 'CS07327F305'(!)        = ''              | ''                 | 'CS07327F305'           |'R1210XA'| '(SMR1210AW)'                  | '73.2'    | '1%'    | '1/2W'   | 'DISCRETE' | 'RES CHIP 73.2 1/2W +-1%(1210)'                    | 'CHIPR1210'    | ''          | ''            | '20171113'
 '73.2'       | '1%'      | '1/2W'   | '1210LF'  | 'EMPTY'  | 'CS07327F305'(!)        = ''              | ''                 | 'CS07327F305'           |'R1210XA'| '(SMR1210AW)'                  | '73.2'    | '1%'    | '1/2W'   | 'IO'       | 'RES CHIP 73.2 1/2W +-1%(1210)'                    | 'CHIPR1210'    | ''          | ''            | '20171113'
 '3.9'        | '1%'      | '1/16W'  | '0402LF'  | 'CHIP'   | 'CS-3902FB05'(!)        = ''              | ''                 | 'CS-3902FB05'           |'R0402'| '(R0402-0201)'                 | '3.9'     | '1%'    | '1/16W'  | 'DISCRETE' | 'RES CHIP 3.9 1/16W +-1% (0402)'                   | 'CHIPR0402'    | ''          | ''            | '20171127'
 '3.9'        | '1%'      | '1/16W'  | '0402LF'  | 'EMPTY'  | 'CS-3902FB05'(!)        = ''              | ''                 | 'CS-3902FB05'           |'R0402'| '(R0402-0201)'                 | '3.9'     | '1%'    | '1/16W'  | 'IO'       | 'RES CHIP 3.9 1/16W +-1% (0402)'                   | 'CHIPR0402'    | ''          | ''            | '20171127'
 '6.49K'      | '1%'      | '1/10W'  | '0603LF'  | 'CHIP'   | 'CS26493F911'(!)        = ''              | ''                 | 'CS26493F911'           |'R0603'| '(SMR0603AW)'                  | '6.49K'   | '1%'    | '1/10W'  | 'DISCRETE' | 'RES CHIP 6.49K 1/10W +-1%(0603)'                  | 'CHIPR0603'    | ''          | ''            | '20171130'
 '6.49K'      | '1%'      | '1/10W'  | '0603LF'  | 'EMPTY'  | 'CS26493F911'(!)        = ''              | ''                 | 'CS26493F911'           |'R0603'| '(SMR0603AW)'                  | '6.49K'   | '1%'    | '1/10W'  | 'IO'       | 'RES CHIP 6.49K 1/10W +-1%(0603)'                  | 'CHIPR0603'    | ''          | ''            | '20171130'
 '200'        | '1%'      | '1/20W'  | '0201LF'  | 'CHIP'   | 'CS12001FE01'(!)        = ''              | ''                 | 'CS12001FE01'           |'R0201'| '(SMR0201AW)'                  | '200'     | '1%'    | '1/20W'  | 'DISCRETE' | 'RES CHIP 200 1/20W +-1%(0201)'                    | 'CHIP0201'     | ''          | ''            | '20171130'
 '200'        | '1%'      | '1/20W'  | '0201LF'  | 'EMPTY'  | 'CS12001FE01'(!)        = ''              | ''                 | 'CS12001FE01'           |'R0201'| '(SMR0201AW)'                  | '200'     | '1%'    | '1/20W'  | 'IO'       | 'RES CHIP 200 1/20W +-1%(0201)'                    | 'CHIP0201'     | ''          | ''            | '20171130'
 '0.0002'     | '1%'      | '4W'     | '2725LF'  | 'CHIP'   | 'CS0000FFT06'(!)        = 'End of Design' | 'Comp-Approve'     | 'CS0000FFT06'           |'R2725'| '(SMR2725AW)'                  | '0.0002'  | '1%'    | '4W'     | 'DISCRETE' | 'RES CHIP 0.0002 4W +-1%(2725)1.1'                 | 'CHIP2725'     | ''          | ''            | '20171215'
 '0.0002'     | '1%'      | '4W'     | '2725LF'  | 'EMPTY'  | 'CS0000FFT06'(!)        = 'End of Design' | 'Comp-Approve'     | 'CS0000FFT06'           |'R2725'| '(SMR2725AW)'                  | '0.0002'  | '1%'    | '4W'     | 'IO'       | 'RES CHIP 0.0002 4W +-1%(2725)1.1'                 | 'CHIP2725'     | ''          | ''            | '20171215'
 '5.62K'      | '0.1%'    | '1/16W'  | '0402LF'  | 'CHIP'   | 'CS25622BB00'(!)        = ''              | ''                 | 'CS25622BB00'           |'R0402'| '(R0402-0201)'                 | '5.62K'   | '0.1%'  | '1/16W'  | 'DISCRETE' | 'RES CHIP 5.62K 1/16W +-0.1%(0402)'                | 'CHIPR0402'    | ''          | ''            | '20180103'
 '5.62K'      | '0.1%'    | '1/16W'  | '0402LF'  | 'EMPTY'  | 'CS25622BB00'(!)        = ''              | ''                 | 'CS25622BB00'           |'R0402'| '(R0402-0201)'                 | '5.62K'   | '0.1%'  | '1/16W'  | 'IO'       | 'RES CHIP 5.62K 1/16W +-0.1%(0402)'                | 'CHIPR0402'    | ''          | ''            | '20180103'
 '143'        | '1%'      | '1/16W'  | '0402LF'  | 'CHIP'   | 'CS11432FB00'(!)        = 'End of Design' | 'Comp-Approve'     | 'CS11432FB00'           |'R0402'| '(R0402-0201)'                 | '143'     | '1%'    | '1/16W'  | 'DISCRETE' | 'RES CHIP 143 1/16W +-1%(0402)'                    | 'CHIPR0402'    | ''          | ''            | '20100429'
 '143'        | '1%'      | '1/16W'  | '0402LF'  | 'EMPTY'  | 'CS11432FB00'(!)        = 'End of Design' | 'Comp-Approve'     | 'CS11432FB00'           |'R0402'| '(R0402-0201)'                 | '143'     | '1%'    | '1/16W'  | 'IO'       | 'RES CHIP 143 1/16W +-1%(0402)'                    | 'CHIPR0402'    | ''          | ''            | '20100429'
 '86.6'       | '1%'      | '1/16W'  | '0402LF'  | 'CHIP'   | 'CS08662FB00'(!)        = 'End of Design' | 'Comp-Approve'     | 'CS08662FB00'           |'R0402'| '(R0402-0201)'                 | '86.6'    | '1%'    | '1/16W'  | 'DISCRETE' | 'RES CHIP 86.6 1/16W +-1%(0402)'                   | 'CHIP0402'     | ''          | ''            | '20180109'
 '86.6'       | '1%'      | '1/16W'  | '0402LF'  | 'EMPTY'  | 'CS08662FB00'(!)        = 'End of Design' | 'Comp-Approve'     | 'CS08662FB00'           |'R0402'| '(R0402-0201)'                 | '86.6'    | '1%'    | '1/16W'  | 'IO'       | 'RES CHIP 86.6 1/16W +-1%(0402)'                   | 'CHIP0402'     | ''          | ''            | '20180109'
 '120'        | '1%'      | '1/16W'  | '0402LF'  | 'CHIP'   | 'CS11202FB02'(!)        = 'End of Design' | 'Comp-Approve'     | 'CS11202FB02'           |'R0402'| '(R0402-0201)'                 | '120'     | '1%'    | '1/16W'  | 'DISCRETE' | 'RES CHIP 120 1/16W +-1%(0402)EF'                  | 'CHIPR0402'    | ''          | ''            | '20180116'
 '120'        | '1%'      | '1/16W'  | '0402LF'  | 'EMPTY'  | 'CS11202FB02'(!)        = 'End of Design' | 'Comp-Approve'     | 'CS11202FB02'           |'R0402'| '(R0402-0201)'                 | '120'     | '1%'    | '1/16W'  | 'IO'       | 'RES CHIP 120 1/16W +-1%(0402)EF'                  | 'CHIPR0402'    | ''          | ''            | '20180116'
 '57.6K'      | '0.1%'    | '1/16W'  | '0402LF'  | 'CHIP'   | 'CS35762BB00'(!)        = ''              | ''                 | 'CS35762BB00'           |'R0402'| '(R0402-0201)'                 | '57.6K'   | '0.1%'  | '1/16W'  | 'DISCRETE' | 'RES CHIP 57.6K 1/16W +-0.1% (0402)'               | 'CHIPR0402'    | ''          | ''            | '20150414'
 '57.6K'      | '0.1%'    | '1/16W'  | '0402LF'  | 'EMPTY'  | 'CS35762BB00'(!)        = ''              | ''                 | 'CS35762BB00'           |'R0402'| '(R0402-0201)'                 | '57.6K'   | '0.1%'  | '1/16W'  | 'IO'       | 'RES CHIP 57.6K 1/16W +-0.1% (0402)'               | 'CHIPR0402'    | ''          | ''            | '20150414'
 '10.2K'      | '1%'      | '1/16W'  | '0402LF'  | 'CHIP'   | 'CS31022FB04'(!)        = 'End of Design' | 'Comp-Approve'     | 'CS31022FB04'           |'R0402'| '(R0402-0201)'                 | '10.2K'   | '1%'    | '1/16W'  | 'DISCRETE' | 'RES CHIP 10.2K 1/16W +-1%(0402)EF'                | 'CHIPR0402'    | ''          | ''            | '20180116'
 '10.2K'      | '1%'      | '1/16W'  | '0402LF'  | 'EMPTY'  | 'CS31022FB04'(!)        = 'End of Design' | 'Comp-Approve'     | 'CS31022FB04'           |'R0402'| '(R0402-0201)'                 | '10.2K'   | '1%'    | '1/16W'  | 'IO'       | 'RES CHIP 10.2K 1/16W +-1%(0402)EF'                | 'CHIPR0402'    | ''          | ''            | '20180116'
 '4.02K'      | '0.1%'    | '1/16W'  | '0402LF'  | 'CHIP'   | 'CS24022BB00'(!)        = ''              | ''                 | 'CS24022BB00'           |'R0402'| '(R0402-0201)'                 | '4.02K'   | '0.1%'  | '1/16W'  | 'DISCRETE' | 'RES CHIP 4.02K 1/16W  +-0.1%(0402)'               | 'CHIPR0402'    | ''          | ''            | '20170829'
 '4.02K'      | '0.1%'    | '1/16W'  | '0402LF'  | 'EMPTY'  | 'CS24022BB00'(!)        = ''              | ''                 | 'CS24022BB00'           |'R0402'| '(R0402-0201)'                 | '4.02K'   | '0.1%'  | '1/16W'  | 'IO'       | 'RES CHIP 4.02K 1/16W  +-0.1%(0402)'               | 'CHIPR0402'    | ''          | ''            | '20170829'
 '375'        | '1%'      | '1/10W'  | '0603LF'  | 'CHIP'   | 'CS13753F906'(!)        = 'End of Design' | 'Comp-Approve'     | 'CS13753F906'           |'R0603'| '(SMR0603AW)'                  | '375'     | '1%'    | '1/10W'  | 'DISCRETE' | 'RES CHIP 375 1/10W+-1%(0603)'                     | 'CHIP0603'     | ''          | ''            | '20180131'
 '375'        | '1%'      | '1/10W'  | '0603LF'  | 'EMPTY'  | 'CS13753F906'(!)        = 'End of Design' | 'Comp-Approve'     | 'CS13753F906'           |'R0603'| '(SMR0603AW)'                  | '375'     | '1%'    | '1/10W'  | 'IO'       | 'RES CHIP 375 1/10W+-1%(0603)'                     | 'CHIP0603'     | ''          | ''            | '20180131'
 '576K'       | '1%'      | '1/16W'  | '0402LF'  | 'CHIP'   | 'CS45762FB13'(!)        = 'End of Design' | 'Comp-Approve'     | 'CS45762FB13'           |'R0402'| '(R0402-0201)'                 | '576K'    | '1%'    | '1/16W'  | 'DISCRETE' | 'RES CHIP 576K 1/16W +-1%(0402)'                   | 'CHIPR0402'    | ''          | ''            | '20180206'
 '576K'       | '1%'      | '1/16W'  | '0402LF'  | 'EMPTY'  | 'CS45762FB13'(!)        = 'End of Design' | 'Comp-Approve'     | 'CS45762FB13'           |'R0402'| '(R0402-0201)'                 | '576K'    | '1%'    | '1/16W'  | 'IO'       | 'RES CHIP 576K 1/16W +-1%(0402)'                   | 'CHIPR0402'    | ''          | ''            | '20180206'
 '1.1M'       | '1%'      | '1/16W'  | '0402LF'  | 'CHIP'   | 'CS51102FB00'(!)        = ''              | ''                 | 'CS51102FB00'           |'R0402'| '(R0402-0201)'                 | '1.1M'    | '1%'    | '1/16W'  | 'DISCRETE' | 'RES CHIP 1.1M 1/16W +-1%(0402)'                   | 'CHIPR0402'    | ''          | ''            | '20180206'
 '1.1M'       | '1%'      | '1/16W'  | '0402LF'  | 'EMPTY'  | 'CS51102FB00'(!)        = ''              | ''                 | 'CS51102FB00'           |'R0402'| '(R0402-0201)'                 | '1.1M'    | '1%'    | '1/16W'  | 'IO'       | 'RES CHIP 1.1M 1/16W +-1%(0402)'                   | 'CHIPR0402'    | ''          | ''            | '20180206'
 '1.18M'      | '1%'      | '1/16W'  | '0402LF'  | 'CHIP'   | 'CS51182FB01'(!)        = ''              | ''                 | 'CS51182FB01'           |'R0402'| '(R0402-0201)'                 | '1.18M'   | '1%'    | '1/16W'  | 'DISCRETE' | 'RES CHIP 1.18M 1/16W +-1%(0402)'                  | 'CHIPR0402'    | ''          | ''            | '20180207'
 '1.18M'      | '1%'      | '1/16W'  | '0402LF'  | 'EMPTY'  | 'CS51182FB01'(!)        = ''              | ''                 | 'CS51182FB01'           |'R0402'| '(R0402-0201)'                 | '1.18M'   | '1%'    | '1/16W'  | 'IO'       | 'RES CHIP 1.18M 1/16W +-1%(0402)'                  | 'CHIPR0402'    | ''          | ''            | '20180207'
 '1.13M'      | '1%'      | '1/16W'  | '0402LF'  | 'CHIP'   | 'CS51132FB00'(!)        = ''              | ''                 | 'CS51132FB00'           |'R0402'| '(R0402-0201)'                 | '1.13M'   | '1%'    | '1/16W'  | 'DISCRETE' | 'RES CHIP 1.13M 1/16W +-1%(0402)'                  | 'CHIPR0402'    | ''          | ''            | '20180207'
 '1.13M'      | '1%'      | '1/16W'  | '0402LF'  | 'EMPTY'  | 'CS51132FB00'(!)        = ''              | ''                 | 'CS51132FB00'           |'R0402'| '(R0402-0201)'                 | '1.13M'   | '1%'    | '1/16W'  | 'IO'       | 'RES CHIP 1.13M 1/16W +-1%(0402)'                  | 'CHIPR0402'    | ''          | ''            | '20180207'
 '0.51'       | '1%'      | '1/16W'  | '0402LF'  | 'CHIP'   | 'CS+5102FB01'(!)        = ''              | ''                 | 'CS+5102FB01'           |'R0402'| '(R0402-0201)'                 | '0.51'    | '1%'    | '1/16W'  | 'DISCRETE' | 'RES CHIP 0.51 1/16W +-1%(0402)EF'                 | 'CHIP0402'     | ''          | ''            | '20180212'
 '0.51'       | '1%'      | '1/16W'  | '0402LF'  | 'EMPTY'  | 'CS+5102FB01'(!)        = ''              | ''                 | 'CS+5102FB01'           |'R0402'| '(R0402-0201)'                 | '0.51'    | '1%'    | '1/16W'  | 'IO'       | 'RES CHIP 0.51 1/16W +-1%(0402)EF'                 | 'CHIP0402'     | ''          | ''            | '20180212'
 '143'        | '1%'      | '1/16W'  | '0402LF'  | 'CHIP'   | 'CS11432FB02'(!)        = ''              | ''                 | 'CS11432FB02'           |'R0402'| '(R0402-0201)'                 | '143'     | '1%'    | '1/16W'  | 'DISCRETE' | 'RES CHIP 143 1/16W +-1%(0402)EF'                  | 'CHIP0402'     | ''          | ''            | '20180212'
 '143'        | '1%'      | '1/16W'  | '0402LF'  | 'EMPTY'  | 'CS11432FB02'(!)        = ''              | ''                 | 'CS11432FB02'           |'R0402'| '(R0402-0201)'                 | '143'     | '1%'    | '1/16W'  | 'IO'       | 'RES CHIP 143 1/16W +-1%(0402)EF'                  | 'CHIP0402'     | ''          | ''            | '20180212'
 '220'        | '1%'      | '1/16W'  | '0402LF'  | 'CHIP'   | 'CS12202FB04'(!)        = ''              | ''                 | 'CS12202FB04'           |'R0402'| '(R0402-0201)'                 | '220'     | '1%'    | '1/16W'  | 'DISCRETE' | 'RES CHIP 220 1/16W +-1%(0402)EF'                  | 'CHIP0402'     | ''          | ''            | '20180212'
 '220'        | '1%'      | '1/16W'  | '0402LF'  | 'EMPTY'  | 'CS12202FB04'(!)        = ''              | ''                 | 'CS12202FB04'           |'R0402'| '(R0402-0201)'                 | '220'     | '1%'    | '1/16W'  | 'IO'       | 'RES CHIP 220 1/16W +-1%(0402)EF'                  | 'CHIP0402'     | ''          | ''            | '20180212'
 '1K'         | '1%'      | '1/20W'  | '0201LF'  | 'CHIP'   | 'CS21001FE07'(!)        = ''              | ''                 | 'CS21001FE07'           |'R0201'| '(SMR0201AW)'                  | '1K'      | '1%'    | '1/20W'  | 'DISCRETE' | 'RES CHIP 1K 1/20W +-1%(0201)EF'                   | 'CHIP0201'     | ''          | ''            | '20180212'
 '1K'         | '1%'      | '1/20W'  | '0201LF'  | 'EMPTY'  | 'CS21001FE07'(!)        = ''              | ''                 | 'CS21001FE07'           |'R0201'| '(SMR0201AW)'                  | '1K'      | '1%'    | '1/20W'  | 'IO'       | 'RES CHIP 1K 1/20W +-1%(0201)EF'                   | 'CHIP0201'     | ''          | ''            | '20180212'
 '5.62K'      | '0.1%'    | '1/16W'  | '0402LF'  | 'CHIP'   | 'CS25622BB01'(!)        = ''              | ''                 | 'CS25622BB01'           |'R0402'| '(R0402-0201)'                 | '5.62K'   | '0.1%'  | '1/16W'  | 'DISCRETE' | 'RES CHIP 5.62K 1/16W +-0.1%(0402)EF'              | 'CHIP0402'     | ''          | ''            | '20180212'
 '5.62K'      | '0.1%'    | '1/16W'  | '0402LF'  | 'EMPTY'  | 'CS25622BB01'(!)        = ''              | ''                 | 'CS25622BB01'           |'R0402'| '(R0402-0201)'                 | '5.62K'   | '0.1%'  | '1/16W'  | 'IO'       | 'RES CHIP 5.62K 1/16W +-0.1%(0402)EF'              | 'CHIP0402'     | ''          | ''            | '20180212'
 '6.2K'       | '1%'      | '1/16W'  | '0402LF'  | 'CHIP'   | 'CS26202FB02'(!)        = ''              | ''                 | 'CS26202FB02'           |'R0402'| '(R0402-0201)'                 | '6.2K'    | '1%'    | '1/16W'  | 'DISCRETE' | 'RES CHIP 6.2K 1/16W +-1%(0402)EF'                 | 'CHIP0402'     | ''          | ''            | '20180212'
 '6.2K'       | '1%'      | '1/16W'  | '0402LF'  | 'EMPTY'  | 'CS26202FB02'(!)        = ''              | ''                 | 'CS26202FB02'           |'R0402'| '(R0402-0201)'                 | '6.2K'    | '1%'    | '1/16W'  | 'IO'       | 'RES CHIP 6.2K 1/16W +-1%(0402)EF'                 | 'CHIP0402'     | ''          | ''            | '20180212'
 '6.8K'       | '1%'      | '1/16W'  | '0402LF'  | 'CHIP'   | 'CS26802FB02'(!)        = ''              | ''                 | 'CS26802FB02'           |'R0402'| '(R0402-0201)'                 | '6.8K'    | '1%'    | '1/16W'  | 'DISCRETE' | 'RES CHIP 6.8K 1/16W +-1%(0402)EF'                 | 'CHIP0402'     | ''          | ''            | '20180212'
 '6.8K'       | '1%'      | '1/16W'  | '0402LF'  | 'EMPTY'  | 'CS26802FB02'(!)        = ''              | ''                 | 'CS26802FB02'           |'R0402'| '(R0402-0201)'                 | '6.8K'    | '1%'    | '1/16W'  | 'IO'       | 'RES CHIP 6.8K 1/16W +-1%(0402)EF'                 | 'CHIP0402'     | ''          | ''            | '20180212'
 '7.5K'       | '0.1%'    | '1/16W'  | '0402LF'  | 'CHIP'   | 'CS27502BB01'(!)        = ''              | ''                 | 'CS27502BB01'           |'R0402'| '(R0402-0201)'                 | '7.5K'    | '0.1%'  | '1/16W'  | 'DISCRETE' | 'RES CHIP 7.5K 1/16W +-0.1%(0402)EF'               | 'CHIP0402'     | ''          | ''            | '20180212'
 '7.5K'       | '0.1%'    | '1/16W'  | '0402LF'  | 'EMPTY'  | 'CS27502BB01'(!)        = ''              | ''                 | 'CS27502BB01'           |'R0402'| '(R0402-0201)'                 | '7.5K'    | '0.1%'  | '1/16W'  | 'IO'       | 'RES CHIP 7.5K 1/16W +-0.1%(0402)EF'               | 'CHIP0402'     | ''          | ''            | '20180212'
 '8.45K'      | '1%'      | '1/16W'  | '0402LF'  | 'CHIP'   | 'CS28452FB06'(!)        = ''              | ''                 | 'CS28452FB06'           |'R0402'| '(R0402-0201)'                 | '8.45K'   | '1%'    | '1/16W'  | 'DISCRETE' | 'RES CHIP 8.45K 1/16W +-1%( 0402)EF'               | 'CHIP0402'     | ''          | ''            | '20180212'
 '8.45K'      | '1%'      | '1/16W'  | '0402LF'  | 'EMPTY'  | 'CS28452FB06'(!)        = ''              | ''                 | 'CS28452FB06'           |'R0402'| '(R0402-0201)'                 | '8.45K'   | '1%'    | '1/16W'  | 'IO'       | 'RES CHIP 8.45K 1/16W +-1%( 0402)EF'               | 'CHIP0402'     | ''          | ''            | '20180212'
 '12K'        | '0.1%'    | '1/16W'  | '0402LF'  | 'CHIP'   | 'CS31202BB01'(!)        = ''              | ''                 | 'CS31202BB01'           |'R0402'| '(R0402-0201)'                 | '12K'     | '0.1%'  | '1/16W'  | 'DISCRETE' | 'RES CHIP 12K 1/16W +-0.1%(0402)EF'                | 'CHIP0402'     | ''          | ''            | '20180212'
 '12K'        | '0.1%'    | '1/16W'  | '0402LF'  | 'EMPTY'  | 'CS31202BB01'(!)        = ''              | ''                 | 'CS31202BB01'           |'R0402'| '(R0402-0201)'                 | '12K'     | '0.1%'  | '1/16W'  | 'IO'       | 'RES CHIP 12K 1/16W +-0.1%(0402)EF'                | 'CHIP0402'     | ''          | ''            | '20180212'
 '20K'        | '5%'      | '1/16W'  | '0402LF'  | 'CHIP'   | 'CS32002JB06'(!)        = ''              | ''                 | 'CS32002JB06'           |'R0402'| '(R0402-0201)'                 | '20K'     | '5%'    | '1/16W'  | 'DISCRETE' | 'RES CHIP 20K 1/16W +-5%(0402)EF'                  | 'CHIP0402'     | ''          | ''            | '20180212'
 '20K'        | '5%'      | '1/16W'  | '0402LF'  | 'EMPTY'  | 'CS32002JB06'(!)        = ''              | ''                 | 'CS32002JB06'           |'R0402'| '(R0402-0201)'                 | '20K'     | '5%'    | '1/16W'  | 'IO'       | 'RES CHIP 20K 1/16W +-5%(0402)EF'                  | 'CHIP0402'     | ''          | ''            | '20180212'
 '34K'        | '1%'      | '1/16W'  | '0402LF'  | 'CHIP'   | 'CS33402FB06'(!)        = ''              | ''                 | 'CS33402FB06'           |'R0402'| '(R0402-0201)'                 | '34K'     | '1%'    | '1/16W'  | 'DISCRETE' | 'RES CHIP 34K 1/16W +-1%(0402)EF'                  | 'CHIP0402'     | ''          | ''            | '20180212'
 '34K'        | '1%'      | '1/16W'  | '0402LF'  | 'EMPTY'  | 'CS33402FB06'(!)        = ''              | ''                 | 'CS33402FB06'           |'R0402'| '(R0402-0201)'                 | '34K'     | '1%'    | '1/16W'  | 'IO'       | 'RES CHIP 34K 1/16W +-1%(0402)EF'                  | 'CHIP0402'     | ''          | ''            | '20180212'
 '1.87K'      | '0.1%'    | '1/16W'  | '0402LF'  | 'CHIP'   | 'CS21872BB00'(!)        = ''              | ''                 | 'CS21872BB00'           |'R0402'| '(R0402-0201)'                 | '1.87K'   | '0.1%'  | '1/16W'  | 'DISCRETE' | 'RES CHIP 1.87K 1/16W +-0.1%(0402)EF'              | 'CHIP0402'     | ''          | ''            | '20180212'
 '1.87K'      | '0.1%'    | '1/16W'  | '0402LF'  | 'EMPTY'  | 'CS21872BB00'(!)        = ''              | ''                 | 'CS21872BB00'           |'R0402'| '(R0402-0201)'                 | '1.87K'   | '0.1%'  | '1/16W'  | 'IO'       | 'RES CHIP 1.87K 1/16W +-0.1%(0402)EF'              | 'CHIP0402'     | ''          | ''            | '20180212'
 '2.37K'      | '0.1%'    | '1/16W'  | '0402LF'  | 'CHIP'   | 'CS22372BB02'(!)        = ''              | ''                 | 'CS22372BB02'           |'R0402'| '(R0402-0201)'                 | '2.37K'   | '0.1%'  | '1/16W'  | 'DISCRETE' | 'RES CHIP 2.37K 1/16W +-0.1%(0402)EF'              | 'CHIP0402'     | ''          | ''            | '20180212'
 '2.37K'      | '0.1%'    | '1/16W'  | '0402LF'  | 'EMPTY'  | 'CS22372BB02'(!)        = ''              | ''                 | 'CS22372BB02'           |'R0402'| '(R0402-0201)'                 | '2.37K'   | '0.1%'  | '1/16W'  | 'IO'       | 'RES CHIP 2.37K 1/16W +-0.1%(0402)EF'              | 'CHIP0402'     | ''          | ''            | '20180212'
 '4.02K'      | '0.1%'    | '1/16W'  | '0402LF'  | 'CHIP'   | 'CS24022BB01'(!)        = ''              | ''                 | 'CS24022BB01'           |'R0402'| '(R0402-0201)'                 | '4.02K'   | '0.1%'  | '1/16W'  | 'DISCRETE' | 'RES CHIP 4.02K 1/16W +-0.1%(0402)EF'              | 'CHIP0402'     | ''          | ''            | '20180212'
 '4.02K'      | '0.1%'    | '1/16W'  | '0402LF'  | 'EMPTY'  | 'CS24022BB01'(!)        = ''              | ''                 | 'CS24022BB01'           |'R0402'| '(R0402-0201)'                 | '4.02K'   | '0.1%'  | '1/16W'  | 'IO'       | 'RES CHIP 4.02K 1/16W +-0.1%(0402)EF'              | 'CHIP0402'     | ''          | ''            | '20180212'
 '57.6K'      | '0.1%'    | '1/16W'  | '0402LF'  | 'CHIP'   | 'CS35762BB01'(!)        = ''              | ''                 | 'CS35762BB01'           |'R0402'| '(R0402-0201)'                 | '57.6K'   | '0.1%'  | '1/16W'  | 'DISCRETE' | 'RES CHIP 57.6K 1/16W +-0.1%(0402)EF'              | 'CHIP0402'     | ''          | ''            | '20180212'
 '57.6K'      | '0.1%'    | '1/16W'  | '0402LF'  | 'EMPTY'  | 'CS35762BB01'(!)        = ''              | ''                 | 'CS35762BB01'           |'R0402'| '(R0402-0201)'                 | '57.6K'   | '0.1%'  | '1/16W'  | 'IO'       | 'RES CHIP 57.6K 1/16W +-0.1%(0402)EF'              | 'CHIP0402'     | ''          | ''            | '20180212'
 '100K'       | '0.1%'    | '1/16W'  | '0402LF'  | 'CHIP'   | 'CS41002BB08'(!)        = ''              | ''                 | 'CS41002BB08'           |'R0402'| '(R0402-0201)'                 | '100K'    | '0.1%'  | '1/16W'  | 'DISCRETE' | 'RES CHIP 100K 1/16W +-0.1%(0402)EF'               | 'CHIP0402'     | ''          | ''            | '20180212'
 '100K'       | '0.1%'    | '1/16W'  | '0402LF'  | 'EMPTY'  | 'CS41002BB08'(!)        = ''              | ''                 | 'CS41002BB08'           |'R0402'| '(R0402-0201)'                 | '100K'    | '0.1%'  | '1/16W'  | 'IO'       | 'RES CHIP 100K 1/16W +-0.1%(0402)EF'               | 'CHIP0402'     | ''          | ''            | '20180212'
 '2.2'        | '1%'      | '1/16W'  | '0402LF'  | 'CHIP'   | 'CS-2202FB01'(!)        = 'End of Design' | 'Comp-Approve'     | 'CS-2202FB01'           |'R0402'| '(R0402-0201)'                 | '2.2'     | '1%'    | '1/16W'  | 'DISCRETE' | 'RES CHIP 2.2 1/16W +-1%(0402)EF'                  | 'CHIP0402'     | ''          | ''            | '20180212'
 '2.2'        | '1%'      | '1/16W'  | '0402LF'  | 'EMPTY'  | 'CS-2202FB01'(!)        = 'End of Design' | 'Comp-Approve'     | 'CS-2202FB01'           |'R0402'| '(R0402-0201)'                 | '2.2'     | '1%'    | '1/16W'  | 'IO'       | 'RES CHIP 2.2 1/16W +-1%(0402)EF'                  | 'CHIP0402'     | ''          | ''            | '20180212'
 '0'          | '5%'      | '1/20W'  | '0201LF'  | 'CHIP'   | 'CS00001JE10'(!)        = 'End of Design' | 'Comp-Approve'     | 'CS00001JE10'           |'R0201'| '(SMR0201AW)'                  | '0'       | '5%'    | '1/20W'  | 'DISCRETE' | 'RES CHIP 0 1/20W +-5% (0201)EF'                   | 'CHIP0201'     | ''          | ''            | '20180212'
 '0'          | '5%'      | '1/20W'  | '0201LF'  | 'EMPTY'  | 'CS00001JE10'(!)        = 'End of Design' | 'Comp-Approve'     | 'CS00001JE10'           |'R0201'| '(SMR0201AW)'                  | '0'       | '5%'    | '1/20W'  | 'IO'       | 'RES CHIP 0 1/20W +-5% (0201)EF'                   | 'CHIP0201'     | ''          | ''            | '20180212'
 '22'         | '5%'      | '1/16W'  | '0402LF'  | 'CHIP'   | 'CS02202JB09'(!)        = 'End of Design' | 'Comp-Approve'     | 'CS02202JB09'           |'R0402'| '(R0402-0201)'                 | '22'      | '5%'    | '1/16W'  | 'DISCRETE' | 'RES CHIP 22 1/16W +-5%(0402)EF'                   | 'CHIP0402'     | ''          | ''            | '20180212'
 '22'         | '5%'      | '1/16W'  | '0402LF'  | 'EMPTY'  | 'CS02202JB09'(!)        = 'End of Design' | 'Comp-Approve'     | 'CS02202JB09'           |'R0402'| '(R0402-0201)'                 | '22'      | '5%'    | '1/16W'  | 'IO'       | 'RES CHIP 22 1/16W +-5%(0402)EF'                   | 'CHIP0402'     | ''          | ''            | '20180212'
 '51'         | '5%'      | '1/16W'  | '0402LF'  | 'CHIP'   | 'CS05102JB04'(!)        = 'End of Design' | 'Comp-Approve'     | 'CS05102JB04'           |'R0402'| '(R0402-0201)'                 | '51'      | '5%'    | '1/16W'  | 'DISCRETE' | 'RES CHIP 51 1/16W +-5%(0402)EF'                   | 'CHIP0402'     | ''          | ''            | '20180212'
 '51'         | '5%'      | '1/16W'  | '0402LF'  | 'EMPTY'  | 'CS05102JB04'(!)        = 'End of Design' | 'Comp-Approve'     | 'CS05102JB04'           |'R0402'| '(R0402-0201)'                 | '51'      | '5%'    | '1/16W'  | 'IO'       | 'RES CHIP 51 1/16W +-5%(0402)EF'                   | 'CHIP0402'     | ''          | ''            | '20180212'
 '82.5'       | '1%'      | '1/16W'  | '0402LF'  | 'CHIP'   | 'CS08252FB02'(!)        = 'End of Design' | 'Comp-Approve'     | 'CS08252FB02'           |'R0402'| '(R0402-0201)'                 | '82.5'    | '1%'    | '1/16W'  | 'DISCRETE' | 'RES CHIP 82.5 1/16W +-1%(0402)EF'                 | 'CHIP0402'     | ''          | ''            | '20180212'
 '82.5'       | '1%'      | '1/16W'  | '0402LF'  | 'EMPTY'  | 'CS08252FB02'(!)        = 'End of Design' | 'Comp-Approve'     | 'CS08252FB02'           |'R0402'| '(R0402-0201)'                 | '82.5'    | '1%'    | '1/16W'  | 'IO'       | 'RES CHIP 82.5 1/16W +-1%(0402)EF'                 | 'CHIP0402'     | ''          | ''            | '20180212'
 '330'        | '1%'      | '1/16W'  | '0402LF'  | 'CHIP'   | 'CS13302FB00'(!)        = 'End of Design' | 'Comp-Approve'     | 'CS13302FB00'           |'R0402'| '(R0402-0201)'                 | '330'     | '1%'    | '1/16W'  | 'DISCRETE' | 'RES CHIP 330 1/16W +-1%(0402)EF'                  | 'CHIP0402'     | ''          | ''            | '20180212'
 '330'        | '1%'      | '1/16W'  | '0402LF'  | 'EMPTY'  | 'CS13302FB00'(!)        = 'End of Design' | 'Comp-Approve'     | 'CS13302FB00'           |'R0402'| '(R0402-0201)'                 | '330'     | '1%'    | '1/16W'  | 'IO'       | 'RES CHIP 330 1/16W +-1%(0402)EF'                  | 'CHIP0402'     | ''          | ''            | '20180212'
 '2.2K'       | '5%'      | '1/16W'  | '0402LF'  | 'CHIP'   | 'CS22202JB07'(!)        = 'End of Design' | 'Comp-Approve'     | 'CS22202JB07'           |'R0402'| '(R0402-0201)'                 | '2.2K'    | '5%'    | '1/16W'  | 'DISCRETE' | 'RES CHIP 2.2K 1/16W +-5%(0402)EF'                 | 'CHIP0402'     | ''          | ''            | '20180212'
 '2.2K'       | '5%'      | '1/16W'  | '0402LF'  | 'EMPTY'  | 'CS22202JB07'(!)        = 'End of Design' | 'Comp-Approve'     | 'CS22202JB07'           |'R0402'| '(R0402-0201)'                 | '2.2K'    | '5%'    | '1/16W'  | 'IO'       | 'RES CHIP 2.2K 1/16W +-5%(0402)EF'                 | 'CHIP0402'     | ''          | ''            | '20180212'
 '2.7K'       | '5%'      | '1/16W'  | '0402LF'  | 'CHIP'   | 'CS22702JB04'(!)        = 'End of Design' | 'Comp-Approve'     | 'CS22702JB04'           |'R0402'| '(R0402-0201)'                 | '2.7K'    | '5%'    | '1/16W'  | 'DISCRETE' | 'RES CHIP 2.7K 1/16W +-5%(0402)EF'                 | 'CHIP0402'     | ''          | ''            | '20180212'
 '2.7K'       | '5%'      | '1/16W'  | '0402LF'  | 'EMPTY'  | 'CS22702JB04'(!)        = 'End of Design' | 'Comp-Approve'     | 'CS22702JB04'           |'R0402'| '(R0402-0201)'                 | '2.7K'    | '5%'    | '1/16W'  | 'IO'       | 'RES CHIP 2.7K 1/16W +-5%(0402)EF'                 | 'CHIP0402'     | ''          | ''            | '20180212'
 '4.53K'      | '1%'      | '1/16W'  | '0402LF'  | 'CHIP'   | 'CS24532FB03'(!)        = 'End of Design' | 'Comp-Approve'     | 'CS24532FB03'           |'R0402'| '(R0402-0201)'                 | '4.53K'   | '1%'    | '1/16W'  | 'DISCRETE' | 'RES CHIP 4.53K 1/16W +-1%(0402)EF'                | 'CHIP0402'     | ''          | ''            | '20180212'
 '4.53K'      | '1%'      | '1/16W'  | '0402LF'  | 'EMPTY'  | 'CS24532FB03'(!)        = 'End of Design' | 'Comp-Approve'     | 'CS24532FB03'           |'R0402'| '(R0402-0201)'                 | '4.53K'   | '1%'    | '1/16W'  | 'IO'       | 'RES CHIP 4.53K 1/16W +-1%(0402)EF'                | 'CHIP0402'     | ''          | ''            | '20180212'
 '8.2K'       | '5%'      | '1/16W'  | '0402LF'  | 'CHIP'   | 'CS28202JB05'(!)        = 'End of Design' | 'Comp-Approve'     | 'CS28202JB05'           |'R0402'| '(R0402-0201)'                 | '8.2K'    | '5%'    | '1/16W'  | 'DISCRETE' | 'RES CHIP 8.2K 1/16W +-5% (0402) EF'               | 'CHIP0402'     | ''          | ''            | '20180212'
 '8.2K'       | '5%'      | '1/16W'  | '0402LF'  | 'EMPTY'  | 'CS28202JB05'(!)        = 'End of Design' | 'Comp-Approve'     | 'CS28202JB05'           |'R0402'| '(R0402-0201)'                 | '8.2K'    | '5%'    | '1/16W'  | 'IO'       | 'RES CHIP 8.2K 1/16W +-5% (0402) EF'               | 'CHIP0402'     | ''          | ''            | '20180212'
 '9.76K'      | '1%'      | '1/16W'  | '0402LF'  | 'CHIP'   | 'CS29762FB05'(!)        = 'End of Design' | 'Comp-Approve'     | 'CS29762FB05'           |'R0402'| '(R0402-0201)'                 | '9.76K'   | '1%'    | '1/16W'  | 'DISCRETE' | 'RES CHIP 9.76K 1/16W +-1%(0402)EF'                | 'CHIP0402'     | ''          | ''            | '20180212'
 '9.76K'      | '1%'      | '1/16W'  | '0402LF'  | 'EMPTY'  | 'CS29762FB05'(!)        = 'End of Design' | 'Comp-Approve'     | 'CS29762FB05'           |'R0402'| '(R0402-0201)'                 | '9.76K'   | '1%'    | '1/16W'  | 'IO'       | 'RES CHIP 9.76K 1/16W +-1%(0402)EF'                | 'CHIP0402'     | ''          | ''            | '20180212'
 '11.3K'      | '1%'      | '1/16W'  | '0402LF'  | 'CHIP'   | 'CS31132FB01'(!)        = 'End of Design' | 'Comp-Approve'     | 'CS31132FB01'           |'R0402'| '(R0402-0201)'                 | '11.3K'   | '1%'    | '1/16W'  | 'DISCRETE' | 'RES CHIP 11.3K 1/16W +-1%(0402)EF'                | 'CHIP0402'     | ''          | ''            | '20180212'
 '11.3K'      | '1%'      | '1/16W'  | '0402LF'  | 'EMPTY'  | 'CS31132FB01'(!)        = 'End of Design' | 'Comp-Approve'     | 'CS31132FB01'           |'R0402'| '(R0402-0201)'                 | '11.3K'   | '1%'    | '1/16W'  | 'IO'       | 'RES CHIP 11.3K 1/16W +-1%(0402)EF'                | 'CHIP0402'     | ''          | ''            | '20180212'
 '28K'        | '1%'      | '1/16W'  | '0402LF'  | 'CHIP'   | 'CS32802FB05'(!)        = 'End of Design' | 'Comp-Approve'     | 'CS32802FB05'           |'R0402'| '(R0402-0201)'                 | '28K'     | '1%'    | '1/16W'  | 'DISCRETE' | 'RES CHIP 28K 1/16W +-1%(0402)EF'                  | 'CHIP0402'     | ''          | ''            | '20180212'
 '28K'        | '1%'      | '1/16W'  | '0402LF'  | 'EMPTY'  | 'CS32802FB05'(!)        = 'End of Design' | 'Comp-Approve'     | 'CS32802FB05'           |'R0402'| '(R0402-0201)'                 | '28K'     | '1%'    | '1/16W'  | 'IO'       | 'RES CHIP 28K 1/16W +-1%(0402)EF'                  | 'CHIP0402'     | ''          | ''            | '20180212'
 '49.9K'      | '1%'      | '1/16W'  | '0402LF'  | 'CHIP'   | 'CS34992FB05'(!)        = 'End of Design' | 'Comp-Approve'     | 'CS34992FB05'           |'R0402'| '(R0402-0201)'                 | '49.9K'   | '1%'    | '1/16W'  | 'DISCRETE' | 'RES CHIP 49.9K 1/16W +-1%(0402)EF'                | 'CHIP0402'     | ''          | ''            | '20180212'
 '49.9K'      | '1%'      | '1/16W'  | '0402LF'  | 'EMPTY'  | 'CS34992FB05'(!)        = 'End of Design' | 'Comp-Approve'     | 'CS34992FB05'           |'R0402'| '(R0402-0201)'                 | '49.9K'   | '1%'    | '1/16W'  | 'IO'       | 'RES CHIP 49.9K 1/16W +-1%(0402)EF'                | 'CHIP0402'     | ''          | ''            | '20180212'
 '51K'        | '1%'      | '1/16W'  | '0402LF'  | 'CHIP'   | 'CS35102FB00'(!)        = 'End of Design' | 'Comp-Approve'     | 'CS35102FB00'           |'R0402'| '(R0402-0201)'                 | '51K'     | '1%'    | '1/16W'  | 'DISCRETE' | 'RES CHIP 51K 1/16W +-1%(0402)EF'                  | 'CHIP0402'     | ''          | ''            | '20180212'
 '51K'        | '1%'      | '1/16W'  | '0402LF'  | 'EMPTY'  | 'CS35102FB00'(!)        = 'End of Design' | 'Comp-Approve'     | 'CS35102FB00'           |'R0402'| '(R0402-0201)'                 | '51K'     | '1%'    | '1/16W'  | 'IO'       | 'RES CHIP 51K 1/16W +-1%(0402)EF'                  | 'CHIP0402'     | ''          | ''            | '20180212'
 '60.4K'      | '1%'      | '1/16W'  | '0402LF'  | 'CHIP'   | 'CS36042FB04'(!)        = 'End of Design' | 'Comp-Approve'     | 'CS36042FB04'           |'R0402'| '(R0402-0201)'                 | '60.4K'   | '1%'    | '1/16W'  | 'DISCRETE' | 'RES CHIP 60.4K 1/16W +-1%(0402)EF'                | 'CHIP0402'     | ''          | ''            | '20180212'
 '60.4K'      | '1%'      | '1/16W'  | '0402LF'  | 'EMPTY'  | 'CS36042FB04'(!)        = 'End of Design' | 'Comp-Approve'     | 'CS36042FB04'           |'R0402'| '(R0402-0201)'                 | '60.4K'   | '1%'    | '1/16W'  | 'IO'       | 'RES CHIP 60.4K 1/16W +-1%(0402)EF'                | 'CHIP0402'     | ''          | ''            | '20180212'
 '63.4K'      | '1%'      | '1/16W'  | '0402LF'  | 'CHIP'   | 'CS36342FB04'(!)        = 'End of Design' | 'Comp-Approve'     | 'CS36342FB04'           |'R0402'| '(R0402-0201)'                 | '63.4K'   | '1%'    | '1/16W'  | 'DISCRETE' | 'RES CHIP 63.4K 1/16W +-1%(0402)EF'                | 'CHIP0402'     | ''          | ''            | '20180212'
 '63.4K'      | '1%'      | '1/16W'  | '0402LF'  | 'EMPTY'  | 'CS36342FB04'(!)        = 'End of Design' | 'Comp-Approve'     | 'CS36342FB04'           |'R0402'| '(R0402-0201)'                 | '63.4K'   | '1%'    | '1/16W'  | 'IO'       | 'RES CHIP 63.4K 1/16W +-1%(0402)EF'                | 'CHIP0402'     | ''          | ''            | '20180212'
 '80.6K'      | '1%'      | '1/16W'  | '0402LF'  | 'CHIP'   | 'CS38062FB04'(!)        = 'End of Design' | 'Comp-Approve'     | 'CS38062FB04'           |'R0402'| '(R0402-0201)'                 | '80.6K'   | '1%'    | '1/16W'  | 'DISCRETE' | 'RES CHIP 80.6K 1/16W +-1%(0402)EF'                | 'CHIP0402'     | ''          | ''            | '20180212'
 '80.6K'      | '1%'      | '1/16W'  | '0402LF'  | 'EMPTY'  | 'CS38062FB04'(!)        = 'End of Design' | 'Comp-Approve'     | 'CS38062FB04'           |'R0402'| '(R0402-0201)'                 | '80.6K'   | '1%'    | '1/16W'  | 'IO'       | 'RES CHIP 80.6K 1/16W +-1%(0402)EF'                | 'CHIP0402'     | ''          | ''            | '20180212'
 '100K'       | '5%'      | '1/20W'  | '0201LF'  | 'CHIP'   | 'CS41001JE05'(!)        = 'End of Design' | 'Comp-Approve'     | 'CS41001JE05'           |'R0201'| '(SMR0201AW)'                  | '100K'    | '5%'    | '1/20W'  | 'DISCRETE' | 'RES CHIP 100K 1/20W +-5%(0201)EF'                 | 'CHIP0201'     | ''          | ''            | '20180212'
 '100K'       | '5%'      | '1/20W'  | '0201LF'  | 'EMPTY'  | 'CS41001JE05'(!)        = 'End of Design' | 'Comp-Approve'     | 'CS41001JE05'           |'R0201'| '(SMR0201AW)'                  | '100K'    | '5%'    | '1/20W'  | 'IO'       | 'RES CHIP 100K 1/20W +-5%(0201)EF'                 | 'CHIP0201'     | ''          | ''            | '20180212'
 '100K'       | '5%'      | '1/16W'  | '0402LF'  | 'CHIP'   | 'CS41002JB06'(!)        = 'End of Design' | 'Comp-Approve'     | 'CS41002JB06'           |'R0402'| '(R0402-0201)'                 | '100K'    | '5%'    | '1/16W'  | 'DISCRETE' | 'RES CHIP 100K 1/16W +-5%(0402)EF'                 | 'CHIP0402'     | ''          | ''            | '20180212'
 '100K'       | '5%'      | '1/16W'  | '0402LF'  | 'EMPTY'  | 'CS41002JB06'(!)        = 'End of Design' | 'Comp-Approve'     | 'CS41002JB06'           |'R0402'| '(R0402-0201)'                 | '100K'    | '5%'    | '1/16W'  | 'IO'       | 'RES CHIP 100K 1/16W +-5%(0402)EF'                 | 'CHIP0402'     | ''          | ''            | '20180212'
 '180K'       | '1%'      | '1/16W'  | '0402LF'  | 'CHIP'   | 'CS41802FB03'(!)        = 'End of Design' | 'Comp-Approve'     | 'CS41802FB03'           |'R0402'| '(R0402-0201)'                 | '180K'    | '1%'    | '1/16W'  | 'DISCRETE' | 'RES CHIP 180K 1/16W +-1%(0402)EF'                 | 'CHIP0402'     | ''          | ''            | '20180212'
 '180K'       | '1%'      | '1/16W'  | '0402LF'  | 'EMPTY'  | 'CS41802FB03'(!)        = 'End of Design' | 'Comp-Approve'     | 'CS41802FB03'           |'R0402'| '(R0402-0201)'                 | '180K'    | '1%'    | '1/16W'  | 'IO'       | 'RES CHIP 180K 1/16W +-1%(0402)EF'                 | 'CHIP0402'     | ''          | ''            | '20180212'
 '22'         | '1%'      | '1/16W'  | '0402LF'  | 'CHIP'   | 'CS02202FB02'(!)        = 'End of Design' | 'Comp-Approve'     | 'CS02202FB02'           |'R0402'| '(R0402-0201)'                 | '22'      | '1%'    | '1/16W'  | 'DISCRETE' | 'RES CHIP 22 1/16W +-1%(0402)EF'                   | 'CHIP0402'     | ''          | ''            | '20180212'
 '22'         | '1%'      | '1/16W'  | '0402LF'  | 'EMPTY'  | 'CS02202FB02'(!)        = 'End of Design' | 'Comp-Approve'     | 'CS02202FB02'           |'R0402'| '(R0402-0201)'                 | '22'      | '1%'    | '1/16W'  | 'IO'       | 'RES CHIP 22 1/16W +-1%(0402)EF'                   | 'CHIP0402'     | ''          | ''            | '20180212'
 '42.2'       | '1%'      | '1/16W'  | '0402LF'  | 'CHIP'   | 'CS04222FB05'(!)        = 'End of Design' | 'Comp-Approve'     | 'CS04222FB05'           |'R0402'| '(R0402-0201)'                 | '42.2'    | '1%'    | '1/16W'  | 'DISCRETE' | 'RES CHIP 42.2 1/16W +-1%(0402)EF'                 | 'CHIP0402'     | ''          | ''            | '20180212'
 '42.2'       | '1%'      | '1/16W'  | '0402LF'  | 'EMPTY'  | 'CS04222FB05'(!)        = 'End of Design' | 'Comp-Approve'     | 'CS04222FB05'           |'R0402'| '(R0402-0201)'                 | '42.2'    | '1%'    | '1/16W'  | 'IO'       | 'RES CHIP 42.2 1/16W +-1%(0402)EF'                 | 'CHIP0402'     | ''          | ''            | '20180212'
 '10K'        | '0.1%'    | '1/16W'  | '0402LF'  | 'CHIP'   | 'CS31002BB06'(!)        = 'End of Design' | 'Comp-Approve'     | 'CS31002BB06'           |'R0402'| '(R0402-0201)'                 | '10K'     | '0.1%'  | '1/16W'  | 'DISCRETE' | 'RES CHIP 10K 1/16W +-0.1%(0402)EF'                | 'CHIP0402'     | ''          | ''            | '20180212'
 '10K'        | '0.1%'    | '1/16W'  | '0402LF'  | 'EMPTY'  | 'CS31002BB06'(!)        = 'End of Design' | 'Comp-Approve'     | 'CS31002BB06'           |'R0402'| '(R0402-0201)'                 | '10K'     | '0.1%'  | '1/16W'  | 'IO'       | 'RES CHIP 10K 1/16W +-0.1%(0402)EF'                | 'CHIP0402'     | ''          | ''            | '20180212'
 '75K'        | '1%'      | '1/16W'  | '0402LF'  | 'CHIP'   | 'CS37502FB05'(!)        = 'End of Design' | 'Comp-Approve'     | 'CS37502FB05'           |'R0402'| '(R0402-0201)'                 | '75K'     | '1%'    | '1/16W'  | 'DISCRETE' | 'RES CHIP 75K 1/16W +-1%(0402)EF'                  | 'CHIP0402'     | ''          | ''            | '20180212'
 '75K'        | '1%'      | '1/16W'  | '0402LF'  | 'EMPTY'  | 'CS37502FB05'(!)        = 'End of Design' | 'Comp-Approve'     | 'CS37502FB05'           |'R0402'| '(R0402-0201)'                 | '75K'     | '1%'    | '1/16W'  | 'IO'       | 'RES CHIP 75K 1/16W +-1%(0402)EF'                  | 'CHIP0402'     | ''          | ''            | '20180212'
 '390K'       | '5%'      | '1/16W'  | '0402LF'  | 'CHIP'   | 'CS43902JB04'(!)        = 'End of Design' | 'Comp-Approve'     | 'CS43902JB04'           |'R0402'| '(R0402-0201)'                 | '390K'    | '5%'    | '1/16W'  | 'DISCRETE' | 'RES CHIP 390K 1/16W +-5%(0402)EF'                 | 'CHIP0402'     | ''          | ''            | '20180212'
 '390K'       | '5%'      | '1/16W'  | '0402LF'  | 'EMPTY'  | 'CS43902JB04'(!)        = 'End of Design' | 'Comp-Approve'     | 'CS43902JB04'           |'R0402'| '(R0402-0201)'                 | '390K'    | '5%'    | '1/16W'  | 'IO'       | 'RES CHIP 390K 1/16W +-5%(0402)EF'                 | 'CHIP0402'     | ''          | ''            | '20180212'
 '1M'         | '1%'      | '1/10W'  | '0603LF'  | 'CHIP'   | 'CS51003F903'(!)        = 'End of Design' | 'Comp-Approve'     | 'CS51003F903'           |'R0603'| '(SMR0603AW)'                  | '1M'      | '1%'    | '1/10W'  | 'DISCRETE' | 'RES CHIP 1M 1/10W +-1%(0603)EF'                   | 'CHIP0603'     | ''          | ''            | '20180212'
 '1M'         | '1%'      | '1/10W'  | '0603LF'  | 'EMPTY'  | 'CS51003F903'(!)        = 'End of Design' | 'Comp-Approve'     | 'CS51003F903'           |'R0603'| '(SMR0603AW)'                  | '1M'      | '1%'    | '1/10W'  | 'IO'       | 'RES CHIP 1M 1/10W +-1%(0603)EF'                   | 'CHIP0603'     | ''          | ''            | '20180212'
 '0'          | '5%'      | '1/16W'  | '0402LF'  | 'CHIP'   | 'CS00002JB13'(!)        = 'End of Design' | 'Comp-Approve'     | 'CS00002JB13'           |'R0402'| '(R0402-0201)'                 | '0'       | '5%'    | '1/16W'  | 'DISCRETE' | 'RES CHIP 0 1/16W +-5%(0402)EF'                    | 'CHIPR0402'    | ''          | ''            | '20180208'
 '0'          | '5%'      | '1/16W'  | '0402LF'  | 'EMPTY'  | 'CS00002JB13'(!)        = 'End of Design' | 'Comp-Approve'     | 'CS00002JB13'           |'R0402'| '(R0402-0201)'                 | '0'       | '5%'    | '1/16W'  | 'IO'       | 'RES CHIP 0 1/16W +-5%(0402)EF'                    | 'CHIPR0402'    | ''          | ''            | '20180208'
 '10'         | '1%'      | '1/16W'  | '0402LF'  | 'CHIP'   | 'CS01002FB07'(!)        = 'End of Design' | 'Comp-Approve'     | 'CS01002FB07'           |'R0402'| '(R0402-0201)'                 | '10'      | '1%'    | '1/16W'  | 'DISCRETE' | 'RES CHIP 10 1/16W +-1%(0402)EF'                   | 'CHIPR0402'    | ''          | ''            | '20180208'
 '10'         | '1%'      | '1/16W'  | '0402LF'  | 'EMPTY'  | 'CS01002FB07'(!)        = 'End of Design' | 'Comp-Approve'     | 'CS01002FB07'           |'R0402'| '(R0402-0201)'                 | '10'      | '1%'    | '1/16W'  | 'IO'       | 'RES CHIP 10 1/16W +-1%(0402)EF'                   | 'CHIPR0402'    | ''          | ''            | '20180208'
 '33.2'       | '1%'      | '1/16W'  | '0402LF'  | 'CHIP'   | 'CS03322FB03'(!)        = 'End of Design' | 'Comp-Approve'     | 'CS03322FB03'           |'R0402'| '(R0402-0201)'                 | '33.2'    | '1%'    | '1/16W'  | 'DISCRETE' | 'RES CHIP 33.2 1/16W +-1%(0402)EF'                 | 'CHIPR0402'    | ''          | ''            | '20180208'
 '33.2'       | '1%'      | '1/16W'  | '0402LF'  | 'EMPTY'  | 'CS03322FB03'(!)        = 'End of Design' | 'Comp-Approve'     | 'CS03322FB03'           |'R0402'| '(R0402-0201)'                 | '33.2'    | '1%'    | '1/16W'  | 'IO'       | 'RES CHIP 33.2 1/16W +-1%(0402)EF'                 | 'CHIPR0402'    | ''          | ''            | '20180208'
 '49.9'       | '1%'      | '1/16W'  | '0402LF'  | 'CHIP'   | 'CS04992FB07'(!)        = 'End of Design' | 'Comp-Approve'     | 'CS04992FB07'           |'R0402'| '(R0402-0201)'                 | '49.9'    | '1%'    | '1/16W'  | 'DISCRETE' | 'RES CHIP 49.9 1/16W +-1%(0402)EF'                 | 'CHIPR0402'    | ''          | ''            | '20180208'
 '49.9'       | '1%'      | '1/16W'  | '0402LF'  | 'EMPTY'  | 'CS04992FB07'(!)        = 'End of Design' | 'Comp-Approve'     | 'CS04992FB07'           |'R0402'| '(R0402-0201)'                 | '49.9'    | '1%'    | '1/16W'  | 'IO'       | 'RES CHIP 49.9 1/16W +-1%(0402)EF'                 | 'CHIPR0402'    | ''          | ''            | '20180208'
 '100'        | '1%'      | '1/16W'  | '0402LF'  | 'CHIP'   | 'CS11002FB07'(!)        = 'End of Design' | 'Comp-Approve'     | 'CS11002FB07'           |'R0402'| '(R0402-0201)'                 | '100'     | '1%'    | '1/16W'  | 'DISCRETE' | 'RES CHIP 100 1/16W +-1%(0402)EF'                  | 'CHIPR0402'    | ''          | ''            | '20180208'
 '100'        | '1%'      | '1/16W'  | '0402LF'  | 'EMPTY'  | 'CS11002FB07'(!)        = 'End of Design' | 'Comp-Approve'     | 'CS11002FB07'           |'R0402'| '(R0402-0201)'                 | '100'     | '1%'    | '1/16W'  | 'IO'       | 'RES CHIP 100 1/16W +-1%(0402)EF'                  | 'CHIPR0402'    | ''          | ''            | '20180208'
 '150'        | '1%'      | '1/16W'  | '0402LF'  | 'CHIP'   | 'CS11502FB07'(!)        = 'End of Design' | 'Comp-Approve'     | 'CS11502FB07'           |'R0402'| '(R0402-0201)'                 | '150'     | '1%'    | '1/16W'  | 'DISCRETE' | 'RES CHIP 150 1/16W +-1%(0402)EF'                  | 'CHIPR0402'    | ''          | ''            | '20180208'
 '150'        | '1%'      | '1/16W'  | '0402LF'  | 'EMPTY'  | 'CS11502FB07'(!)        = 'End of Design' | 'Comp-Approve'     | 'CS11502FB07'           |'R0402'| '(R0402-0201)'                 | '150'     | '1%'    | '1/16W'  | 'IO'       | 'RES CHIP 150 1/16W +-1%(0402)EF'                  | 'CHIPR0402'    | ''          | ''            | '20180208'
 '200'        | '1%'      | '1/16W'  | '0402LF'  | 'CHIP'   | 'CS12002FB06'(!)        = 'End of Design' | 'Comp-Approve'     | 'CS12002FB06'           |'R0402'| '(R0402-0201)'                 | '200'     | '1%'    | '1/16W'  | 'DISCRETE' | 'RES CHIP 200 1/16W +-1%(0402)EF'                  | 'CHIPR0402'    | ''          | ''            | '20180208'
 '200'        | '1%'      | '1/16W'  | '0402LF'  | 'EMPTY'  | 'CS12002FB06'(!)        = 'End of Design' | 'Comp-Approve'     | 'CS12002FB06'           |'R0402'| '(R0402-0201)'                 | '200'     | '1%'    | '1/16W'  | 'IO'       | 'RES CHIP 200 1/16W +-1%(0402)EF'                  | 'CHIPR0402'    | ''          | ''            | '20180208'
 '412'        | '1%'      | '1/16W'  | '0402LF'  | 'CHIP'   | 'CS14122FB04'(!)        = 'End of Design' | 'Comp-Approve'     | 'CS14122FB04'           |'R0402'| '(R0402-0201)'                 | '412'     | '1%'    | '1/16W'  | 'DISCRETE' | 'RES CHIP 412 1/16W +-1%(0402)EF'                  | 'CHIPR0402'    | ''          | ''            | '20180208'
 '412'        | '1%'      | '1/16W'  | '0402LF'  | 'EMPTY'  | 'CS14122FB04'(!)        = 'End of Design' | 'Comp-Approve'     | 'CS14122FB04'           |'R0402'| '(R0402-0201)'                 | '412'     | '1%'    | '1/16W'  | 'IO'       | 'RES CHIP 412 1/16W +-1%(0402)EF'                  | 'CHIPR0402'    | ''          | ''            | '20180208'
 '1K'         | '1%'      | '1/16W'  | '0402LF'  | 'CHIP'   | 'CS21002FB06'(!)        = 'End of Design' | 'Comp-Approve'     | 'CS21002FB06'           |'R0402'| '(R0402-0201)'                 | '1K'      | '1%'    | '1/16W'  | 'DISCRETE' | 'RES CHIP 1K 1/16W +-1%(0402)EF'                   | 'CHIPR0402'    | ''          | ''            | '20180208'
 '1K'         | '1%'      | '1/16W'  | '0402LF'  | 'EMPTY'  | 'CS21002FB06'(!)        = 'End of Design' | 'Comp-Approve'     | 'CS21002FB06'           |'R0402'| '(R0402-0201)'                 | '1K'      | '1%'    | '1/16W'  | 'IO'       | 'RES CHIP 1K 1/16W +-1%(0402)EF'                   | 'CHIPR0402'    | ''          | ''            | '20180208'
 '1.02K'      | '1%'      | '1/16W'  | '0402LF'  | 'CHIP'   | 'CS21022FB03'(!)        = 'End of Design' | 'Comp-Approve'     | 'CS21022FB03'           |'R0402'| '(R0402-0201)'                 | '1.02K'   | '1%'    | '1/16W'  | 'DISCRETE' | 'RES CHIP 1.02K 1/16W +-1%(0402)EF'                | 'CHIPR0402'    | ''          | ''            | '20180208'
 '1.02K'      | '1%'      | '1/16W'  | '0402LF'  | 'EMPTY'  | 'CS21022FB03'(!)        = 'End of Design' | 'Comp-Approve'     | 'CS21022FB03'           |'R0402'| '(R0402-0201)'                 | '1.02K'   | '1%'    | '1/16W'  | 'IO'       | 'RES CHIP 1.02K 1/16W +-1%(0402)EF'                | 'CHIPR0402'    | ''          | ''            | '20180208'
 '1.5K'       | '1%'      | '1/16W'  | '0402LF'  | 'CHIP'   | 'CS21502FB07'(!)        = 'End of Design' | 'Comp-Approve'     | 'CS21502FB07'           |'R0402'| '(R0402-0201)'                 | '1.5K'    | '1%'    | '1/16W'  | 'DISCRETE' | 'RES CHIP 1.5K 1/16W +-1%(0402)EF'                 | 'CHIPR0402'    | ''          | ''            | '20180208'
 '1.5K'       | '1%'      | '1/16W'  | '0402LF'  | 'EMPTY'  | 'CS21502FB07'(!)        = 'End of Design' | 'Comp-Approve'     | 'CS21502FB07'           |'R0402'| '(R0402-0201)'                 | '1.5K'    | '1%'    | '1/16W'  | 'IO'       | 'RES CHIP 1.5K 1/16W +-1%(0402)EF'                 | 'CHIPR0402'    | ''          | ''            | '20180208'
 '4.7K'       | '1%'      | '1/16W'  | '0402LF'  | 'CHIP'   | 'CS24702FB06'(!)        = 'End of Design' | 'Comp-Approve'     | 'CS24702FB06'           |'R0402'| '(R0402-0201)'                 | '4.7K'    | '1%'    | '1/16W'  | 'DISCRETE' | 'RES CHIP 4.7K 1/16W +-1%(0402)EF'                 | 'CHIPR0402'    | ''          | ''            | '20180208'
 '4.7K'       | '1%'      | '1/16W'  | '0402LF'  | 'EMPTY'  | 'CS24702FB06'(!)        = 'End of Design' | 'Comp-Approve'     | 'CS24702FB06'           |'R0402'| '(R0402-0201)'                 | '4.7K'    | '1%'    | '1/16W'  | 'IO'       | 'RES CHIP 4.7K 1/16W +-1%(0402)EF'                 | 'CHIPR0402'    | ''          | ''            | '20180208'
 '5.9K'       | '1%'      | '1/16W'  | '0402LF'  | 'CHIP'   | 'CS25902FB04'(!)        = 'End of Design' | 'Comp-Approve'     | 'CS25902FB04'           |'R0402'| '(R0402-0201)'                 | '5.9K'    | '1%'    | '1/16W'  | 'DISCRETE' | 'RES CHIP 5.9K 1/16W +-1%(0402)EF'                 | 'CHIPR0402'    | ''          | ''            | '20180208'
 '5.9K'       | '1%'      | '1/16W'  | '0402LF'  | 'EMPTY'  | 'CS25902FB04'(!)        = 'End of Design' | 'Comp-Approve'     | 'CS25902FB04'           |'R0402'| '(R0402-0201)'                 | '5.9K'    | '1%'    | '1/16W'  | 'IO'       | 'RES CHIP 5.9K 1/16W +-1%(0402)EF'                 | 'CHIPR0402'    | ''          | ''            | '20180208'
 '7.5K'       | '1%'      | '1/16W'  | '0402LF'  | 'CHIP'   | 'CS27502FB04'(!)        = 'End of Design' | 'Comp-Approve'     | 'CS27502FB04'           |'R0402'| '(R0402-0201)'                 | '7.5K'    | '1%'    | '1/16W'  | 'DISCRETE' | 'RES CHIP 7.5K 1/16W +-1%(0402)EF'                 | 'CHIPR0402'    | ''          | ''            | '20180208'
 '7.5K'       | '1%'      | '1/16W'  | '0402LF'  | 'EMPTY'  | 'CS27502FB04'(!)        = 'End of Design' | 'Comp-Approve'     | 'CS27502FB04'           |'R0402'| '(R0402-0201)'                 | '7.5K'    | '1%'    | '1/16W'  | 'IO'       | 'RES CHIP 7.5K 1/16W +-1%(0402)EF'                 | 'CHIPR0402'    | ''          | ''            | '20180208'
 '10K'        | '1%'      | '1/16W'  | '0402LF'  | 'CHIP'   | 'CS31002FB08'(!)        = 'End of Design' | 'Comp-Approve'     | 'CS31002FB08'           |'R0402'| '(R0402-0201)'                 | '10K'     | '1%'    | '1/16W'  | 'DISCRETE' | 'RES CHIP 10K 1/16W +-1%(0402)EF'                  | 'CHIPR0402'    | ''          | ''            | '20180208'
 '10K'        | '1%'      | '1/16W'  | '0402LF'  | 'EMPTY'  | 'CS31002FB08'(!)        = 'End of Design' | 'Comp-Approve'     | 'CS31002FB08'           |'R0402'| '(R0402-0201)'                 | '10K'     | '1%'    | '1/16W'  | 'IO'       | 'RES CHIP 10K 1/16W +-1%(0402)EF'                  | 'CHIPR0402'    | ''          | ''            | '20180208'
 '10K'        | '5%'      | '1/16W'  | '0402LF'  | 'CHIP'   | 'CS31002JB08'(!)        = 'End of Design' | 'Comp-Approve'     | 'CS31002JB08'           |'R0402'| '(R0402-0201)'                 | '10K'     | '5%'    | '1/16W'  | 'DISCRETE' | 'RES CHIP 10K 1/16W +-5%(0402)EF'                  | 'CHIPR0402'    | ''          | ''            | '20180208'
 '10K'        | '5%'      | '1/16W'  | '0402LF'  | 'EMPTY'  | 'CS31002JB08'(!)        = 'End of Design' | 'Comp-Approve'     | 'CS31002JB08'           |'R0402'| '(R0402-0201)'                 | '10K'     | '5%'    | '1/16W'  | 'IO'       | 'RES CHIP 10K 1/16W +-5%(0402)EF'                  | 'CHIPR0402'    | ''          | ''            | '20180208'
 '20K'        | '1%'      | '1/16W'  | '0402LF'  | 'CHIP'   | 'CS32002FB06'(!)        = 'End of Design' | 'Comp-Approve'     | 'CS32002FB06'           |'R0402'| '(R0402-0201)'                 | '20K'     | '1%'    | '1/16W'  | 'DISCRETE' | 'RES CHIP 20K 1/16W +-1%(0402)EF'                  | 'CHIPR0402'    | ''          | ''            | '20180208'
 '20K'        | '1%'      | '1/16W'  | '0402LF'  | 'EMPTY'  | 'CS32002FB06'(!)        = 'End of Design' | 'Comp-Approve'     | 'CS32002FB06'           |'R0402'| '(R0402-0201)'                 | '20K'     | '1%'    | '1/16W'  | 'IO'       | 'RES CHIP 20K 1/16W +-1%(0402)EF'                  | 'CHIPR0402'    | ''          | ''            | '20180208'
 '22.1K'      | '1%'      | '1/16W'  | '0402LF'  | 'CHIP'   | 'CS32212FB02'(!)        = 'End of Design' | 'Comp-Approve'     | 'CS32212FB02'           |'R0402'| '(R0402-0201)'                 | '22.1K'   | '1%'    | '1/16W'  | 'DISCRETE' | 'RES CHIP 22.1K 1/16W +-1%(0402)EF'                | 'CHIPR0402'    | ''          | ''            | '20180208'
 '22.1K'      | '1%'      | '1/16W'  | '0402LF'  | 'EMPTY'  | 'CS32212FB02'(!)        = 'End of Design' | 'Comp-Approve'     | 'CS32212FB02'           |'R0402'| '(R0402-0201)'                 | '22.1K'   | '1%'    | '1/16W'  | 'IO'       | 'RES CHIP 22.1K 1/16W +-1%(0402)EF'                | 'CHIPR0402'    | ''          | ''            | '20180208'
 '47K'        | '1%'      | '1/16W'  | '0402LF'  | 'CHIP'   | 'CS34702FB01'(!)        = 'End of Design' | 'Comp-Approve'     | 'CS34702FB01'           |'R0402'| '(R0402-0201)'                 | '47K'     | '1%'    | '1/16W'  | 'DISCRETE' | 'RES CHIP 47K 1/16W +-1%(0402)EF'                  | 'CHIPR0402'    | ''          | ''            | '20180208'
 '47K'        | '1%'      | '1/16W'  | '0402LF'  | 'EMPTY'  | 'CS34702FB01'(!)        = 'End of Design' | 'Comp-Approve'     | 'CS34702FB01'           |'R0402'| '(R0402-0201)'                 | '47K'     | '1%'    | '1/16W'  | 'IO'       | 'RES CHIP 47K 1/16W +-1%(0402)EF'                  | 'CHIPR0402'    | ''          | ''            | '20180208'
 '52.3K'      | '1%'      | '1/16W'  | '0402LF'  | 'CHIP'   | 'CS35232FB02'(!)        = 'End of Design' | 'Comp-Approve'     | 'CS35232FB02'           |'R0402'| '(R0402-0201)'                 | '52.3K'   | '1%'    | '1/16W'  | 'DISCRETE' | 'RES CHIP 52.3K 1/16W +-1%(0402)EF'                | 'CHIPR0402'    | ''          | ''            | '20180208'
 '52.3K'      | '1%'      | '1/16W'  | '0402LF'  | 'EMPTY'  | 'CS35232FB02'(!)        = 'End of Design' | 'Comp-Approve'     | 'CS35232FB02'           |'R0402'| '(R0402-0201)'                 | '52.3K'   | '1%'    | '1/16W'  | 'IO'       | 'RES CHIP 52.3K 1/16W +-1%(0402)EF'                | 'CHIPR0402'    | ''          | ''            | '20180208'
 '97.6K'      | '1%'      | '1/16W'  | '0402LF'  | 'CHIP'   | 'CS39762FB02'(!)        = 'End of Design' | 'Comp-Approve'     | 'CS39762FB02'           |'R0402'| '(R0402-0201)'                 | '97.6K'   | '1%'    | '1/16W'  | 'DISCRETE' | 'RES CHIP 97.6K 1/16W +-1%(0402)EF'                | 'CHIPR0402'    | ''          | ''            | '20180208'
 '97.6K'      | '1%'      | '1/16W'  | '0402LF'  | 'EMPTY'  | 'CS39762FB02'(!)        = 'End of Design' | 'Comp-Approve'     | 'CS39762FB02'           |'R0402'| '(R0402-0201)'                 | '97.6K'   | '1%'    | '1/16W'  | 'IO'       | 'RES CHIP 97.6K 1/16W +-1%(0402)EF'                | 'CHIPR0402'    | ''          | ''            | '20180208'
 '100K'       | '1%'      | '1/16W'  | '0402LF'  | 'CHIP'   | 'CS41002FB09'(!)        = 'End of Design' | 'Comp-Approve'     | 'CS41002FB09'           |'R0402'| '(R0402-0201)'                 | '100K'    | '1%'    | '1/16W'  | 'DISCRETE' | 'RES CHIP 100K 1/16W +-1%(0402)EF'                 | 'CHIPR0402'    | ''          | ''            | '20180208'
 '100K'       | '1%'      | '1/16W'  | '0402LF'  | 'EMPTY'  | 'CS41002FB09'(!)        = 'End of Design' | 'Comp-Approve'     | 'CS41002FB09'           |'R0402'| '(R0402-0201)'                 | '100K'    | '1%'    | '1/16W'  | 'IO'       | 'RES CHIP 100K 1/16W +-1%(0402)EF'                 | 'CHIPR0402'    | ''          | ''            | '20180208'
 '130K'       | '1%'      | '1/16W'  | '0402LF'  | 'CHIP'   | 'CS41302FB05'(!)        = 'End of Design' | 'Comp-Release Qty' | 'CS41302FB05'           |'R0402'| '(R0402-0201)'                 | '130K'    | '1%'    | '1/16W'  | 'DISCRETE' | 'RES CHIP 130K 1/16W +-1%(0402)EF'                 | 'CHIPR0402'    | ''          | ''            | '20180208'
 '130K'       | '1%'      | '1/16W'  | '0402LF'  | 'EMPTY'  | 'CS41302FB05'(!)        = 'End of Design' | 'Comp-Release Qty' | 'CS41302FB05'           |'R0402'| '(R0402-0201)'                 | '130K'    | '1%'    | '1/16W'  | 'IO'       | 'RES CHIP 130K 1/16W +-1%(0402)EF'                 | 'CHIPR0402'    | ''          | ''            | '20180208'
 '147K'       | '1%'      | '1/16W'  | '0402LF'  | 'CHIP'   | 'CS41472FB03'(!)        = 'End of Design' | 'Comp-Approve'     | 'CS41472FB03'           |'R0402'| '(R0402-0201)'                 | '147K'    | '1%'    | '1/16W'  | 'DISCRETE' | 'RES CHIP 147K 1/16W +-1%(0402)EF'                 | 'CHIPR0402'    | ''          | ''            | '20180208'
 '147K'       | '1%'      | '1/16W'  | '0402LF'  | 'EMPTY'  | 'CS41472FB03'(!)        = 'End of Design' | 'Comp-Approve'     | 'CS41472FB03'           |'R0402'| '(R0402-0201)'                 | '147K'    | '1%'    | '1/16W'  | 'IO'       | 'RES CHIP 147K 1/16W +-1%(0402)EF'                 | 'CHIPR0402'    | ''          | ''            | '20180208'
 '154K'       | '1%'      | '1/16W'  | '0402LF'  | 'CHIP'   | 'CS41542FB05'(!)        = 'End of Design' | 'Comp-Approve'     | 'CS41542FB05'           |'R0402'| '(R0402-0201)'                 | '154K'    | '1%'    | '1/16W'  | 'DISCRETE' | 'RES CHIP 154K 1/16W +-1%(0402)EF'                 | 'CHIPR0402'    | ''          | ''            | '20180208'
 '154K'       | '1%'      | '1/16W'  | '0402LF'  | 'EMPTY'  | 'CS41542FB05'(!)        = 'End of Design' | 'Comp-Approve'     | 'CS41542FB05'           |'R0402'| '(R0402-0201)'                 | '154K'    | '1%'    | '1/16W'  | 'IO'       | 'RES CHIP 154K 1/16W +-1%(0402)EF'                 | 'CHIPR0402'    | ''          | ''            | '20180208'
 '200K'       | '1%'      | '1/16W'  | '0402LF'  | 'CHIP'   | 'CS42002FB05'(!)        = 'End of Design' | 'Comp-Approve'     | 'CS42002FB05'           |'R0402'| '(R0402-0201)'                 | '200K'    | '1%'    | '1/16W'  | 'DISCRETE' | 'RES CHIP 200K 1/16W +-1%(0402)EF'                 | 'CHIPR0402'    | ''          | ''            | '20180208'
 '200K'       | '1%'      | '1/16W'  | '0402LF'  | 'EMPTY'  | 'CS42002FB05'(!)        = 'End of Design' | 'Comp-Approve'     | 'CS42002FB05'           |'R0402'| '(R0402-0201)'                 | '200K'    | '1%'    | '1/16W'  | 'IO'       | 'RES CHIP 200K 1/16W +-1%(0402)EF'                 | 'CHIPR0402'    | ''          | ''            | '20180208'
 '267K'       | '1%'      | '1/16W'  | '0402LF'  | 'CHIP'   | 'CS42672FB03'(!)        = 'End of Design' | 'Comp-Approve'     | 'CS42672FB03'           |'R0402'| '(R0402-0201)'                 | '267K'    | '1%'    | '1/16W'  | 'DISCRETE' | 'RES CHIP 267K 1/16W +-1%(0402)EF'                 | 'CHIPR0402'    | ''          | ''            | '20180208'
 '267K'       | '1%'      | '1/16W'  | '0402LF'  | 'EMPTY'  | 'CS42672FB03'(!)        = 'End of Design' | 'Comp-Approve'     | 'CS42672FB03'           |'R0402'| '(R0402-0201)'                 | '267K'    | '1%'    | '1/16W'  | 'IO'       | 'RES CHIP 267K 1/16W +-1%(0402)EF'                 | 'CHIPR0402'    | ''          | ''            | '20180208'
 '0'          | '5%'      | '1/10W'  | '0603LF'  | 'CHIP'   | 'CS00003J910'(!)        = 'End of Design' | 'Comp-Approve'     | 'CS00003J910'           |'R0603'| '(SMR0603AW)'                  | '0'       | '5%'    | '1/16W'  | 'DISCRETE' | 'RES CHIP 0 1/10W +-5% (0603)EF'                   | 'CHIPR0603'    | ''          | ''            | '20180208'
 '0'          | '5%'      | '1/10W'  | '0603LF'  | 'EMPTY'  | 'CS00003J910'(!)        = 'End of Design' | 'Comp-Approve'     | 'CS00003J910'           |'R0603'| '(SMR0603AW)'                  | '0'       | '5%'    | '1/16W'  | 'IO'       | 'RES CHIP 0 1/10W +-5% (0603)EF'                   | 'CHIPR0603'    | ''          | ''            | '20180208'
 '200K'       | '0.1%'    | '1/10W'  | '0603LF'  | 'CHIP'   | 'CS42003B902'(!)        = 'End of Design' | 'Comp-Approve'     | 'CS42003B902'           |'R0603_H24'| '(SMR0603AW)'                  | '200K'    | '0.1%'  | '1/10W'  | 'DISCRETE' | 'RES CHIP 200K 1/10W +-0.1%(0603)EF'               | 'CHIPR0603'    | ''          | ''            | '20180213'
 '200K'       | '0.1%'    | '1/10W'  | '0603LF'  | 'EMPTY'  | 'CS42003B902'(!)        = 'End of Design' | 'Comp-Approve'     | 'CS42003B902'           |'R0603_H24'| '(SMR0603AW)'                  | '200K'    | '0.1%'  | '1/10W'  | 'IO'       | 'RES CHIP 200K 1/10W +-0.1%(0603)EF'               | 'CHIPR0603'    | ''          | ''            | '20180213'
 '1'          | '5'       | '1/8W'   | '0805LF'  | 'CHIP'   | 'CS-1004JA02'(!)        = ''              | ''                 | 'CS-1004JA02'           |'R0805_H26'| '(SMR0805AW)'                  | '1'       | '5%'    | '1/8W'   | 'DISCRETE' | 'RES CHIP 1 1/8W +-5%(0805)EF'                     | 'CHIPR0805'    | ''          | ''            | '20180213'
 '1'          | '5'       | '1/8W'   | '0805LF'  | 'EMPTY'  | 'CS-1004JA02'(!)        = ''              | ''                 | 'CS-1004JA02'           |'R0805_H26'| '(SMR0805AW)'                  | '1'       | '5%'    | '1/8W'   | 'IO'       | 'RES CHIP 1 1/8W +-5%(0805)EF'                     | 'CHIPR0805'    | ''          | ''            | '20180213'
 '0.002'      | '1%'      | '2W'     | '2512LF'  | 'CHIP'   | 'CS+002AFR06'(!)        = 'End of Design' | 'Comp-Approve'     | 'CS+002AFR06'           |'R2512XS'| '(SMR2512AW)'                  | '0.002'   | '1%'    | '2W'     | 'DISCRETE' | 'RES CHIP 0.002 2W +-1%(2512)EF'                   | 'CHIPR2512'    | ''          | ''            | '20180213'
 '0.002'      | '1%'      | '2W'     | '2512LF'  | 'EMPTY'  | 'CS+002AFR06'(!)        = 'End of Design' | 'Comp-Approve'     | 'CS+002AFR06'           |'R2512XS'| '(SMR2512AW)'                  | '0.002'   | '1%'    | '2W'     | 'IO'       | 'RES CHIP 0.002 2W +-1%(2512)EF'                   | 'CHIPR2512'    | ''          | ''            | '20180213'
 '20'         | '1%'      | '1/16W'  | '0402LF'  | 'CHIP'   | 'CS02002FB03'(!)        = 'End of Design' | 'Comp-Approve'     | 'CS02002FB03'           |'R0402'| '(R0402-0201)'                 | '20'      | '1%'    | '1/16W'  | 'DISCRETE' | 'RES CHIP 20 1/16W +-1%(0402)EF'                   | 'CHIPR0402'    | ''          | ''            | '20180221'
 '20'         | '1%'      | '1/16W'  | '0402LF'  | 'EMPTY'  | 'CS02002FB03'(!)        = 'End of Design' | 'Comp-Approve'     | 'CS02002FB03'           |'R0402'| '(R0402-0201)'                 | '20'      | '1%'    | '1/16W'  | 'IO'       | 'RES CHIP 20 1/16W +-1%(0402)EF'                   | 'CHIPR0402'    | ''          | ''            | '20180221'
 '22.1'       | '1%'      | '1/16W'  | '0402LF'  | 'CHIP'   | 'CS02212FB02'(!)        = 'End of Design' | 'Comp-Approve'     | 'CS02212FB02'           |'R0402'| '(R0402-0201)'                 | '22.1'    | '1%'    | '1/16W'  | 'DISCRETE' | 'RES CHIP 22.1 1/16W +-1%(0402)EF'                 | 'CHIPR0402'    | ''          | ''            | '20180221'
 '22.1'       | '1%'      | '1/16W'  | '0402LF'  | 'EMPTY'  | 'CS02212FB02'(!)        = 'End of Design' | 'Comp-Approve'     | 'CS02212FB02'           |'R0402'| '(R0402-0201)'                 | '22.1'    | '1%'    | '1/16W'  | 'IO'       | 'RES CHIP 22.1 1/16W +-1%(0402)EF'                 | 'CHIPR0402'    | ''          | ''            | '20180221'
 '27.4'       | '1%'      | '1/16W'  | '0402LF'  | 'CHIP'   | 'CS02742FB03'(!)        = 'End of Design' | 'Comp-Release Qty' | 'CS02742FB03'           |'R0402'| '(R0402-0201)'                 | '27.4'    | '1%'    | '1/16W'  | 'DISCRETE' | 'RES CHIP 27.4 1/16W +-1%(0402)EF'                 | 'CHIPR0402'    | ''          | ''            | '20180221'
 '27.4'       | '1%'      | '1/16W'  | '0402LF'  | 'EMPTY'  | 'CS02742FB03'(!)        = 'End of Design' | 'Comp-Release Qty' | 'CS02742FB03'           |'R0402'| '(R0402-0201)'                 | '27.4'    | '1%'    | '1/16W'  | 'IO'       | 'RES CHIP 27.4 1/16W +-1%(0402)EF'                 | 'CHIPR0402'    | ''          | ''            | '20180221'
 '47'         | '1%'      | '1/16W'  | '0402LF'  | 'CHIP'   | 'CS04702FB03'(!)        = 'End of Design' | 'Comp-Approve'     | 'CS04702FB03'           |'R0402'| '(R0402-0201)'                 | '47'      | '1%'    | '1/16W'  | 'DISCRETE' | 'RES CHIP 47 1/16W +-1% (0402)EF'                  | 'CHIPR0402'    | ''          | ''            | '20180221'
 '47'         | '1%'      | '1/16W'  | '0402LF'  | 'EMPTY'  | 'CS04702FB03'(!)        = 'End of Design' | 'Comp-Approve'     | 'CS04702FB03'           |'R0402'| '(R0402-0201)'                 | '47'      | '1%'    | '1/16W'  | 'IO'       | 'RES CHIP 47 1/16W +-1% (0402)EF'                  | 'CHIPR0402'    | ''          | ''            | '20180221'
 '60.4'       | '1%'      | '1/16W'  | '0402LF'  | 'CHIP'   | 'CS06042FB03'(!)        = 'End of Design' | 'Comp-Approve'     | 'CS06042FB03'           |'R0402'| '(R0402-0201)'                 | '60.4'    | '1%'    | '1/16W'  | 'DISCRETE' | 'RES CHIP 60.4 1/16W +-1%(0402)EF'                 | 'CHIPR0402'    | ''          | ''            | '20180221'
 '60.4'       | '1%'      | '1/16W'  | '0402LF'  | 'EMPTY'  | 'CS06042FB03'(!)        = 'End of Design' | 'Comp-Approve'     | 'CS06042FB03'           |'R0402'| '(R0402-0201)'                 | '60.4'    | '1%'    | '1/16W'  | 'IO'       | 'RES CHIP 60.4 1/16W +-1%(0402)EF'                 | 'CHIPR0402'    | ''          | ''            | '20180221'
 '75'         | '1%'      | '1/16W'  | '0402LF'  | 'CHIP'   | 'CS07502FB04'(!)        = 'End of Design' | 'Comp-Approve'     | 'CS07502FB04'           |'R0402'| '(R0402-0201)'                 | '75'      | '1%'    | '1/16W'  | 'DISCRETE' | 'RES CHIP 75 1/16W +-1%(0402)EF'                   | 'CHIPR0402'    | ''          | ''            | '20180221'
 '75'         | '1%'      | '1/16W'  | '0402LF'  | 'EMPTY'  | 'CS07502FB04'(!)        = 'End of Design' | 'Comp-Approve'     | 'CS07502FB04'           |'R0402'| '(R0402-0201)'                 | '75'      | '1%'    | '1/16W'  | 'IO'       | 'RES CHIP 75 1/16W +-1%(0402)EF'                   | 'CHIPR0402'    | ''          | ''            | '20180221'
 '113'        | '1%'      | '1/16W'  | '0402LF'  | 'CHIP'   | 'CS11132FB02'(!)        = 'End of Design' | 'Comp-Approve'     | 'CS11132FB02'           |'R0402'| '(R0402-0201)'                 | '113'     | '1%'    | '1/16W'  | 'DISCRETE' | 'RES CHIP 113 1/16W +-1%(0402)EF'                  | 'CHIPR0402'    | ''          | ''            | '20180221'
 '113'        | '1%'      | '1/16W'  | '0402LF'  | 'EMPTY'  | 'CS11132FB02'(!)        = 'End of Design' | 'Comp-Approve'     | 'CS11132FB02'           |'R0402'| '(R0402-0201)'                 | '113'     | '1%'    | '1/16W'  | 'IO'       | 'RES CHIP 113 1/16W +-1%(0402)EF'                  | 'CHIPR0402'    | ''          | ''            | '20180221'
 '130'        | '1%'      | '1/16W'  | '0402LF'  | 'CHIP'   | 'CS11302FB03'(!)        = 'End of Design' | 'Comp-Approve'     | 'CS11302FB03'           |'R0402'| '(R0402-0201)'                 | '130'     | '1%'    | '1/16W'  | 'DISCRETE' | 'RES CHIP 130 1/16W +-1%(0402)EF'                  | 'CHIPR0402'    | ''          | ''            | '20180221'
 '130'        | '1%'      | '1/16W'  | '0402LF'  | 'EMPTY'  | 'CS11302FB03'(!)        = 'End of Design' | 'Comp-Approve'     | 'CS11302FB03'           |'R0402'| '(R0402-0201)'                 | '130'     | '1%'    | '1/16W'  | 'IO'       | 'RES CHIP 130 1/16W +-1%(0402)EF'                  | 'CHIPR0402'    | ''          | ''            | '20180221'
 '169'        | '1%'      | '1/16W'  | '0402LF'  | 'CHIP'   | 'CS11692FB01'(!)        = 'End of Design' | 'Comp-Approve'     | 'CS11692FB01'           |'R0402'| '(R0402-0201)'                 | '169'     | '1%'    | '1/16W'  | 'DISCRETE' | 'RES CHIP 169 1/16W +-1%(0402)EF'                  | 'CHIPR0402'    | ''          | ''            | '20180221'
 '169'        | '1%'      | '1/16W'  | '0402LF'  | 'EMPTY'  | 'CS11692FB01'(!)        = 'End of Design' | 'Comp-Approve'     | 'CS11692FB01'           |'R0402'| '(R0402-0201)'                 | '169'     | '1%'    | '1/16W'  | 'IO'       | 'RES CHIP 169 1/16W +-1%(0402)EF'                  | 'CHIPR0402'    | ''          | ''            | '20180221'
 '220'        | '0.1%'    | '1/16W'  | '0402LF'  | 'CHIP'   | 'CS12202BB00'(!)        = 'End of Design' | 'Comp-Approve'     | 'CS12202BB00'           |'R0402'| '(R0402-0201)'                 | '220'     | '0.1%'  | '1/16W'  | 'DISCRETE' | 'RES CHIP 220 1/16W +-0.1%(0402)EF'                | 'CHIPR0402'    | ''          | ''            | '20180221'
 '220'        | '0.1%'    | '1/16W'  | '0402LF'  | 'EMPTY'  | 'CS12202BB00'(!)        = 'End of Design' | 'Comp-Approve'     | 'CS12202BB00'           |'R0402'| '(R0402-0201)'                 | '220'     | '0.1%'  | '1/16W'  | 'IO'       | 'RES CHIP 220 1/16W +-0.1%(0402)EF'                | 'CHIPR0402'    | ''          | ''            | '20180221'
 '240'        | '1%'      | '1/16W'  | '0402LF'  | 'CHIP'   | 'CS12402FB01'(!)        = 'End of Design' | 'Comp-Approve'     | 'CS12402FB01'           |'R0402'| '(R0402-0201)'                 | '240'     | '1%'    | '1/16W'  | 'DISCRETE' | 'RES CHIP 240 1/16W +-1%(0402)EF'                  | 'CHIPR0402'    | ''          | ''            | '20180221'
 '240'        | '1%'      | '1/16W'  | '0402LF'  | 'EMPTY'  | 'CS12402FB01'(!)        = 'End of Design' | 'Comp-Approve'     | 'CS12402FB01'           |'R0402'| '(R0402-0201)'                 | '240'     | '1%'    | '1/16W'  | 'IO'       | 'RES CHIP 240 1/16W +-1%(0402)EF'                  | 'CHIPR0402'    | ''          | ''            | '20180221'
 '332'        | '1%'      | '1/16W'  | '0402LF'  | 'CHIP'   | 'CS13322FB05'(!)        = 'End of Design' | 'Comp-Approve'     | 'CS13322FB05'           |'R0402'| '(R0402-0201)'                 | '332'     | '1%'    | '1/16W'  | 'DISCRETE' | 'RES CHIP 332 1/16W +-1%(0402)EF'                  | 'CHIPR0402'    | ''          | ''            | '20180221'
 '332'        | '1%'      | '1/16W'  | '0402LF'  | 'EMPTY'  | 'CS13322FB05'(!)        = 'End of Design' | 'Comp-Approve'     | 'CS13322FB05'           |'R0402'| '(R0402-0201)'                 | '332'     | '1%'    | '1/16W'  | 'IO'       | 'RES CHIP 332 1/16W +-1%(0402)EF'                  | 'CHIPR0402'    | ''          | ''            | '20180221'
 '348'        | '1%'      | '1/16W'  | '0402LF'  | 'CHIP'   | 'CS13482FB02'(!)        = 'End of Design' | 'Comp-Approve'     | 'CS13482FB02'           |'R0402'| '(R0402-0201)'                 | '348'     | '1%'    | '1/16W'  | 'DISCRETE' | 'RES CHIP 348 1/16W +-1%(0402)EF'                  | 'CHIPR0402'    | ''          | ''            | '20180221'
 '348'        | '1%'      | '1/16W'  | '0402LF'  | 'EMPTY'  | 'CS13482FB02'(!)        = 'End of Design' | 'Comp-Approve'     | 'CS13482FB02'           |'R0402'| '(R0402-0201)'                 | '348'     | '1%'    | '1/16W'  | 'IO'       | 'RES CHIP 348 1/16W +-1%(0402)EF'                  | 'CHIPR0402'    | ''          | ''            | '20180221'
 '402'        | '1%'      | '1/16W'  | '0402LF'  | 'CHIP'   | 'CS14022FB02'(!)        = 'End of Design' | 'Comp-Approve'     | 'CS14022FB02'           |'R0402'| '(R0402-0201)'                 | '402'     | '1%'    | '1/16W'  | 'DISCRETE' | 'RES CHIP 402 1/16W +-1%(0402)EF'                  | 'CHIPR0402'    | ''          | ''            | '20180221'
 '402'        | '1%'      | '1/16W'  | '0402LF'  | 'EMPTY'  | 'CS14022FB02'(!)        = 'End of Design' | 'Comp-Approve'     | 'CS14022FB02'           |'R0402'| '(R0402-0201)'                 | '402'     | '1%'    | '1/16W'  | 'IO'       | 'RES CHIP 402 1/16W +-1%(0402)EF'                  | 'CHIPR0402'    | ''          | ''            | '20180221'
 '475'        | '1%'      | '1/16W'  | '0402LF'  | 'CHIP'   | 'CS14752FB04'(!)        = 'End of Design' | 'Comp-Approve'     | 'CS14752FB04'           |'R0402'| '(R0402-0201)'                 | '475'     | '1%'    | '1/16W'  | 'DISCRETE' | 'RES CHIP 475 1/16W +-1%(0402)EF'                  | 'CHIPR0402'    | ''          | ''            | '20180221'
 '475'        | '1%'      | '1/16W'  | '0402LF'  | 'EMPTY'  | 'CS14752FB04'(!)        = 'End of Design' | 'Comp-Approve'     | 'CS14752FB04'           |'R0402'| '(R0402-0201)'                 | '475'     | '1%'    | '1/16W'  | 'IO'       | 'RES CHIP 475 1/16W +-1%(0402)EF'                  | 'CHIPR0402'    | ''          | ''            | '20180221'
 '499'        | '1%'      | '1/16W'  | '0402LF'  | 'CHIP'   | 'CS14992FB06'(!)        = 'End of Design' | 'Comp-Approve'     | 'CS14992FB06'           |'R0402'| '(R0402-0201)'                 | '499'     | '1%'    | '1/16W'  | 'DISCRETE' | 'RES CHIP 499 1/16W +-1%(0402)EF'                  | 'CHIPR0402'    | ''          | ''            | '20180221'
 '499'        | '1%'      | '1/16W'  | '0402LF'  | 'EMPTY'  | 'CS14992FB06'(!)        = 'End of Design' | 'Comp-Approve'     | 'CS14992FB06'           |'R0402'| '(R0402-0201)'                 | '499'     | '1%'    | '1/16W'  | 'IO'       | 'RES CHIP 499 1/16W +-1%(0402)EF'                  | 'CHIPR0402'    | ''          | ''            | '20180221'
 '511'        | '1%'      | '1/16W'  | '0402LF'  | 'CHIP'   | 'CS15112FB03'(!)        = 'End of Design' | 'Comp-Approve'     | 'CS15112FB03'           |'R0402'| '(R0402-0201)'                 | '511'     | '1%'    | '1/16W'  | 'DISCRETE' | 'RES CHIP 511 1/16W +-1%(0402)EF'                  | 'CHIPR0402'    | ''          | ''            | '20180221'
 '511'        | '1%'      | '1/16W'  | '0402LF'  | 'EMPTY'  | 'CS15112FB03'(!)        = 'End of Design' | 'Comp-Approve'     | 'CS15112FB03'           |'R0402'| '(R0402-0201)'                 | '511'     | '1%'    | '1/16W'  | 'IO'       | 'RES CHIP 511 1/16W +-1%(0402)EF'                  | 'CHIPR0402'    | ''          | ''            | '20180221'
 '665'        | '1%'      | '1/16W'  | '0402LF'  | 'CHIP'   | 'CS16652FB00'(!)        = 'End of Design' | 'Comp-Approve'     | 'CS16652FB00'           |'R0402'| '(R0402-0201)'                 | '665'     | '1%'    | '1/16W'  | 'DISCRETE' | 'RES CHIP 665 1/16W +-1%(0402)EF'                  | 'CHIPR0402'    | ''          | ''            | '20180221'
 '665'        | '1%'      | '1/16W'  | '0402LF'  | 'EMPTY'  | 'CS16652FB00'(!)        = 'End of Design' | 'Comp-Approve'     | 'CS16652FB00'           |'R0402'| '(R0402-0201)'                 | '665'     | '1%'    | '1/16W'  | 'IO'       | 'RES CHIP 665 1/16W +-1%(0402)EF'                  | 'CHIPR0402'    | ''          | ''            | '20180221'
 '845'        | '1%'      | '1/16W'  | '0402LF'  | 'CHIP'   | 'CS18452FB01'(!)        = 'End of Design' | 'Comp-Approve'     | 'CS18452FB01'           |'R0402'| '(R0402-0201)'                 | '845'     | '1%'    | '1/16W'  | 'DISCRETE' | 'RES CHIP 845 1/16W +-1%(0402)EF'                  | 'CHIPR0402'    | ''          | ''            | '20180221'
 '845'        | '1%'      | '1/16W'  | '0402LF'  | 'EMPTY'  | 'CS18452FB01'(!)        = 'End of Design' | 'Comp-Approve'     | 'CS18452FB01'           |'R0402'| '(R0402-0201)'                 | '845'     | '1%'    | '1/16W'  | 'IO'       | 'RES CHIP 845 1/16W +-1%(0402)EF'                  | 'CHIPR0402'    | ''          | ''            | '20180221'
 '2'          | '1%'      | '1/16W'  | '0402LF'  | 'CHIP'   | 'CS-2002FB02'(!)        = 'End of Design' | 'Comp-Approve'     | 'CS-2002FB02'           |'R0402'| '(R0402-0201)'                 | '2'       | '1%'    | '1/16W'  | 'DISCRETE' | 'RES CHIP 2 1/16W +-1%(0402)EF'                    | 'CHIPR0402'    | ''          | ''            | '20180221'
 '2'          | '1%'      | '1/16W'  | '0402LF'  | 'EMPTY'  | 'CS-2002FB02'(!)        = 'End of Design' | 'Comp-Approve'     | 'CS-2002FB02'           |'R0402'| '(R0402-0201)'                 | '2'       | '1%'    | '1/16W'  | 'IO'       | 'RES CHIP 2 1/16W +-1%(0402)EF'                    | 'CHIPR0402'    | ''          | ''            | '20180221'
 '1K'         | '0.1%'    | '1/16W'  | '0402LF'  | 'CHIP'   | 'CS21002BB05'(!)        = 'End of Design' | 'Comp-Approve'     | 'CS21002BB05'           |'R0402'| '(R0402-0201)'                 | '1K'      | '0.1%'  | '1/16W'  | 'DISCRETE' | 'RES CHIP 1K 1/16W +-0.1%(0402)EF'                 | 'CHIPR0402'    | ''          | ''            | '20180221'
 '1K'         | '0.1%'    | '1/16W'  | '0402LF'  | 'EMPTY'  | 'CS21002BB05'(!)        = 'End of Design' | 'Comp-Approve'     | 'CS21002BB05'           |'R0402'| '(R0402-0201)'                 | '1K'      | '0.1%'  | '1/16W'  | 'IO'       | 'RES CHIP 1K 1/16W +-0.1%(0402)EF'                 | 'CHIPR0402'    | ''          | ''            | '20180221'
 '1.21K'      | '1%'      | '1/16W'  | '0402LF'  | 'CHIP'   | 'CS21212FB05'(!)        = 'End of Design' | 'Comp-Approve'     | 'CS21212FB05'           |'R0402'| '(R0402-0201)'                 | '1.21K'   | '1%'    | '1/16W'  | 'DISCRETE' | 'RES CHIP 1.21K 1/16W +-1%(0402)EF'                | 'CHIPR0402'    | ''          | ''            | '20180221'
 '1.21K'      | '1%'      | '1/16W'  | '0402LF'  | 'EMPTY'  | 'CS21212FB05'(!)        = 'End of Design' | 'Comp-Approve'     | 'CS21212FB05'           |'R0402'| '(R0402-0201)'                 | '1.21K'   | '1%'    | '1/16W'  | 'IO'       | 'RES CHIP 1.21K 1/16W +-1%(0402)EF'                | 'CHIPR0402'    | ''          | ''            | '20180221'
 '1.82K'      | '1%'      | '1/16W'  | '0402LF'  | 'CHIP'   | 'CS21822FB03'(!)        = 'End of Design' | 'Comp-Approve'     | 'CS21822FB03'           |'R0402'| '(R0402-0201)'                 | '1.82K'   | '1%'    | '1/16W'  | 'DISCRETE' | 'RES CHIP 1.82K 1/16W +-1%(0402)EF'                | 'CHIPR0402'    | ''          | ''            | '20180221'
 '1.82K'      | '1%'      | '1/16W'  | '0402LF'  | 'EMPTY'  | 'CS21822FB03'(!)        = 'End of Design' | 'Comp-Approve'     | 'CS21822FB03'           |'R0402'| '(R0402-0201)'                 | '1.82K'   | '1%'    | '1/16W'  | 'IO'       | 'RES CHIP 1.82K 1/16W +-1%(0402)EF'                | 'CHIPR0402'    | ''          | ''            | '20180221'
 '2K'         | '1%'      | '1/16W'  | '0402LF'  | 'CHIP'   | 'CS22002FB07'(!)        = 'End of Design' | 'Comp-Approve'     | 'CS22002FB07'           |'R0402'| '(R0402-0201)'                 | '2K'      | '1%'    | '1/16W'  | 'DISCRETE' | 'RES CHIP 2K 1/16W +-1%(0402)EF'                   | 'CHIPR0402'    | ''          | ''            | '20180221'
 '2K'         | '1%'      | '1/16W'  | '0402LF'  | 'EMPTY'  | 'CS22002FB07'(!)        = 'End of Design' | 'Comp-Approve'     | 'CS22002FB07'           |'R0402'| '(R0402-0201)'                 | '2K'      | '1%'    | '1/16W'  | 'IO'       | 'RES CHIP 2K 1/16W +-1%(0402)EF'                   | 'CHIPR0402'    | ''          | ''            | '20180221'
 '2.21K'      | '1%'      | '1/16W'  | '0402LF'  | 'CHIP'   | 'CS22212FB06'(!)        = 'End of Design' | 'Comp-Approve'     | 'CS22212FB06'           |'R0402'| '(R0402-0201)'                 | '2.21K'   | '1%'    | '1/16W'  | 'DISCRETE' | 'RES CHIP 2.21K 1/16W +-1%(0402)EF'                | 'CHIPR0402'    | ''          | ''            | '20180221'
 '2.21K'      | '1%'      | '1/16W'  | '0402LF'  | 'EMPTY'  | 'CS22212FB06'(!)        = 'End of Design' | 'Comp-Approve'     | 'CS22212FB06'           |'R0402'| '(R0402-0201)'                 | '2.21K'   | '1%'    | '1/16W'  | 'IO'       | 'RES CHIP 2.21K 1/16W +-1%(0402)EF'                | 'CHIPR0402'    | ''          | ''            | '20180221'
 '2.49K'      | '1%'      | '1/16W'  | '0402LF'  | 'CHIP'   | 'CS22492FB05'(!)        = 'End of Design' | 'Comp-Approve'     | 'CS22492FB05'           |'R0402'| '(R0402-0201)'                 | '2.49K'   | '1%'    | '1/16W'  | 'DISCRETE' | 'RES CHIP 2.49K 1/16W +-1%(0402)EF'                | 'CHIPR0402'    | ''          | ''            | '20180221'
 '2.49K'      | '1%'      | '1/16W'  | '0402LF'  | 'EMPTY'  | 'CS22492FB05'(!)        = 'End of Design' | 'Comp-Approve'     | 'CS22492FB05'           |'R0402'| '(R0402-0201)'                 | '2.49K'   | '1%'    | '1/16W'  | 'IO'       | 'RES CHIP 2.49K 1/16W +-1%(0402)EF'                | 'CHIPR0402'    | ''          | ''            | '20180221'
 '2.87K'      | '1%'      | '1/16W'  | '0402LF'  | 'CHIP'   | 'CS22872FB03'(!)        = 'End of Design' | 'Comp-Approve'     | 'CS22872FB03'           |'R0402'| '(R0402-0201)'                 | '2.87K'   | '1%'    | '1/16W'  | 'DISCRETE' | 'RES CHIP 2.87K 1/16W +-1%(0402)EF'                | 'CHIPR0402'    | ''          | ''            | '20180221'
 '2.87K'      | '1%'      | '1/16W'  | '0402LF'  | 'EMPTY'  | 'CS22872FB03'(!)        = 'End of Design' | 'Comp-Approve'     | 'CS22872FB03'           |'R0402'| '(R0402-0201)'                 | '2.87K'   | '1%'    | '1/16W'  | 'IO'       | 'RES CHIP 2.87K 1/16W +-1%(0402)EF'                | 'CHIPR0402'    | ''          | ''            | '20180221'
 '3.16K'      | '1%'      | '1/16W'  | '0402LF'  | 'CHIP'   | 'CS23162FB03'(!)        = 'End of Design' | 'Comp-Approve'     | 'CS23162FB03'           |'R0402'| '(R0402-0201)'                 | '3.16K'   | '1%'    | '1/16W'  | 'DISCRETE' | 'RES CHIP 3.16K 1/16W +-1%(0402)EF'                | 'CHIPR0402'    | ''          | ''            | '20180221'
 '3.16K'      | '1%'      | '1/16W'  | '0402LF'  | 'EMPTY'  | 'CS23162FB03'(!)        = 'End of Design' | 'Comp-Approve'     | 'CS23162FB03'           |'R0402'| '(R0402-0201)'                 | '3.16K'   | '1%'    | '1/16W'  | 'IO'       | 'RES CHIP 3.16K 1/16W +-1%(0402)EF'                | 'CHIPR0402'    | ''          | ''            | '20180221'
 '4.02K'      | '1%'      | '1/16W'  | '0402LF'  | 'CHIP'   | 'CS24022FB04'(!)        = 'End of Design' | 'Comp-Approve'     | 'CS24022FB04'           |'R0402'| '(R0402-0201)'                 | '4.02K'   | '1%'    | '1/16W'  | 'DISCRETE' | 'RES CHIP 4.02K 1/16W +-1%(0402)EF'                | 'CHIPR0402'    | ''          | ''            | '20180221'
 '4.02K'      | '1%'      | '1/16W'  | '0402LF'  | 'EMPTY'  | 'CS24022FB04'(!)        = 'End of Design' | 'Comp-Approve'     | 'CS24022FB04'           |'R0402'| '(R0402-0201)'                 | '4.02K'   | '1%'    | '1/16W'  | 'IO'       | 'RES CHIP 4.02K 1/16W +-1%(0402)EF'                | 'CHIPR0402'    | ''          | ''            | '20180221'
 '4.75K'      | '0.1%'    | '1/16W'  | '0402LF'  | 'CHIP'   | 'CS24752BB02'(!)        = 'End of Design' | 'Comp-Approve'     | 'CS24752BB02'           |'R0402'| '(R0402-0201)'                 | '4.75K'   | '0.1%'  | '1/16W'  | 'DISCRETE' | 'RES CHIP 4.75K 1/16W +-0.1%(0402)EF'              | 'CHIPR0402'    | ''          | ''            | '20180221'
 '4.75K'      | '0.1%'    | '1/16W'  | '0402LF'  | 'EMPTY'  | 'CS24752BB02'(!)        = 'End of Design' | 'Comp-Approve'     | 'CS24752BB02'           |'R0402'| '(R0402-0201)'                 | '4.75K'   | '0.1%'  | '1/16W'  | 'IO'       | 'RES CHIP 4.75K 1/16W +-0.1%(0402)EF'              | 'CHIPR0402'    | ''          | ''            | '20180221'
 '4.87K'      | '1%'      | '1/16W'  | '0402LF'  | 'CHIP'   | 'CS24872FB01'(!)        = 'End of Design' | 'Comp-Approve'     | 'CS24872FB01'           |'R0402'| '(R0402-0201)'                 | '4.87K'   | '1%'    | '1/16W'  | 'DISCRETE' | 'RES CHIP 4.87K 1/16W +-1%(0402)EF'                | 'CHIPR0402'    | ''          | ''            | '20180221'
 '4.87K'      | '1%'      | '1/16W'  | '0402LF'  | 'EMPTY'  | 'CS24872FB01'(!)        = 'End of Design' | 'Comp-Approve'     | 'CS24872FB01'           |'R0402'| '(R0402-0201)'                 | '4.87K'   | '1%'    | '1/16W'  | 'IO'       | 'RES CHIP 4.87K 1/16W +-1%(0402)EF'                | 'CHIPR0402'    | ''          | ''            | '20180221'
 '6.19K'      | '1%'      | '1/16W'  | '0402LF'  | 'CHIP'   | 'CS26192FB03'(!)        = 'End of Design' | 'Comp-Approve'     | 'CS26192FB03'           |'R0402'| '(R0402-0201)'                 | '6.19K'   | '1%'    | '1/16W'  | 'DISCRETE' | 'RES CHIP 6.19K 1/16W +-1%(0402)EF'                | 'CHIPR0402'    | ''          | ''            | '20180221'
 '6.19K'      | '1%'      | '1/16W'  | '0402LF'  | 'EMPTY'  | 'CS26192FB03'(!)        = 'End of Design' | 'Comp-Approve'     | 'CS26192FB03'           |'R0402'| '(R0402-0201)'                 | '6.19K'   | '1%'    | '1/16W'  | 'IO'       | 'RES CHIP 6.19K 1/16W +-1%(0402)EF'                | 'CHIPR0402'    | ''          | ''            | '20180221'
 '6.65K'      | '1%'      | '1/16W'  | '0402LF'  | 'CHIP'   | 'CS26652FB04'(!)        = 'End of Design' | 'Comp-Approve'     | 'CS26652FB04'           |'R0402'| '(R0402-0201)'                 | '6.65K'   | '1%'    | '1/16W'  | 'DISCRETE' | 'RES CHIP 6.65K 1/16W +-1%(0402)EF'                | 'CHIPR0402'    | ''          | ''            | '20180221'
 '6.65K'      | '1%'      | '1/16W'  | '0402LF'  | 'EMPTY'  | 'CS26652FB04'(!)        = 'End of Design' | 'Comp-Approve'     | 'CS26652FB04'           |'R0402'| '(R0402-0201)'                 | '6.65K'   | '1%'    | '1/16W'  | 'IO'       | 'RES CHIP 6.65K 1/16W +-1%(0402)EF'                | 'CHIPR0402'    | ''          | ''            | '20180221'
 '6.81K'      | '1%'      | '1/16W'  | '0402LF'  | 'CHIP'   | 'CS26812FB04'(!)        = ''              | ''                 | 'CS26812FB04'           |'R0402'| '(R0402-0201)'                 | '6.81K'   | '1%'    | '1/16W'  | 'DISCRETE' | 'RES CHIP 6.81K 1/16W +-1%(0402)EF'                | 'CHIPR0402'    | ''          | ''            | '20180221'
 '6.81K'      | '1%'      | '1/16W'  | '0402LF'  | 'EMPTY'  | 'CS26812FB04'(!)        = ''              | ''                 | 'CS26812FB04'           |'R0402'| '(R0402-0201)'                 | '6.81K'   | '1%'    | '1/16W'  | 'IO'       | 'RES CHIP 6.81K 1/16W +-1%(0402)EF'                | 'CHIPR0402'    | ''          | ''            | '20180221'
 '8.25K'      | '1%'      | '1/16W'  | '0402LF'  | 'CHIP'   | 'CS28252FB03'(!)        = 'End of Design' | 'Comp-Approve'     | 'CS28252FB03'           |'R0402'| '(R0402-0201)'                 | '8.25K'   | '1%'    | '1/16W'  | 'DISCRETE' | 'RES CHIP 8.25K 1/16W +-1%(0402)EF'                | 'CHIPR0402'    | ''          | ''            | '20180221'
 '8.25K'      | '1%'      | '1/16W'  | '0402LF'  | 'EMPTY'  | 'CS28252FB03'(!)        = 'End of Design' | 'Comp-Approve'     | 'CS28252FB03'           |'R0402'| '(R0402-0201)'                 | '8.25K'   | '1%'    | '1/16W'  | 'IO'       | 'RES CHIP 8.25K 1/16W +-1%(0402)EF'                | 'CHIPR0402'    | ''          | ''            | '20180221'
 '9.31K'      | '1%'      | '1/16W'  | '0402LF'  | 'CHIP'   | 'CS29312FB02'(!)        = 'End of Design' | 'Comp-Approve'     | 'CS29312FB02'           |'R0402'| '(R0402-0201)'                 | '9.31K'   | '1%'    | '1/16W'  | 'DISCRETE' | 'RES CHIP 9.31K 1/16W +-1%(0402)EF'                | 'CHIPR0402'    | ''          | ''            | '20180221'
 '9.31K'      | '1%'      | '1/16W'  | '0402LF'  | 'EMPTY'  | 'CS29312FB02'(!)        = 'End of Design' | 'Comp-Approve'     | 'CS29312FB02'           |'R0402'| '(R0402-0201)'                 | '9.31K'   | '1%'    | '1/16W'  | 'IO'       | 'RES CHIP 9.31K 1/16W +-1%(0402)EF'                | 'CHIPR0402'    | ''          | ''            | '20180221'
 '11K'        | '1%'      | '1/16W'  | '0402LF'  | 'CHIP'   | 'CS31102FB05'(!)        = 'End of Design' | 'Comp-Approve'     | 'CS31102FB05'           |'R0402'| '(R0402-0201)'                 | '11K'     | '1%'    | '1/16W'  | 'DISCRETE' | 'RES CHIP 11K 1/16W +-1%(0402)EF'                  | 'CHIPR0402'    | ''          | ''            | '20180221'
 '11K'        | '1%'      | '1/16W'  | '0402LF'  | 'EMPTY'  | 'CS31102FB05'(!)        = 'End of Design' | 'Comp-Approve'     | 'CS31102FB05'           |'R0402'| '(R0402-0201)'                 | '11K'     | '1%'    | '1/16W'  | 'IO'       | 'RES CHIP 11K 1/16W +-1%(0402)EF'                  | 'CHIPR0402'    | ''          | ''            | '20180221'
 '11.5K'      | '1%'      | '1/16W'  | '0402LF'  | 'CHIP'   | 'CS31152FB03'(!)        = 'End of Design' | 'Comp-Approve'     | 'CS31152FB03'           |'R0402'| '(R0402-0201)'                 | '11.5K'   | '1%'    | '1/16W'  | 'DISCRETE' | 'RES CHIP 11.5K 1/16W +-1%(0402)EF'                | 'CHIPR0402'    | ''          | ''            | '20180221'
 '11.5K'      | '1%'      | '1/16W'  | '0402LF'  | 'EMPTY'  | 'CS31152FB03'(!)        = 'End of Design' | 'Comp-Approve'     | 'CS31152FB03'           |'R0402'| '(R0402-0201)'                 | '11.5K'   | '1%'    | '1/16W'  | 'IO'       | 'RES CHIP 11.5K 1/16W +-1%(0402)EF'                | 'CHIPR0402'    | ''          | ''            | '20180221'
 '11.8K'      | '1%'      | '1/16W'  | '0402LF'  | 'CHIP'   | 'CS31182FB03'(!)        = 'End of Design' | 'Comp-Approve'     | 'CS31182FB03'           |'R0402'| '(R0402-0201)'                 | '11.8K'   | '1%'    | '1/16W'  | 'DISCRETE' | 'RES CHIP 11.8K 1/16W +-1%(0402)EF'                | 'CHIPR0402'    | ''          | ''            | '20180221'
 '11.8K'      | '1%'      | '1/16W'  | '0402LF'  | 'EMPTY'  | 'CS31182FB03'(!)        = 'End of Design' | 'Comp-Approve'     | 'CS31182FB03'           |'R0402'| '(R0402-0201)'                 | '11.8K'   | '1%'    | '1/16W'  | 'IO'       | 'RES CHIP 11.8K 1/16W +-1%(0402)EF'                | 'CHIPR0402'    | ''          | ''            | '20180221'
 '12K'        | '1%'      | '1/16W'  | '0402LF'  | 'CHIP'   | 'CS31202FB04'(!)        = 'End of Design' | 'Comp-Approve'     | 'CS31202FB04'           |'R0402'| '(R0402-0201)'                 | '12K'     | '1%'    | '1/16W'  | 'DISCRETE' | 'RES CHIP 12K 1/16W +-1%(0402)EF'                  | 'CHIPR0402'    | ''          | ''            | '20180221'
 '12K'        | '1%'      | '1/16W'  | '0402LF'  | 'EMPTY'  | 'CS31202FB04'(!)        = 'End of Design' | 'Comp-Approve'     | 'CS31202FB04'           |'R0402'| '(R0402-0201)'                 | '12K'     | '1%'    | '1/16W'  | 'IO'       | 'RES CHIP 12K 1/16W +-1%(0402)EF'                  | 'CHIPR0402'    | ''          | ''            | '20180221'
 '12.1K'      | '1%'      | '1/16W'  | '0402LF'  | 'CHIP'   | 'CS31212FB05'(!)        = 'End of Design' | 'Comp-Approve'     | 'CS31212FB05'           |'R0402'| '(R0402-0201)'                 | '12.1K'   | '1%'    | '1/16W'  | 'DISCRETE' | 'RES CHIP 12.1K 1/16W +-1%(0402)EF'                | 'CHIPR0402'    | ''          | ''            | '20180221'
 '12.1K'      | '1%'      | '1/16W'  | '0402LF'  | 'EMPTY'  | 'CS31212FB05'(!)        = 'End of Design' | 'Comp-Approve'     | 'CS31212FB05'           |'R0402'| '(R0402-0201)'                 | '12.1K'   | '1%'    | '1/16W'  | 'IO'       | 'RES CHIP 12.1K 1/16W +-1%(0402)EF'                | 'CHIPR0402'    | ''          | ''            | '20180221'
 '12.4K'      | '1%'      | '1/16W'  | '0402LF'  | 'CHIP'   | 'CS31242FB02'(!)        = 'End of Design' | 'Comp-Approve'     | 'CS31242FB02'           |'R0402'| '(R0402-0201)'                 | '12.4K'   | '1%'    | '1/16W'  | 'DISCRETE' | 'RES CHIP 12.4K 1/16W +-1%(0402)EF'                | 'CHIPR0402'    | ''          | ''            | '20180221'
 '12.4K'      | '1%'      | '1/16W'  | '0402LF'  | 'EMPTY'  | 'CS31242FB02'(!)        = 'End of Design' | 'Comp-Approve'     | 'CS31242FB02'           |'R0402'| '(R0402-0201)'                 | '12.4K'   | '1%'    | '1/16W'  | 'IO'       | 'RES CHIP 12.4K 1/16W +-1%(0402)EF'                | 'CHIPR0402'    | ''          | ''            | '20180221'
 '13K'        | '1%'      | '1/16W'  | '0402LF'  | 'CHIP'   | 'CS31302FB04'(!)        = 'End of Design' | 'Comp-Approve'     | 'CS31302FB04'           |'R0402'| '(R0402-0201)'                 | '13K'     | '1%'    | '1/16W'  | 'DISCRETE' | 'RES CHIP 13K 1/16W +-1%(0402)EF'                  | 'CHIPR0402'    | ''          | ''            | '20180221'
 '13K'        | '1%'      | '1/16W'  | '0402LF'  | 'EMPTY'  | 'CS31302FB04'(!)        = 'End of Design' | 'Comp-Approve'     | 'CS31302FB04'           |'R0402'| '(R0402-0201)'                 | '13K'     | '1%'    | '1/16W'  | 'IO'       | 'RES CHIP 13K 1/16W +-1%(0402)EF'                  | 'CHIPR0402'    | ''          | ''            | '20180221'
 '14K'        | '1%'      | '1/16W'  | '0402LF'  | 'CHIP'   | 'CS31402FB03'(!)        = 'End of Design' | 'Comp-Approve'     | 'CS31402FB03'           |'R0402'| '(R0402-0201)'                 | '14K'     | '1%'    | '1/16W'  | 'DISCRETE' | 'RES CHIP 14K 1/16W +-1%(0402)EF'                  | 'CHIPR0402'    | ''          | ''            | '20180221'
 '14K'        | '1%'      | '1/16W'  | '0402LF'  | 'EMPTY'  | 'CS31402FB03'(!)        = 'End of Design' | 'Comp-Approve'     | 'CS31402FB03'           |'R0402'| '(R0402-0201)'                 | '14K'     | '1%'    | '1/16W'  | 'IO'       | 'RES CHIP 14K 1/16W +-1%(0402)EF'                  | 'CHIPR0402'    | ''          | ''            | '20180221'
 '14.3K'      | '1%'      | '1/16W'  | '0402LF'  | 'CHIP'   | 'CS31432FB02'(!)        = 'End of Design' | 'Comp-Approve'     | 'CS31432FB02'           |'R0402'| '(R0402-0201)'                 | '14.3K'   | '1%'    | '1/16W'  | 'DISCRETE' | 'RES CHIP 14.3K 1/16W +-1%(0402)EF'                | 'CHIPR0402'    | ''          | ''            | '20180221'
 '14.3K'      | '1%'      | '1/16W'  | '0402LF'  | 'EMPTY'  | 'CS31432FB02'(!)        = 'End of Design' | 'Comp-Approve'     | 'CS31432FB02'           |'R0402'| '(R0402-0201)'                 | '14.3K'   | '1%'    | '1/16W'  | 'IO'       | 'RES CHIP 14.3K 1/16W +-1%(0402)EF'                | 'CHIPR0402'    | ''          | ''            | '20180221'
 '15K'        | '0.1%'    | '1/16W'  | '0402LF'  | 'CHIP'   | 'CS31502BB03'(!)        = 'End of Design' | 'Comp-Approve'     | 'CS31502BB03'           |'R0402'| '(R0402-0201)'                 | '15K'     | '0.1%'  | '1/16W'  | 'DISCRETE' | 'RES CHIP 15K  1/16W +-0.1%(0402)EF'               | 'CHIPR0402'    | ''          | ''            | '20180221'
 '15K'        | '0.1%'    | '1/16W'  | '0402LF'  | 'EMPTY'  | 'CS31502BB03'(!)        = 'End of Design' | 'Comp-Approve'     | 'CS31502BB03'           |'R0402'| '(R0402-0201)'                 | '15K'     | '0.1%'  | '1/16W'  | 'IO'       | 'RES CHIP 15K  1/16W +-0.1%(0402)EF'               | 'CHIPR0402'    | ''          | ''            | '20180221'
 '15.8K'      | '1%'      | '1/16W'  | '0402LF'  | 'CHIP'   | 'CS31582FB02'(!)        = 'End of Design' | 'Comp-Approve'     | 'CS31582FB02'           |'R0402'| '(R0402-0201)'                 | '15.8K'   | '1%'    | '1/16W'  | 'DISCRETE' | 'RES CHIP 15.8K 1/16W +-1% (0402)EF'               | 'CHIPR0402'    | ''          | ''            | '20180221'
 '15.8K'      | '1%'      | '1/16W'  | '0402LF'  | 'EMPTY'  | 'CS31582FB02'(!)        = 'End of Design' | 'Comp-Approve'     | 'CS31582FB02'           |'R0402'| '(R0402-0201)'                 | '15.8K'   | '1%'    | '1/16W'  | 'IO'       | 'RES CHIP 15.8K 1/16W +-1% (0402)EF'               | 'CHIPR0402'    | ''          | ''            | '20180221'
 '16.5K'      | '1%'      | '1/16W'  | '0402LF'  | 'CHIP'   | 'CS31652FB05'(!)        = 'End of Design' | 'Comp-Approve'     | 'CS31652FB05'           |'R0402'| '(R0402-0201)'                 | '16.5K'   | '1%'    | '1/16W'  | 'DISCRETE' | 'RES CHIP 16.5K 1/16W +-1%(0402)EF'                | 'CHIPR0402'    | ''          | ''            | '20180221'
 '16.5K'      | '1%'      | '1/16W'  | '0402LF'  | 'EMPTY'  | 'CS31652FB05'(!)        = 'End of Design' | 'Comp-Approve'     | 'CS31652FB05'           |'R0402'| '(R0402-0201)'                 | '16.5K'   | '1%'    | '1/16W'  | 'IO'       | 'RES CHIP 16.5K 1/16W +-1%(0402)EF'                | 'CHIPR0402'    | ''          | ''            | '20180221'
 '22K'        | '1%'      | '1/16W'  | '0402LF'  | 'CHIP'   | 'CS32202FB02'(!)        = 'End of Design' | 'Comp-Approve'     | 'CS32202FB02'           |'R0402'| '(R0402-0201)'                 | '22K'     | '1%'    | '1/16W'  | 'DISCRETE' | 'RES CHIP 22K 1/16W +-1%(0402)EF'                  | 'CHIPR0402'    | ''          | ''            | '20180221'
 '22K'        | '1%'      | '1/16W'  | '0402LF'  | 'EMPTY'  | 'CS32202FB02'(!)        = 'End of Design' | 'Comp-Approve'     | 'CS32202FB02'           |'R0402'| '(R0402-0201)'                 | '22K'     | '1%'    | '1/16W'  | 'IO'       | 'RES CHIP 22K 1/16W +-1%(0402)EF'                  | 'CHIPR0402'    | ''          | ''            | '20180221'
 '24.9K'      | '1%'      | '1/16W'  | '0402LF'  | 'CHIP'   | 'CS32492FB04'(!)        = 'End of Design' | 'Comp-Approve'     | 'CS32492FB04'           |'R0402'| '(R0402-0201)'                 | '24.9K'   | '1%'    | '1/16W'  | 'DISCRETE' | 'RES CHIP 24.9K 1/16W +-1%(0402)EF'                | 'CHIPR0402'    | ''          | ''            | '20180221'
 '24.9K'      | '1%'      | '1/16W'  | '0402LF'  | 'EMPTY'  | 'CS32492FB04'(!)        = 'End of Design' | 'Comp-Approve'     | 'CS32492FB04'           |'R0402'| '(R0402-0201)'                 | '24.9K'   | '1%'    | '1/16W'  | 'IO'       | 'RES CHIP 24.9K 1/16W +-1%(0402)EF'                | 'CHIPR0402'    | ''          | ''            | '20180221'
 '25.5K'      | '1%'      | '1/16W'  | '0402LF'  | 'CHIP'   | 'CS32552FB06'(!)        = 'End of Design' | 'Comp-Approve'     | 'CS32552FB06'           |'R0402'| '(R0402-0201)'                 | '25.5K'   | '1%'    | '1/16W'  | 'DISCRETE' | 'RES CHIP 25.5K 1/16W +-1%(0402)EF'                | 'CHIPR0402'    | ''          | ''            | '20180221'
 '25.5K'      | '1%'      | '1/16W'  | '0402LF'  | 'EMPTY'  | 'CS32552FB06'(!)        = 'End of Design' | 'Comp-Approve'     | 'CS32552FB06'           |'R0402'| '(R0402-0201)'                 | '25.5K'   | '1%'    | '1/16W'  | 'IO'       | 'RES CHIP 25.5K 1/16W +-1%(0402)EF'                | 'CHIPR0402'    | ''          | ''            | '20180221'
 '26.1K'      | '1%'      | '1/16W'  | '0402LF'  | 'CHIP'   | 'CS32612FB02'(!)        = 'End of Design' | 'Comp-Approve'     | 'CS32612FB02'           |'R0402'| '(R0402-0201)'                 | '26.1K'   | '1%'    | '1/16W'  | 'DISCRETE' | 'RES CHIP 26.1K 1/16W +-1%(0402)EF'                | 'CHIPR0402'    | ''          | ''            | '20180221'
 '26.1K'      | '1%'      | '1/16W'  | '0402LF'  | 'EMPTY'  | 'CS32612FB02'(!)        = 'End of Design' | 'Comp-Approve'     | 'CS32612FB02'           |'R0402'| '(R0402-0201)'                 | '26.1K'   | '1%'    | '1/16W'  | 'IO'       | 'RES CHIP 26.1K 1/16W +-1%(0402)EF'                | 'CHIPR0402'    | ''          | ''            | '20180221'
 '27.4K'      | '1%'      | '1/16W'  | '0402LF'  | 'CHIP'   | 'CS32742FB04'(!)        = 'End of Design' | 'Comp-Approve'     | 'CS32742FB04'           |'R0402'| '(R0402-0201)'                 | '27.4K'   | '1%'    | '1/16W'  | 'DISCRETE' | 'RES CHIP 27.4K 1/16W +-1%(0402)EF'                | 'CHIPR0402'    | ''          | ''            | '20180221'
 '27.4K'      | '1%'      | '1/16W'  | '0402LF'  | 'EMPTY'  | 'CS32742FB04'(!)        = 'End of Design' | 'Comp-Approve'     | 'CS32742FB04'           |'R0402'| '(R0402-0201)'                 | '27.4K'   | '1%'    | '1/16W'  | 'IO'       | 'RES CHIP 27.4K 1/16W +-1%(0402)EF'                | 'CHIPR0402'    | ''          | ''            | '20180221'
 '33K'        | '1%'      | '1/16W'  | '0402LF'  | 'CHIP'   | 'CS33302FB00'(!)        = ''              | ''                 | 'CS33302FB00'           |'R0402'| '(R0402-0201)'                 | '33K'     | '1%'    | '1/16W'  | 'DISCRETE' | 'RES CHIP 33K 1/16W +-1%(0402)EF'                  | 'CHIPR0402'    | ''          | ''            | '20180221'
 '33K'        | '1%'      | '1/16W'  | '0402LF'  | 'EMPTY'  | 'CS33302FB00'(!)        = ''              | ''                 | 'CS33302FB00'           |'R0402'| '(R0402-0201)'                 | '33K'     | '1%'    | '1/16W'  | 'IO'       | 'RES CHIP 33K 1/16W +-1%(0402)EF'                  | 'CHIPR0402'    | ''          | ''            | '20180221'
 '35.7K'      | '1%'      | '1/16W'  | '0402LF'  | 'CHIP'   | 'CS33572FB01'(!)        = 'End of Design' | 'Comp-Approve'     | 'CS33572FB01'           |'R0402'| '(R0402-0201)'                 | '35.7K'   | '1%'    | '1/16W'  | 'DISCRETE' | 'RES CHIP 35.7K 1/16W +-1%(0402) EF'               | 'CHIPR0402'    | ''          | ''            | '20180221'
 '35.7K'      | '1%'      | '1/16W'  | '0402LF'  | 'EMPTY'  | 'CS33572FB01'(!)        = 'End of Design' | 'Comp-Approve'     | 'CS33572FB01'           |'R0402'| '(R0402-0201)'                 | '35.7K'   | '1%'    | '1/16W'  | 'IO'       | 'RES CHIP 35.7K 1/16W +-1%(0402) EF'               | 'CHIPR0402'    | ''          | ''            | '20180221'
 '39.2K'      | '1%'      | '1/16W'  | '0402LF'  | 'CHIP'   | 'CS33922FB05'(!)        = 'End of Design' | 'Comp-Approve'     | 'CS33922FB05'           |'R0402'| '(R0402-0201)'                 | '39.2K'   | '1%'    | '1/16W'  | 'DISCRETE' | 'RES CHIP 39.2K 1/16W +-1%(0402)EF'                | 'CHIPR0402'    | ''          | ''            | '20180221'
 '39.2K'      | '1%'      | '1/16W'  | '0402LF'  | 'EMPTY'  | 'CS33922FB05'(!)        = 'End of Design' | 'Comp-Approve'     | 'CS33922FB05'           |'R0402'| '(R0402-0201)'                 | '39.2K'   | '1%'    | '1/16W'  | 'IO'       | 'RES CHIP 39.2K 1/16W +-1%(0402)EF'                | 'CHIPR0402'    | ''          | ''            | '20180221'
 '43.2K'      | '1%'      | '1/16W'  | '0402LF'  | 'CHIP'   | 'CS34322FB03'(!)        = 'End of Design' | 'Comp-Approve'     | 'CS34322FB03'           |'R0402'| '(R0402-0201)'                 | '43.2K'   | '1%'    | '1/16W'  | 'DISCRETE' | 'RES CHIP 43.2K 1/16W +-1%(0402)EF'                | 'CHIPR0402'    | ''          | ''            | '20180221'
 '43.2K'      | '1%'      | '1/16W'  | '0402LF'  | 'EMPTY'  | 'CS34322FB03'(!)        = 'End of Design' | 'Comp-Approve'     | 'CS34322FB03'           |'R0402'| '(R0402-0201)'                 | '43.2K'   | '1%'    | '1/16W'  | 'IO'       | 'RES CHIP 43.2K 1/16W +-1%(0402)EF'                | 'CHIPR0402'    | ''          | ''            | '20180221'
 '44.2K'      | '1%'      | '1/16W'  | '0402LF'  | 'CHIP'   | 'CS34422FB04'(!)        = 'End of Design' | 'Comp-Approve'     | 'CS34422FB04'           |'R0402'| '(R0402-0201)'                 | '44.2K'   | '1%'    | '1/16W'  | 'DISCRETE' | 'RES CHIP 44.2K 1/16W +-1%(0402)EF'                | 'CHIPR0402'    | ''          | ''            | '20180221'
 '44.2K'      | '1%'      | '1/16W'  | '0402LF'  | 'EMPTY'  | 'CS34422FB04'(!)        = 'End of Design' | 'Comp-Approve'     | 'CS34422FB04'           |'R0402'| '(R0402-0201)'                 | '44.2K'   | '1%'    | '1/16W'  | 'IO'       | 'RES CHIP 44.2K 1/16W +-1%(0402)EF'                | 'CHIPR0402'    | ''          | ''            | '20180221'
 '47.5K'      | '1%'      | '1/16W'  | '0402LF'  | 'CHIP'   | 'CS34752FB03'(!)        = 'End of Design' | 'Comp-Approve'     | 'CS34752FB03'           |'R0402'| '(R0402-0201)'                 | '47.5K'   | '1%'    | '1/16W'  | 'DISCRETE' | 'RES CHIP 47.5K 1/16W +-1%(0402)EF'                | 'CHIPR0402'    | ''          | ''            | '20180221'
 '47.5K'      | '1%'      | '1/16W'  | '0402LF'  | 'EMPTY'  | 'CS34752FB03'(!)        = 'End of Design' | 'Comp-Approve'     | 'CS34752FB03'           |'R0402'| '(R0402-0201)'                 | '47.5K'   | '1%'    | '1/16W'  | 'IO'       | 'RES CHIP 47.5K 1/16W +-1%(0402)EF'                | 'CHIPR0402'    | ''          | ''            | '20180221'
 '51.1K'      | '1%'      | '1/16W'  | '0402LF'  | 'CHIP'   | 'CS35112FB03'(!)        = 'End of Design' | 'Comp-Approve'     | 'CS35112FB03'           |'R0402'| '(R0402-0201)'                 | '51.1K'   | '1%'    | '1/16W'  | 'DISCRETE' | 'RES CHIP 51.1K 1/16W +-1%(0402)EF'                | 'CHIPR0402'    | ''          | ''            | '20180221'
 '51.1K'      | '1%'      | '1/16W'  | '0402LF'  | 'EMPTY'  | 'CS35112FB03'(!)        = 'End of Design' | 'Comp-Approve'     | 'CS35112FB03'           |'R0402'| '(R0402-0201)'                 | '51.1K'   | '1%'    | '1/16W'  | 'IO'       | 'RES CHIP 51.1K 1/16W +-1%(0402)EF'                | 'CHIPR0402'    | ''          | ''            | '20180221'
 '54.9K'      | '1%'      | '1/16W'  | '0402LF'  | 'CHIP'   | 'CS35492FB03'(!)        = 'End of Design' | 'Comp-Approve'     | 'CS35492FB03'           |'R0402'| '(R0402-0201)'                 | '54.9K'   | '1%'    | '1/16W'  | 'DISCRETE' | 'RES CHIP 54.9K 1/16W  +-1%(0402)EF'               | 'CHIPR0402'    | ''          | ''            | '20180221'
 '54.9K'      | '1%'      | '1/16W'  | '0402LF'  | 'EMPTY'  | 'CS35492FB03'(!)        = 'End of Design' | 'Comp-Approve'     | 'CS35492FB03'           |'R0402'| '(R0402-0201)'                 | '54.9K'   | '1%'    | '1/16W'  | 'IO'       | 'RES CHIP 54.9K 1/16W  +-1%(0402)EF'               | 'CHIPR0402'    | ''          | ''            | '20180221'
 '64.9K'      | '1%'      | '1/16W'  | '0402LF'  | 'CHIP'   | 'CS36492FB02'(!)        = 'End of Design' | 'Comp-Approve'     | 'CS36492FB02'           |'R0402'| '(R0402-0201)'                 | '64.9K'   | '1%'    | '1/16W'  | 'DISCRETE' | 'RES CHIP 64.9K 1/16W +-1%(0402)EF'                | 'CHIPR0402'    | ''          | ''            | '20180221'
 '64.9K'      | '1%'      | '1/16W'  | '0402LF'  | 'EMPTY'  | 'CS36492FB02'(!)        = 'End of Design' | 'Comp-Approve'     | 'CS36492FB02'           |'R0402'| '(R0402-0201)'                 | '64.9K'   | '1%'    | '1/16W'  | 'IO'       | 'RES CHIP 64.9K 1/16W +-1%(0402)EF'                | 'CHIPR0402'    | ''          | ''            | '20180221'
 '66.5K'      | '1%'      | '1/16W'  | '0402LF'  | 'CHIP'   | 'CS36652FB03'(!)        = 'End of Design' | 'Comp-Approve'     | 'CS36652FB03'           |'R0402'| '(R0402-0201)'                 | '66.5K'   | '1%'    | '1/16W'  | 'DISCRETE' | 'RES CHIP 66.5K 1/16W +-1%(0402)EF'                | 'CHIPR0402'    | ''          | ''            | '20180221'
 '66.5K'      | '1%'      | '1/16W'  | '0402LF'  | 'EMPTY'  | 'CS36652FB03'(!)        = 'End of Design' | 'Comp-Approve'     | 'CS36652FB03'           |'R0402'| '(R0402-0201)'                 | '66.5K'   | '1%'    | '1/16W'  | 'IO'       | 'RES CHIP 66.5K 1/16W +-1%(0402)EF'                | 'CHIPR0402'    | ''          | ''            | '20180221'
 '86.6K'      | '1%'      | '1/16W'  | '0402LF'  | 'CHIP'   | 'CS38662FB05'(!)        = 'End of Design' | 'Comp-Approve'     | 'CS38662FB05'           |'R0402'| '(R0402-0201)'                 | '86.6K'   | '1%'    | '1/16W'  | 'DISCRETE' | 'RES CHIP 86.6K 1/16W +-1%(0402)EF'                | 'CHIPR0402'    | ''          | ''            | '20180221'
 '86.6K'      | '1%'      | '1/16W'  | '0402LF'  | 'EMPTY'  | 'CS38662FB05'(!)        = 'End of Design' | 'Comp-Approve'     | 'CS38662FB05'           |'R0402'| '(R0402-0201)'                 | '86.6K'   | '1%'    | '1/16W'  | 'IO'       | 'RES CHIP 86.6K 1/16W +-1%(0402)EF'                | 'CHIPR0402'    | ''          | ''            | '20180221'
 '121K'       | '1%'      | '1/16W'  | '0402LF'  | 'CHIP'   | 'CS41212FB02'(!)        = 'End of Design' | 'Comp-Approve'     | 'CS41212FB02'           |'R0402'| '(R0402-0201)'                 | '121K'    | '1%'    | '1/16W'  | 'DISCRETE' | 'RES CHIP 121K 1/16W +-1%(0402)EF'                 | 'CHIPR0402'    | ''          | ''            | '20180221'
 '121K'       | '1%'      | '1/16W'  | '0402LF'  | 'EMPTY'  | 'CS41212FB02'(!)        = 'End of Design' | 'Comp-Approve'     | 'CS41212FB02'           |'R0402'| '(R0402-0201)'                 | '121K'    | '1%'    | '1/16W'  | 'IO'       | 'RES CHIP 121K 1/16W +-1%(0402)EF'                 | 'CHIPR0402'    | ''          | ''            | '20180221'
 '137K'       | '1%'      | '1/16W'  | '0402LF'  | 'CHIP'   | 'CS41372FB01'(!)        = 'End of Design' | 'Comp-Approve'     | 'CS41372FB01'           |'R0402'| '(R0402-0201)'                 | '137K'    | '1%'    | '1/16W'  | 'DISCRETE' | 'RES CHIP 137K 1/16W +-1%(0402)EF'                 | 'CHIPR0402'    | ''          | ''            | '20180221'
 '137K'       | '1%'      | '1/16W'  | '0402LF'  | 'EMPTY'  | 'CS41372FB01'(!)        = 'End of Design' | 'Comp-Approve'     | 'CS41372FB01'           |'R0402'| '(R0402-0201)'                 | '137K'    | '1%'    | '1/16W'  | 'IO'       | 'RES CHIP 137K 1/16W +-1%(0402)EF'                 | 'CHIPR0402'    | ''          | ''            | '20180221'
 '150K'       | '1%'      | '1/16W'  | '0402LF'  | 'CHIP'   | 'CS41502FB04'(!)        = 'End of Design' | 'Comp-Approve'     | 'CS41502FB04'           |'R0402'| '(R0402-0201)'                 | '150K'    | '1%'    | '1/16W'  | 'DISCRETE' | 'RES CHIP 150K 1/16W +-1%(0402)EF'                 | 'CHIPR0402'    | ''          | ''            | '20180221'
 '150K'       | '1%'      | '1/16W'  | '0402LF'  | 'EMPTY'  | 'CS41502FB04'(!)        = 'End of Design' | 'Comp-Approve'     | 'CS41502FB04'           |'R0402'| '(R0402-0201)'                 | '150K'    | '1%'    | '1/16W'  | 'IO'       | 'RES CHIP 150K 1/16W +-1%(0402)EF'                 | 'CHIPR0402'    | ''          | ''            | '20180221'
 '510K'       | '5%'      | '1/16W'  | '0402LF'  | 'CHIP'   | 'CS45102JB03'(!)        = 'End of Design' | 'Comp-Approve'     | 'CS45102JB03'           |'R0402'| '(R0402-0201)'                 | '510K'    | '5%'    | '1/16W'  | 'DISCRETE' | 'RES CHIP 510K 1/16W +-5%(0402)EF'                 | 'CHIPR0402'    | ''          | ''            | '20180221'
 '510K'       | '5%'      | '1/16W'  | '0402LF'  | 'EMPTY'  | 'CS45102JB03'(!)        = 'End of Design' | 'Comp-Approve'     | 'CS45102JB03'           |'R0402'| '(R0402-0201)'                 | '510K'    | '5%'    | '1/16W'  | 'IO'       | 'RES CHIP 510K 1/16W +-5%(0402)EF'                 | 'CHIPR0402'    | ''          | ''            | '20180221'
 '1M'         | '1%'      | '1/16W'  | '0402LF'  | 'CHIP'   | 'CS51002FB05'(!)        = 'End of Design' | 'Comp-Approve'     | 'CS51002FB05'           |'R0402'| '(R0402-0201)'                 | '1M'      | '1%'    | '1/16W'  | 'DISCRETE' | 'RES CHIP 1M 1/16W +-1%(0402)EF'                   | 'CHIPR0402'    | ''          | ''            | '20180221'
 '1M'         | '1%'      | '1/16W'  | '0402LF'  | 'EMPTY'  | 'CS51002FB05'(!)        = 'End of Design' | 'Comp-Approve'     | 'CS51002FB05'           |'R0402'| '(R0402-0201)'                 | '1M'      | '1%'    | '1/16W'  | 'IO'       | 'RES CHIP 1M 1/16W +-1%(0402)EF'                   | 'CHIPR0402'    | ''          | ''            | '20180221'
 '2.2'        | '1%'      | '1/10W'  | '0603LF'  | 'CHIP'   | 'CS-2203F902'(!)        = 'End of Design' | 'Comp-Approve'     | 'CS-2203F902'           |'R0603'| '(SMR0603AW)'                  | '2.2'     | '1%'    | '1/10W'  | 'DISCRETE' | 'RES CHIP 2.2 1/10W +-1%(0603)EF'                  | 'CHIPR0603'    | ''          | ''            | '20180221'
 '2.2'        | '1%'      | '1/10W'  | '0603LF'  | 'EMPTY'  | 'CS-2203F902'(!)        = 'End of Design' | 'Comp-Approve'     | 'CS-2203F902'           |'R0603'| '(SMR0603AW)'                  | '2.2'     | '1%'    | '1/10W'  | 'IO'       | 'RES CHIP 2.2 1/10W +-1%(0603)EF'                  | 'CHIPR0603'    | ''          | ''            | '20180221'
 '10M'        | '1%'      | '1/10W'  | '0603LF'  | 'CHIP'   | 'CS61003F901'(!)        = 'End of Design' | 'Comp-Approve'     | 'CS61003F901'           |'R0603'| '(SMR0603AW)'                  | '10M'     | '1%'    | '1/10W'  | 'DISCRETE' | 'RES CHIP 10M 1/10W +-1%(0603)EF'                  | 'CHIPR0603'    | ''          | ''            | '20180221'
 '10M'        | '1%'      | '1/10W'  | '0603LF'  | 'EMPTY'  | 'CS61003F901'(!)        = 'End of Design' | 'Comp-Approve'     | 'CS61003F901'           |'R0603'| '(SMR0603AW)'                  | '10M'     | '1%'    | '1/10W'  | 'IO'       | 'RES CHIP 10M 1/10W +-1%(0603)EF'                  | 'CHIPR0603'    | ''          | ''            | '20180221'
 '0'          | ''        | '1/2W'   | '1206LF'  | 'CHIP'   | 'CS00007T200'(!)        = 'End of Design' | 'Comp-Approve'     | 'CS00007T200'           |'R1206XI'| '(SMRR1206AW)'                 | '0'       | ''      | '1/2W'   | 'DISCRETE' | 'RES CHIP 0 1/2W (1206)EF'                         | 'CHIPR1206'    | ''          | ''            | '20180221'
 '0'          | ''        | '1/2W'   | '1206LF'  | 'EMPTY'  | 'CS00007T200'(!)        = 'End of Design' | 'Comp-Approve'     | 'CS00007T200'           |'R1206XI'| '(SMRR1206AW)'                 | '0'       | ''      | '1/2W'   | 'IO'       | 'RES CHIP 0 1/2W (1206)EF'                         | 'CHIPR1206'    | ''          | ''            | '20180221'
 '51.1'       | '1%'      | '1/16W'  | '0402LF'  | 'CHIP'   | 'CS05112FB05'(!)        = 'End of Design' | 'Comp-Approve'     | 'CS05112FB05'           |'R0402'| '(R0402-0201)'                 | '51.1'    | '1%'    | '1/16W'  | 'DISCRETE' | 'RES CHIP 51.1 1/16W +-1%(0402)EF'                 | 'CHIPR0402'    | ''          | ''            | '20180221'
 '51.1'       | '1%'      | '1/16W'  | '0402LF'  | 'EMPTY'  | 'CS05112FB05'(!)        = 'End of Design' | 'Comp-Approve'     | 'CS05112FB05'           |'R0402'| '(R0402-0201)'                 | '51.1'    | '1%'    | '1/16W'  | 'IO'       | 'RES CHIP 51.1 1/16W +-1%(0402)EF'                 | 'CHIPR0402'    | ''          | ''            | '20180221'
 '1'          | '1%'      | '1/16W'  | '0402LF'  | 'CHIP'   | 'CS-1002FB04'(!)        = 'End of Design' | 'Comp-Approve'     | 'CS-1002FB04'           |'R0402'| '(R0402-0201)'                 | '1'       | '1%'    | '1/16W'  | 'DISCRETE' | 'RES CHIP 1 1/16W +-1%(0402)EF'                    | 'CHIPR0402'    | ''          | ''            | '20180221'
 '1'          | '1%'      | '1/16W'  | '0402LF'  | 'EMPTY'  | 'CS-1002FB04'(!)        = 'End of Design' | 'Comp-Approve'     | 'CS-1002FB04'           |'R0402'| '(R0402-0201)'                 | '1'       | '1%'    | '1/16W'  | 'IO'       | 'RES CHIP 1 1/16W +-1%(0402)EF'                    | 'CHIPR0402'    | ''          | ''            | '20180221'
 '4.7'        | '5%'      | '1/16W'  | '0402LF'  | 'CHIP'   | 'CS-4702JB29'(!)        = 'End of Design' | 'Comp-Approve'     | 'CS-4702JB29'           |'R0402'| '(R0402-0201)'                 | '4.7'     | '5%'    | '1/16W'  | 'DISCRETE' | 'RES CHIP 4.7 1/16W +-5% (0402)'                   | 'CHIPR0402'    | ''          | ''            | '20180305'
 '4.7'        | '5%'      | '1/16W'  | '0402LF'  | 'EMPTY'  | 'CS-4702JB29'(!)        = 'End of Design' | 'Comp-Approve'     | 'CS-4702JB29'           |'R0402'| '(R0402-0201)'                 | '4.7'     | '5%'    | '1/16W'  | 'IO'       | 'RES CHIP 4.7 1/16W +-5% (0402)'                   | 'CHIPR0402'    | ''          | ''            | '20180305'
 '8.66K'      | '1%'      | '1/10W'  | '0603LF'  | 'CHIP'   | 'CS28663F911'(!)        = ''              | ''                 | 'CS28663F911'           |'R0603'| '(SMR0603AW)'                  | '8.66K'   | '1%'    | '1/10W'  | 'DISCRETE' | 'RES CHIP 8.66K 1/10W +-1% (0603)'                 | 'CHIP0603'     | ''          | ''            | '20180313'
 '8.66K'      | '1%'      | '1/10W'  | '0603LF'  | 'EMPTY'  | 'CS28663F911'(!)        = ''              | ''                 | 'CS28663F911'           |'R0603'| '(SMR0603AW)'                  | '8.66K'   | '1%'    | '1/10W'  | 'IO'       | 'RES CHIP 8.66K 1/10W +-1% (0603)'                 | 'CHIP0603'     | ''          | ''            | '20180313'
 '11.2K'      | '1%'      | '1/16W'  | '0402LF'  | 'CHIP'   | 'CS31122FB11'(!)        = 'End of Design' | 'Comp-Approve'     | 'CS31122FB11'           |'R0402'| '(R0402-0201)'                 | '11.2K'   | '1%'    | '1/16W'  | 'DISCRETE' | 'RES CHIP 11.2K 1/16W +-1% (0402)'                 | 'CHIP0402'     | ''          | ''            | '20180313'
 '11.2K'      | '1%'      | '1/16W'  | '0402LF'  | 'EMPTY'  | 'CS31122FB11'(!)        = 'End of Design' | 'Comp-Approve'     | 'CS31122FB11'           |'R0402'| '(R0402-0201)'                 | '11.2K'   | '1%'    | '1/16W'  | 'IO'       | 'RES CHIP 11.2K 1/16W +-1% (0402)'                 | 'CHIP0402'     | ''          | ''            | '20180313'
 '40.2K'      | '1%'      | '1/10W'  | '0603LF ' | 'CHIP'   | 'CS34023F911'(!)        = ''              | ''                 | 'CS34023F911'           |'R0603'| '(SMR0603AW)'                  | '40.2K'   | '1%'    | '1/10W'  | 'DISCRETE' | 'RESISTOR CHIP 40.2K 1/10W +-1%(0603)'             | 'CHIPR0603'    | ''          | ''            | '20180319'
 '40.2K'      | '1%'      | '1/10W'  | '0603LF ' | 'EMPTY'  | 'CS34023F911'(!)        = ''              | ''                 | 'CS34023F911'           |'R0603'| '(SMR0603AW)'                  | '40.2K'   | '1%'    | '1/10W'  | 'IO'       | 'RESISTOR CHIP 40.2K 1/10W +-1%(0603)'             | 'CHIPR0603'    | ''          | ''            | '20180319'
 '562'        | '1%'      | '1/16W'  | '0402LF'  | 'CHIP'   | 'CS15622FB16'(!)        = 'End of Design' | 'Comp-Approve'     | 'CS15622FB16'           |'R0402'| '(R0402-0201)'                 | '562'     | '1%'    | '1/16W'  | 'DISCRETE' | 'RES CHIP 562 1/16W +-1% (0402)'                   | 'CHIPR0402'    | ''          | ''            | '20180328'
 '562'        | '1%'      | '1/16W'  | '0402LF'  | 'EMPTY'  | 'CS15622FB16'(!)        = 'End of Design' | 'Comp-Approve'     | 'CS15622FB16'           |'R0402'| '(R0402-0201)'                 | '562'     | '1%'    | '1/16W'  | 'IO'       | 'RES CHIP 562 1/16W +-1% (0402)'                   | 'CHIPR0402'    | ''          | ''            | '20180328'
 '62K'        | '1%'      | '1/16W'  | '0402LF'  | 'CHIP'   | 'CS36202FB19'(!)        = 'End of Design' | 'Comp-Approve'     | 'CS36202FB19'           |'R0402'| '(R0402-0201)'                 | '62K'     | '1%'    | '1/16W'  | 'DISCRETE' | 'RES CHIP 62K 1/16W +-1%(0402)'                    | 'CHIPR0402'    | ''          | ''            | '20180316'
 '62K'        | '1%'      | '1/16W'  | '0402LF'  | 'EMPTY'  | 'CS36202FB19'(!)        = 'End of Design' | 'Comp-Approve'     | 'CS36202FB19'           |'R0402'| '(R0402-0201)'                 | '62K'     | '1%'    | '1/16W'  | 'IO'       | 'RES CHIP 62K 1/16W +-1%(0402)'                    | 'CHIPR0402'    | ''          | ''            | '20180316'
 '78.7K'      | '1%'      | '1/16W'  | '0402LF'  | 'CHIP'   | 'CS37872FB15'(!)        = 'End of Design' | 'Comp-Approve'     | 'CS37872FB15'           |'R0402'| '(R0402-0201)'                 | '78.7K'   | '1%'    | '1/16W'  | 'DISCRETE' | 'RES CHIP 78.7K 1/16W +-1%(0402)'                  | 'CHIPR0402'    | ''          | ''            | '20180402'
 '78.7K'      | '1%'      | '1/16W'  | '0402LF'  | 'EMPTY'  | 'CS37872FB15'(!)        = 'End of Design' | 'Comp-Approve'     | 'CS37872FB15'           |'R0402'| '(R0402-0201)'                 | '78.7K'   | '1%'    | '1/16W'  | 'IO'       | 'RES CHIP 78.7K 1/16W +-1%(0402)'                  | 'CHIPR0402'    | ''          | ''            | '20180402'
 '267K'       | '0.1%'    | '1/16W'  | '0402LF'  | 'CHIP'   | 'CS42672BB00'(!)        = ''              | ''                 | 'CS42672BB00'           |'R0402'| '(R0402-0201)'                 | '267K'    | '0.1%'  | '1/16W'  | 'DISCRETE' | 'RES CHIP 267K 1/16W +-0.1%(0402)'                 | 'CHIPR0402'    | ''          | ''            | '20180418'
 '267K'       | '0.1%'    | '1/16W'  | '0402LF'  | 'EMPTY'  | 'CS42672BB00'(!)        = ''              | ''                 | 'CS42672BB00'           |'R0402'| '(R0402-0201)'                 | '267K'    | '0.1%'  | '1/16W'  | 'IO'       | 'RES CHIP 267K 1/16W +-0.1%(0402)'                 | 'CHIPR0402'    | ''          | ''            | '20180418'
 '549'        | '1%'      | '1/4W'   | '1206LF'  | 'CHIP'   | 'CS15496F200'(!)        = ''              | ''                 | 'CS15496F200'           |'R1206XF'| '(SMR1206AW)'                  | '549'     | '1%'    | '1/4W'   | 'DISCRETE' | 'RES CHIP 549 1/4W 1%(1206)'                       | 'CHIPR1206'    | ''          | ''            | '20180418'
 '549'        | '1%'      | '1/4W'   | '1206LF'  | 'EMPTY'  | 'CS15496F200'(!)        = ''              | ''                 | 'CS15496F200'           |'R1206XF'| '(SMR1206AW)'                  | '549'     | '1%'    | '1/4W'   | 'IO'       | 'RES CHIP 549 1/4W 1%(1206)'                       | 'CHIPR1206'    | ''          | ''            | '20180418'
 '243K'       | '1%'      | '1/16W'  | '0402LF'  | 'CHIP'   | 'CS42432FB02'(!)        = 'End of Design' | 'Comp-Approve'     | 'CS42432FB02'           |'R0402'| '(R0402-0201)'                 | '243K'    | '1%'    | '1/16W'  | 'DISCRETE' | 'RES CHIP 243K 1/16W +-1%(0402)'                   | 'CHIPR0402'    | ''          | ''            | '20180420'
 '243K'       | '1%'      | '1/16W'  | '0402LF'  | 'EMPTY'  | 'CS42432FB02'(!)        = 'End of Design' | 'Comp-Approve'     | 'CS42432FB02'           |'R0402'| '(R0402-0201)'                 | '243K'    | '1%'    | '1/16W'  | 'IO'       | 'RES CHIP 243K 1/16W +-1%(0402)'                   | 'CHIPR0402'    | ''          | ''            | '20180420'
 '147K'       | '1%'      | '1/8W'   | '0805LF'  | 'CHIP'   | 'CS41474FA00'(!)        = ''              | ''                 | 'CS41474FA00'           |'R0805'| '(SMR0805AW)'                  | '147K'    | '1%'    | '1/8W'   | 'DISCRETE' | 'RES CHIP 147K 1/8W +-1%(0805)'                    | 'CHIPR0805'    | ''          | ''            | '20180424'
 '147K'       | '1%'      | '1/8W'   | '0805LF'  | 'EMPTY'  | 'CS41474FA00'(!)        = ''              | ''                 | 'CS41474FA00'           |'R0805'| '(SMR0805AW)'                  | '147K'    | '1%'    | '1/8W'   | 'IO'       | 'RES CHIP 147K 1/8W +-1%(0805)'                    | 'CHIPR0805'    | ''          | ''            | '20180424'
 '1.54K'      | '1%'      | '1/16W'  | '0402LF'  | 'CHIP'   | 'TMP_QCS21542FB00'(!)   = 'End of Design' | 'Comp-Approve'     | 'CS21542FB00'           |'R0402'| '(R0402-0201)'                 | '1.54K'   | '1%'    | '1/16W'  | 'DISCRETE' | 'RES CHIP 1.54K 1/16W +-1%(0402)'                  | 'CHIP0402'     | ''          | ''            | ''        
 '1.54K'      | '1%'      | '1/16W'  | '0402LF'  | 'EMPTY'  | 'TMP_QCS21542FB00'(!)   = 'End of Design' | 'Comp-Approve'     | 'CS21542FB00'           |'R0402'| '(R0402-0201)'                 | '1.54K'   | '1%'    | '1/16W'  | 'IO'       | 'RES CHIP 1.54K 1/16W +-1%(0402)'                  | 'CHIP0402'     | ''          | ''            | ''        
 '6.19K'      | '1%'      | '1/16W'  | '0402LF'  | 'CHIP'   | 'TMP_QCS26192FB14'(!)   = 'End of Design' | 'Comp-Approve'     | 'CS26192FB14'           |'R0402'| '(R0402-0201)'                 | '6.19K'   | '1%'    | '1/16W'  | 'DISCRETE' | 'RES CHIP 6.19K 1/16W +-1%  (0402)'                | 'CHIP0402'     | ''          | ''            | ''        
 '6.19K'      | '1%'      | '1/16W'  | '0402LF'  | 'EMPTY'  | 'TMP_QCS26192FB14'(!)   = 'End of Design' | 'Comp-Approve'     | 'CS26192FB14'           |'R0402'| '(R0402-0201)'                 | '6.19K'   | '1%'    | '1/16W'  | 'IO'       | 'RES CHIP 6.19K 1/16W +-1%  (0402)'                | 'CHIP0402'     | ''          | ''            | ''        
 '47K'        | '1%'      | '1/16W'  | '0402LF'  | 'CHIP'   | 'TMP_QCS34702FB11'(!)   = 'End of Design' | 'Comp-Release Qty' | 'CS34702FB11'           |'R0402'| '(R0402-0201)'                 | '47K'     | '1%'    | '1/16W'  | 'DISCRETE' | 'RES CHIP 47K 1/16W +-1% (0402)'                   | 'CHIP0402'     | ''          | ''            | ''        
 '47K'        | '1%'      | '1/16W'  | '0402LF'  | 'EMPTY'  | 'TMP_QCS34702FB11'(!)   = 'End of Design' | 'Comp-Release Qty' | 'CS34702FB11'           |'R0402'| '(R0402-0201)'                 | '47K'     | '1%'    | '1/16W'  | 'IO'       | 'RES CHIP 47K 1/16W +-1% (0402)'                   | 'CHIP0402'     | ''          | ''            | ''        
 '10K'        | '5%'      | '1/16W'  | '0402LF'  | 'CHIP'   | 'TMP_QCS31002JB28'(!)   = 'End of Design' | 'Comp-Approve'     | 'CS31002JB28'           |'R0402'| '(R0402-0201)'                 | '10K'     | '5%'    | '1/16W'  | 'DISCRETE' | 'RES CHIP 10K 1/16W 5%(0402)'                      | 'CHIP0402'     | ''          | ''            | ''        
 '10K'        | '5%'      | '1/16W'  | '0402LF'  | 'EMPTY'  | 'TMP_QCS31002JB28'(!)   = 'End of Design' | 'Comp-Approve'     | 'CS31002JB28'           |'R0402'| '(R0402-0201)'                 | '10K'     | '5%'    | '1/16W'  | 'IO'       | 'RES CHIP 10K 1/16W 5%(0402)'                      | 'CHIP0402'     | ''          | ''            | ''        
 '1K'         | '1%'      | '1/16W'  | '0402LF'  | 'CHIP'   | 'TMP_QCS21002FB24'(!)   = 'End of Design' | 'Comp-Approve'     | 'CS21002FB24'           |'R0402'| '(R0402-0201)'                 | '1K'      | '1%'    | '1/16W'  | 'DISCRETE' | 'RES CHIP 1K 1/16W +-1% (0402)'                    | 'CHIP0402'     | ''          | ''            | ''        
 '1K'         | '1%'      | '1/16W'  | '0402LF'  | 'EMPTY'  | 'TMP_QCS21002FB24'(!)   = 'End of Design' | 'Comp-Approve'     | 'CS21002FB24'           |'R0402'| '(R0402-0201)'                 | '1K'      | '1%'    | '1/16W'  | 'IO'       | 'RES CHIP 1K 1/16W +-1% (0402)'                    | 'CHIP0402'     | ''          | ''            | ''        
 '0'          | '5%'      | '1/10W'  | '0603'    | 'CHIP'   | 'TMP_QCS00003J951'(!)   = ''              | ''                 | 'CS00003J951'           |'R0603'| '(SMR0603AW)'                  | '0'       | '5%'    | '1/10W'  | 'DISCRETE' | 'RESISTOR CHIP 0 1/10W+-5%(0603)'                  | 'CHIP0603'     | ''          | ''            | ''        
 '0'          | '5%'      | '1/10W'  | '0603'    | 'EMPTY'  | 'TMP_QCS00003J951'(!)   = ''              | ''                 | 'CS00003J951'           |'R0603'| '(SMR0603AW)'                  | '0'       | '5%'    | '1/10W'  | 'IO'       | 'RESISTOR CHIP 0 1/10W+-5%(0603)'                  | 'CHIP0603'     | ''          | ''            | ''        
 '3.4M'       | '1%'      | '1/8W'   | '0805LF'  | 'CHIP'   | 'CS53404FA00'(!)        = ''              | ''                 | 'CS53404FA00'           |'R0805'| '(SMR0805AW)'                  | '3.4M'    | '1%'    | '1/8W'   | 'DISCRETE' | 'RES CHIP 3.4M 1/8W +-1%(0805)'                    | 'CHIPR0805'    | ''          | ''            | '20180502'
 '3.4M'       | '1%'      | '1/8W'   | '0805LF'  | 'EMPTY'  | 'CS53404FA00'(!)        = ''              | ''                 | 'CS53404FA00'           |'R0805'| '(SMR0805AW)'                  | '3.4M'    | '1%'    | '1/8W'   | 'IO'       | 'RES CHIP 3.4M 1/8W +-1%(0805)'                    | 'CHIPR0805'    | ''          | ''            | '20180502'
 '0.006'      | '1%'      | '1W'     | '1206LF'  | 'CHIP'   | 'CS+0068F200'(!)        = ''              | ''                 | 'CS+0068F200'           |'R1206XI_H18'| '(SMR1206AW)'                  | '0.006'   | '1%'    | '1W'     | 'DISCRETE' | 'RES CHIP 0.006 1W +-1%(1206)EF'                   | 'CHIPR1206'    | ''          | ''            | '20180514'
 '0.006'      | '1%'      | '1W'     | '1206LF'  | 'EMPTY'  | 'CS+0068F200'(!)        = ''              | ''                 | 'CS+0068F200'           |'R1206XI_H18'| '(SMR1206AW)'                  | '0.006'   | '1%'    | '1W'     | 'IO'       | 'RES CHIP 0.006 1W +-1%(1206)EF'                   | 'CHIPR1206'    | ''          | ''            | '20180514'
 '1.47M'      | '1%'      | '1/8W'   | '0805LF'  | 'CHIP'   | 'CS51474FA00'(!)        = ''              | ''                 | 'CS51474FA00'           |'R0805'| '(SMR0805AW)'                  | '1.47M'   | '1%'    | '1/8W'   | 'DISCRETE' | 'RES CHIP 1.47M 1/8W +-1%(0805)'                   | 'CHIPR0805'    | ''          | ''            | '20180514'
 '1.47M'      | '1%'      | '1/8W'   | '0805LF'  | 'EMPTY'  | 'CS51474FA00'(!)        = ''              | ''                 | 'CS51474FA00'           |'R0805'| '(SMR0805AW)'                  | '1.47M'   | '1%'    | '1/8W'   | 'IO'       | 'RES CHIP 1.47M 1/8W +-1%(0805)'                   | 'CHIPR0805'    | ''          | ''            | '20180514'
 '2.05M'      | '1%'      | '1/8W'   | '0805LF'  | 'CHIP'   | 'CS52054FA00'(!)        = ''              | ''                 | 'CS52054FA00'           |'R0805'| '(SMR0805AW)'                  | '2.05M'   | '1%'    | '1/8W'   | 'DISCRETE' | 'RES CHIP 2.05M 1/8W +-1%(0805)'                   | 'CHIPR0805'    | ''          | ''            | '20180515'
 '2.05M'      | '1%'      | '1/8W'   | '0805LF'  | 'EMPTY'  | 'CS52054FA00'(!)        = ''              | ''                 | 'CS52054FA00'           |'R0805'| '(SMR0805AW)'                  | '2.05M'   | '1%'    | '1/8W'   | 'IO'       | 'RES CHIP 2.05M 1/8W +-1%(0805)'                   | 'CHIPR0805'    | ''          | ''            | '20180515'
 '30.9K'      | '1%'      | '1/16W'  | '0402LF'  | 'CHIP'   | 'CS33092FB06'(!)        = 'End of Design' | 'Comp-Approve'     | 'CS33092FB06'           |'R0402'| '(R0402-0201)'                 | '30.9K'   | '1%'    | '1/16W'  | 'DISCRETE' | 'RES CHIP 30.9K 1/16W +-1%(0402)'                  | 'CHIPR0402'    | ''          | ''            | '20130510'
 '30.9K'      | '1%'      | '1/16W'  | '0402LF'  | 'EMPTY'  | 'CS33092FB06'(!)        = 'End of Design' | 'Comp-Approve'     | 'CS33092FB06'           |'R0402'| '(R0402-0201)'                 | '30.9K'   | '1%'    | '1/16W'  | 'IO'       | 'RES CHIP 30.9K 1/16W +-1%(0402)'                  | 'CHIPR0402'    | ''          | ''            | '20130510'
 '66.5K'      | '1%'      | '1/16W'  | '0402LF'  | 'CHIP'   | 'TMP_QCS36652FB16'(!)   = 'End of Design' | 'Comp-Approve'     | 'CS36652FB16'           |'R0402'| '(R0402-0201)'                 | '66.5K'   | '1%'    | '1/16W'  | 'DISCRETE' | 'RES CHIP 66.5K 1/16W +-1%(0402)'                  | 'CHIP0402'     | ''          | ''            | ''        
 '66.5K'      | '1%'      | '1/16W'  | '0402LF'  | 'EMPTY'  | 'TMP_QCS36652FB16'(!)   = 'End of Design' | 'Comp-Approve'     | 'CS36652FB16'           |'R0402'| '(R0402-0201)'                 | '66.5K'   | '1%'    | '1/16W'  | 'IO'       | 'RES CHIP 66.5K 1/16W +-1%(0402)'                  | 'CHIP0402'     | ''          | ''            | ''        
 '7.87'       | '1%'      | '1/16W'  | '0402LF'  | 'CHIP'   | 'CS-7872FB00'(!)        = ''              | ''                 | 'CS-7872FB00'           |'R0402'| '(R0402-0201)'                 | '7.87'    | '1%'    | '1/16W'  | 'DISCRETE' | 'RES CHIP 7.87 1/16W +-1%(0402)'                   | 'CHIPR0402'    | ''          | ''            | '20180522'
 '7.87'       | '1%'      | '1/16W'  | '0402LF'  | 'EMPTY'  | 'CS-7872FB00'(!)        = ''              | ''                 | 'CS-7872FB00'           |'R0402'| '(R0402-0201)'                 | '7.87'    | '1%'    | '1/16W'  | 'IO'       | 'RES CHIP 7.87 1/16W +-1%(0402)'                   | 'CHIPR0402'    | ''          | ''            | '20180522'
 '0.5'        | '1%'      | '2W'     | '2512LF'  | 'CHIP'   | 'CS+500AFR00'(!)        = ''              | ''                 | 'CS+500AFR00'           |'R2512XA'| '(SMR2512AW)'                  | '0.5'     | '1%'    | '2W'     | 'DISCRETE' | 'RES CHIP 0.5 2W +-1%(2512)'                       | 'CHIPR2512'    | ''          | ''            | '20180523'
 '0.5'        | '1%'      | '2W'     | '2512LF'  | 'EMPTY'  | 'CS+500AFR00'(!)        = ''              | ''                 | 'CS+500AFR00'           |'R2512XA'| '(SMR2512AW)'                  | '0.5'     | '1%'    | '2W'     | 'IO'       | 'RES CHIP 0.5 2W +-1%(2512)'                       | 'CHIPR2512'    | ''          | ''            | '20180523'
 '1.5'        | '1%'      | '1/8W'   | '0402LF'  | 'CHIP'   | 'CS-1504FB00'(!)        = ''              | ''                 | 'CS-1504FB00'           |'R0402'| '(R0402-0201)'                 | '1.5'     | '1%'    | '1/8W'   | 'DISCRETE' | 'RES CHIP 1.5 1/8W +-1%(0402)'                     | 'CHIPR0402'    | ''          | ''            | '20180523'
 '1.5'        | '1%'      | '1/8W'   | '0402LF'  | 'EMPTY'  | 'CS-1504FB00'(!)        = ''              | ''                 | 'CS-1504FB00'           |'R0402'| '(R0402-0201)'                 | '1.5'     | '1%'    | '1/8W'   | 'IO'       | 'RES CHIP 1.5 1/8W +-1%(0402)'                     | 'CHIPR0402'    | ''          | ''            | '20180523'
 '1'          | '1%'      | '1/8W'   | '0402LF'  | 'CHIP'   | 'CS-1004FB00'(!)        = ''              | ''                 | 'CS-1004FB00'           |'R0402'| '(R0402-0201)'                 | '1'       | '1%'    | '1/8W'   | 'DISCRETE' | 'RES CHIP 1 1/8W +-1%(0402)'                       | 'CHIPR0402'    | ''          | ''            | '20180523'
 '1'          | '1%'      | '1/8W'   | '0402LF'  | 'EMPTY'  | 'CS-1004FB00'(!)        = ''              | ''                 | 'CS-1004FB00'           |'R0402'| '(R0402-0201)'                 | '1'       | '1%'    | '1/8W'   | 'IO'       | 'RES CHIP 1 1/8W +-1%(0402)'                       | 'CHIPR0402'    | ''          | ''            | '20180523'
 '365K'       | '1%'      | '1/16W'  | '0402LF'  | 'CHIP'   | 'CS43652FB10'(!)        = 'End of Design' | 'Comp-Approve'     | 'CS43652FB10'           |'R0402'| '(R0402-0201)'                 | '365K'    | '1%'    | '1/16W'  | 'DISCRETE' | 'RES CHIP 365K 1/16W +-1%(0402)'                   | 'CHIPR0402'    | ''          | ''            | '20180704'
 '365K'       | '1%'      | '1/16W'  | '0402LF'  | 'EMPTY'  | 'CS43652FB10'(!)        = 'End of Design' | 'Comp-Approve'     | 'CS43652FB10'           |'R0402'| '(R0402-0201)'                 | '365K'    | '1%'    | '1/16W'  | 'IO'       | 'RES CHIP 365K 1/16W +-1%(0402)'                   | 'CHIPR0402'    | ''          | ''            | '20180704'
 '100K'       | '0.1%'    | '1/8W'   | '0805LF'  | 'CHIP'   | 'CS41004BA01'(!)        = ''              | ''                 | 'CS41004BA01'           |'R0805'| '(SMR0805AW)'                  | '100K'    | '0.1%'  | '1/8W'   | 'DISCRETE' | 'RES CHIP 100K 1/8W +-0.1%(0805)'                  | 'CHIPR0805'    | ''          | ''            | '20180704'
 '100K'       | '0.1%'    | '1/8W'   | '0805LF'  | 'EMPTY'  | 'CS41004BA01'(!)        = ''              | ''                 | 'CS41004BA01'           |'R0805'| '(SMR0805AW)'                  | '100K'    | '0.1%'  | '1/8W'   | 'IO'       | 'RES CHIP 100K 1/8W +-0.1%(0805)'                  | 'CHIPR0805'    | ''          | ''            | '20180704'
 '100K'       | '1%'      | '1/8W'   | '0805LF'  | 'CHIP'   | 'CS41004FA00'(!)        = 'End of Design' | 'Comp-Approve'     | 'CS41004FA00'           |'R0805'| '(SMR0805AW)'                  | '100K'    | '1%'    | '1/8W'   | 'DISCRETE' | 'RESISTOR CHIP 100K 1/8W+-1%(0805)'                | 'CHIPR0805'    | ''          | ''            | '20170927'
 '100K'       | '1%'      | '1/8W'   | '0805LF'  | 'EMPTY'  | 'CS41004FA00'(!)        = 'End of Design' | 'Comp-Approve'     | 'CS41004FA00'           |'R0805'| '(SMR0805AW)'                  | '100K'    | '1%'    | '1/8W'   | 'IO'       | 'RESISTOR CHIP 100K 1/8W+-1%(0805)'                | 'CHIPR0805'    | ''          | ''            | '20170927'
 '0'          | '1%'      | '1/16W'  | '0402LF'  | 'CHIP'   | 'TMP_QCS00002FB00'(!)   = 'End of Design' | 'Comp-Approve'     | 'CS00002FB00'           |'R0402'| '(R0402-0201)'                 | '0'       | '1%'    | '1/16W'  | 'DISCRETE' | 'RES CHIP 0 1/16W +-1%(0402)'                      | 'CHIP0402'     | ''          | ''            | ''        
 '0'          | '1%'      | '1/16W'  | '0402LF'  | 'EMPTY'  | 'TMP_QCS00002FB00'(!)   = 'End of Design' | 'Comp-Approve'     | 'CS00002FB00'           |'R0402'| '(R0402-0201)'                 | '0'       | '1%'    | '1/16W'  | 'IO'       | 'RES CHIP 0 1/16W +-1%(0402)'                      | 'CHIP0402'     | ''          | ''            | ''        
 '549K'       | '1%'      | '1/16W'  | '0402LF'  | 'CHIP'   | 'CS45492FB08'(!)        = ''              | ''                 | 'CS45492FB08'           |'R0402'| '(R0402-0201)'                 | '549K'    | '1%'    | '1/16W'  | 'DISCRETE' | 'RES CHIP 549K 1/16W +-1%(0402)'                   | 'CHIPR0402'    | ''          | ''            | '20180709'
 '549K'       | '1%'      | '1/16W'  | '0402LF'  | 'EMPTY'  | 'CS45492FB08'(!)        = ''              | ''                 | 'CS45492FB08'           |'R0402'| '(R0402-0201)'                 | '549K'    | '1%'    | '1/16W'  | 'IO'       | 'RES CHIP 549K 1/16W +-1%(0402)'                   | 'CHIPR0402'    | ''          | ''            | '20180709'
 '1.5K'       | '5%'      | '1/8W'   | '0805LF'  | 'CHIP'   | 'CS21504JA02'(!)        = ''              | ''                 | 'CS21504JA02'           |'R0805_H26'| '(SMR0805AW)'                  | '1.5K'    | '5%'    | '1/8W'   | 'DISCRETE' | 'RES CHIP 1.5K 1/8W +-5%(0805)'                    | 'CHIPR0805'    | ''          | ''            | '20180720'
 '1.5K'       | '5%'      | '1/8W'   | '0805LF'  | 'EMPTY'  | 'CS21504JA02'(!)        = ''              | ''                 | 'CS21504JA02'           |'R0805_H26'| '(SMR0805AW)'                  | '1.5K'    | '5%'    | '1/8W'   | 'IO'       | 'RES CHIP 1.5K 1/8W +-5%(0805)'                    | 'CHIPR0805'    | ''          | ''            | '20180720'
 '15'         | '5%'      | '1/16W'  | '0402LF'  | 'CHIP'   | 'CS01502JB12'(!)        = 'End of Design' | 'Comp-Approve'     | 'CS01502JB12'           |'R0402'| '(R0402-0201)'                 | '15'      | '5%'    | '1/16W'  | 'DISCRETE' | 'RES CHIP 15 1/16W +-5%(0402)L-F'                  | 'CHIPR0402'    | ''          | ''            | '20180720'
 '15'         | '5%'      | '1/16W'  | '0402LF'  | 'EMPTY'  | 'CS01502JB12'(!)        = 'End of Design' | 'Comp-Approve'     | 'CS01502JB12'           |'R0402'| '(R0402-0201)'                 | '15'      | '5%'    | '1/16W'  | 'IO'       | 'RES CHIP 15 1/16W +-5%(0402)L-F'                  | 'CHIPR0402'    | ''          | ''            | '20180720'
 '95.3K'      | '1%'      | '1/4W'   | '1206LF'  | 'CHIP'   | 'CS39536F200'(!)        = ''              | ''                 | 'CS39536F200'           |'R1206XJ'| '(SMR1206AW)'                  | '95.3K'   | '1%'    | '1/4W'   | 'DISCRETE' | 'RES CHIP 95.3K 1/4W +-1%(1206)'                   | 'CHIPR1206'    | ''          | ''            | '20180725'
 '95.3K'      | '1%'      | '1/4W'   | '1206LF'  | 'EMPTY'  | 'CS39536F200'(!)        = ''              | ''                 | 'CS39536F200'           |'R1206XJ'| '(SMR1206AW)'                  | '95.3K'   | '1%'    | '1/4W'   | 'IO'       | 'RES CHIP 95.3K 1/4W +-1%(1206)'                   | 'CHIPR1206'    | ''          | ''            | '20180725'
 '100'        | '1%'      | '1/8W'   | '0805LF'  | 'CHIP'   | 'CS11004FA34'(!)        = ''              | ''                 | 'CS11004FA34'           |'R0805_H26'| '(SMR0805AW)'                  | '100'     | '1%'    | '1/8W'   | 'DISCRETE' | 'RES CHIP 100 1/8W +-1%(0805)'                     | 'CHIPR0805'    | ''          | ''            | '20180802'
 '100'        | '1%'      | '1/8W'   | '0805LF'  | 'EMPTY'  | 'CS11004FA34'(!)        = ''              | ''                 | 'CS11004FA34'           |'R0805_H26'| '(SMR0805AW)'                  | '100'     | '1%'    | '1/8W'   | 'IO'       | 'RES CHIP 100 1/8W +-1%(0805)'                     | 'CHIPR0805'    | ''          | ''            | '20180802'
 '10'         | '5%'      | '1/20W'  | '0201LF'  | 'CHIP'   | 'CS01001JE11'(!)        = ''              | ''                 | 'CS01001JE11'           |'R0201'| '(SMR0201AW)'                  | '10'      | '5%'    | '1/20W'  | 'DISCRETE' | 'RES CHIP 10(1/20W,+-5%,0201)'                     | 'CHIPR0201'    | ''          | ''            | '20180802'
 '10'         | '5%'      | '1/20W'  | '0201LF'  | 'EMPTY'  | 'CS01001JE11'(!)        = ''              | ''                 | 'CS01001JE11'           |'R0201'| '(SMR0201AW)'                  | '10'      | '5%'    | '1/20W'  | 'IO'       | 'RES CHIP 10(1/20W,+-5%,0201)'                     | 'CHIPR0201'    | ''          | ''            | '20180802'
 '22.0'       | '1%'      | '1/20W'  | '0201LF'  | 'CHIP'   | 'CS02201FE00'(!)        = ''              | ''                 | 'CS02201FE00'           |'R0201'| '(SMR0201AW)'                  | '22.0'    | '1%'    | '1/20W'  | 'DISCRETE' | 'RES CHIP 22.0 1/20W +-1%(0201)'                   | 'CHIPR0201'    | ''          | ''            | '20150324'
 '22.0'       | '1%'      | '1/20W'  | '0201LF'  | 'EMPTY'  | 'CS02201FE00'(!)        = ''              | ''                 | 'CS02201FE00'           |'R0201'| '(SMR0201AW)'                  | '22.0'    | '1%'    | '1/20W'  | 'IO'       | 'RES CHIP 22.0 1/20W +-1%(0201)'                   | 'CHIPR0201'    | ''          | ''            | '20150324'
 '60.4'       | '1%'      | '1/20W'  | '0201LF'  | 'CHIP'   | 'CS06041FE00'(!)        = ''              | ''                 | 'CS06041FE00'           |'R0201'| '(SMR0201AW)'                  | '60.4'    | '1%'    | '1/20W'  | 'DISCRETE' | 'RES CHIP 60.4 1/20W,+-1%(0201)'                   | 'CHIPR0201'    | ''          | ''            | '20120209'
 '60.4'       | '1%'      | '1/20W'  | '0201LF'  | 'EMPTY'  | 'CS06041FE00'(!)        = ''              | ''                 | 'CS06041FE00'           |'R0201'| '(SMR0201AW)'                  | '60.4'    | '1%'    | '1/20W'  | 'IO'       | 'RES CHIP 60.4 1/20W,+-1%(0201)'                   | 'CHIPR0201'    | ''          | ''            | '20120209'
 '150'        | '1%'      | '1/20W'  | '0201LF'  | 'CHIP'   | 'CS11501FE01'(!)        = ''              | ''                 | 'CS11501FE01'           |'R0201'| '(SMR0201AW)'                  | '150'     | '1%'    | '1/20W'  | 'DISCRETE' | 'RES CHIP 150 1/20W +-1%(0201)'                    | 'CHIPR0201'    | ''          | ''            | '20170825'
 '150'        | '1%'      | '1/20W'  | '0201LF'  | 'EMPTY'  | 'CS11501FE01'(!)        = ''              | ''                 | 'CS11501FE01'           |'R0201'| '(SMR0201AW)'                  | '150'     | '1%'    | '1/20W'  | 'IO'       | 'RES CHIP 150 1/20W +-1%(0201)'                    | 'CHIPR0201'    | ''          | ''            | '20170825'
 '22.1'       | '1%'      | '1/20W'  | '0201LF'  | 'CHIP'   | 'CS02211FE01'(!)        = ''              | ''                 | 'CS02211FE01'           |'R0201'| '(SMR0201AW)'                  | '22.1'    | '1%'    | '1/20W'  | 'DISCRETE' | 'RES CHIP 22.1 1/20W(+-1%,0201)'                   | 'CHIPR0201'    | ''          | ''            | '20180803'
 '22.1'       | '1%'      | '1/20W'  | '0201LF'  | 'EMPTY'  | 'CS02211FE01'(!)        = ''              | ''                 | 'CS02211FE01'           |'R0201'| '(SMR0201AW)'                  | '22.1'    | '1%'    | '1/20W'  | 'IO'       | 'RES CHIP 22.1 1/20W(+-1%,0201)'                   | 'CHIPR0201'    | ''          | ''            | '20180803'
 '33'         | '5%'      | '1/20W'  | '0201LF'  | 'CHIP'   | 'CS03301JE09'(!)        = ''              | ''                 | 'CS03301JE09'           |'R0201'| '(SMR0201AW)'                  | '33'      | '5%'    | '1/20W'  | 'DISCRETE' | 'RES CHIP 33 1/20W +-5%(0201)'                     | 'CHIPR0201'    | ''          | ''            | '20180803'
 '33'         | '5%'      | '1/20W'  | '0201LF'  | 'EMPTY'  | 'CS03301JE09'(!)        = ''              | ''                 | 'CS03301JE09'           |'R0201'| '(SMR0201AW)'                  | '33'      | '5%'    | '1/20W'  | 'IO'       | 'RES CHIP 33 1/20W +-5%(0201)'                     | 'CHIPR0201'    | ''          | ''            | '20180803'
 '33.2'       | '1%'      | '1/20W'  | '0201LF'  | 'CHIP'   | 'CS03321FE00'(!)        = ''              | ''                 | 'CS03321FE00'           |'R0201'| '(SMR0201AW)'                  | '33.2'    | '1%'    | '1/20W'  | 'DISCRETE' | 'RES CHIP 33.2 1/20W +-1%(0201)'                   | 'CHIPR0201'    | ''          | ''            | '20180803'
 '33.2'       | '1%'      | '1/20W'  | '0201LF'  | 'EMPTY'  | 'CS03321FE00'(!)        = ''              | ''                 | 'CS03321FE00'           |'R0201'| '(SMR0201AW)'                  | '33.2'    | '1%'    | '1/20W'  | 'IO'       | 'RES CHIP 33.2 1/20W +-1%(0201)'                   | 'CHIPR0201'    | ''          | ''            | '20180803'
 '75'         | '1%'      | '1/20W'  | '0201LF'  | 'CHIP'   | 'CS07501FE05'(!)        = ''              | ''                 | 'CS07501FE05'           |'R0201'| '(SMR0201AW)'                  | '75'      | '1%'    | '1/20W'  | 'DISCRETE' | 'RES CHIP 75 1/20W +-1%(0201)'                     | 'CHIPR0201'    | ''          | ''            | '20180803'
 '75'         | '1%'      | '1/20W'  | '0201LF'  | 'EMPTY'  | 'CS07501FE05'(!)        = ''              | ''                 | 'CS07501FE05'           |'R0201'| '(SMR0201AW)'                  | '75'      | '1%'    | '1/20W'  | 'IO'       | 'RES CHIP 75 1/20W +-1%(0201)'                     | 'CHIPR0201'    | ''          | ''            | '20180803'
 '120'        | '1%'      | '1/20W'  | '0201LF'  | 'CHIP'   | 'CS11201FE01'(!)        = 'End of Design' | 'Comp-Release Qty' | 'CS11201FE01'           |'R0201'| '(SMR0201AW)'                  | '120'     | '1%'    | '1/20W'  | 'DISCRETE' | 'RES CHIP 120 1/20W +-1%(0201)'                    | 'CHIPR0201'    | ''          | ''            | '20180803'
 '120'        | '1%'      | '1/20W'  | '0201LF'  | 'EMPTY'  | 'CS11201FE01'(!)        = 'End of Design' | 'Comp-Release Qty' | 'CS11201FE01'           |'R0201'| '(SMR0201AW)'                  | '120'     | '1%'    | '1/20W'  | 'IO'       | 'RES CHIP 120 1/20W +-1%(0201)'                    | 'CHIPR0201'    | ''          | ''            | '20180803'
 '220'        | '1%'      | '1/20W'  | '0201LF'  | 'CHIP'   | 'CS12201FE11'(!)        = 'End of Design' | 'Comp-Approve'     | 'CS12201FE11'           |'R0201'| '(SMR0201AW)'                  | '220'     | '1%'    | '1/20W'  | 'DISCRETE' | 'RES CHIP 220(1/20W,+-1%,0201)'                    | 'CHIPR0201'    | ''          | ''            | '20180803'
 '220'        | '1%'      | '1/20W'  | '0201LF'  | 'EMPTY'  | 'CS12201FE11'(!)        = 'End of Design' | 'Comp-Approve'     | 'CS12201FE11'           |'R0201'| '(SMR0201AW)'                  | '220'     | '1%'    | '1/20W'  | 'IO'       | 'RES CHIP 220(1/20W,+-1%,0201)'                    | 'CHIPR0201'    | ''          | ''            | '20180803'
 '221'        | '1%'      | '1/20W'  | '0201LF'  | 'CHIP'   | 'CS12211FE07'(!)        = ''              | ''                 | 'CS12211FE07'           |'R0201'| '(SMR0201AW)'                  | '221'     | '1%'    | '1/20W'  | 'DISCRETE' | 'RES CHIP 221 1/20W +-1%(0201)'                    | 'CHIPR0201'    | ''          | ''            | '20180803'
 '221'        | '1%'      | '1/20W'  | '0201LF'  | 'EMPTY'  | 'CS12211FE07'(!)        = ''              | ''                 | 'CS12211FE07'           |'R0201'| '(SMR0201AW)'                  | '221'     | '1%'    | '1/20W'  | 'IO'       | 'RES CHIP 221 1/20W +-1%(0201)'                    | 'CHIPR0201'    | ''          | ''            | '20180803'
 '300'        | '5%'      | '1/20W'  | '0201LF'  | 'CHIP'   | 'CS13001JE00'(!)        = ''              | ''                 | 'CS13001JE00'           |'R0201'| '(SMR0201AW)'                  | '300'     | '5%'    | '1/20W'  | 'DISCRETE' | 'RES CHIP 300 1/20W +-5%(0201)'                    | 'CHIPR0201'    | ''          | ''            | '20180803'
 '300'        | '5%'      | '1/20W'  | '0201LF'  | 'EMPTY'  | 'CS13001JE00'(!)        = ''              | ''                 | 'CS13001JE00'           |'R0201'| '(SMR0201AW)'                  | '300'     | '5%'    | '1/20W'  | 'IO'       | 'RES CHIP 300 1/20W +-5%(0201)'                    | 'CHIPR0201'    | ''          | ''            | '20180803'
 '330'        | '5%'      | '1/20W'  | '0201LF'  | 'CHIP'   | 'CS13301JE00'(!)        = ''              | ''                 | 'CS13301JE00'           |'R0201'| '(SMR0201AW)'                  | '330'     | '5%'    | '1/20W'  | 'DISCRETE' | 'RES CHIP 330 1/20W +-5%(0201)'                    | 'CHIPR0201'    | ''          | ''            | '20180803'
 '330'        | '5%'      | '1/20W'  | '0201LF'  | 'EMPTY'  | 'CS13301JE00'(!)        = ''              | ''                 | 'CS13301JE00'           |'R0201'| '(SMR0201AW)'                  | '330'     | '5%'    | '1/20W'  | 'IO'       | 'RES CHIP 330 1/20W +-5%(0201)'                    | 'CHIPR0201'    | ''          | ''            | '20180803'
 '332'        | '1%'      | '1/20W'  | '0201LF'  | 'CHIP'   | 'CS13321FE01'(!)        = ''              | ''                 | 'CS13321FE01'           |'R0201'| '(SMR0201AW)'                  | '332'     | '1%'    | '1/20W'  | 'DISCRETE' | 'RES CHIP 332 1/20W +-1%(0201)'                    | 'CHIPR0201'    | ''          | ''            | '20180803'
 '332'        | '1%'      | '1/20W'  | '0201LF'  | 'EMPTY'  | 'CS13321FE01'(!)        = ''              | ''                 | 'CS13321FE01'           |'R0201'| '(SMR0201AW)'                  | '332'     | '1%'    | '1/20W'  | 'IO'       | 'RES CHIP 332 1/20W +-1%(0201)'                    | 'CHIPR0201'    | ''          | ''            | '20180803'
 '475'        | '1%'      | '1/20W'  | '0201LF'  | 'CHIP'   | 'CS14751FE00'(!)        = ''              | ''                 | 'CS14751FE00'           |'R0201'| '(SMR0201AW)'                  | '475'     | '1%'    | '1/20W'  | 'DISCRETE' | 'RES CHIP 475 1/20W,+-1%(0201)'                    | 'CHIPR0201'    | ''          | ''            | '20180803'
 '475'        | '1%'      | '1/20W'  | '0201LF'  | 'EMPTY'  | 'CS14751FE00'(!)        = ''              | ''                 | 'CS14751FE00'           |'R0201'| '(SMR0201AW)'                  | '475'     | '1%'    | '1/20W'  | 'IO'       | 'RES CHIP 475 1/20W,+-1%(0201)'                    | 'CHIPR0201'    | ''          | ''            | '20180803'
 '680'        | '5%'      | '1/20W'  | '0201LF'  | 'CHIP'   | 'CS16801JE00'(!)        = ''              | ''                 | 'CS16801JE00'           |'R0201'| '(SMR0201AW)'                  | '680'     | '5%'    | '1/20W'  | 'DISCRETE' | 'RES CHIP 680 1/20W +-5%(0201)'                    | 'CHIPR0201'    | ''          | ''            | '20180803'
 '680'        | '5%'      | '1/20W'  | '0201LF'  | 'EMPTY'  | 'CS16801JE00'(!)        = ''              | ''                 | 'CS16801JE00'           |'R0201'| '(SMR0201AW)'                  | '680'     | '5%'    | '1/20W'  | 'IO'       | 'RES CHIP 680 1/20W +-5%(0201)'                    | 'CHIPR0201'    | ''          | ''            | '20180803'
 '1.5K'       | '1%'      | '1/20W'  | '0201LF'  | 'CHIP'   | 'CS21501FE01'(!)        = ''              | ''                 | 'CS21501FE01'           |'R0201'| '(SMR0201AW)'                  | '1.5K'    | '1%'    | '1/20W'  | 'DISCRETE' | 'RES CHIP 1.5K 1/20W +-1%(0201)'                   | 'CHIPR0201'    | ''          | ''            | '20180803'
 '1.5K'       | '1%'      | '1/20W'  | '0201LF'  | 'EMPTY'  | 'CS21501FE01'(!)        = ''              | ''                 | 'CS21501FE01'           |'R0201'| '(SMR0201AW)'                  | '1.5K'    | '1%'    | '1/20W'  | 'IO'       | 'RES CHIP 1.5K 1/20W +-1%(0201)'                   | 'CHIPR0201'    | ''          | ''            | '20180803'
 '2.2K'       | '5%'      | '1/20W'  | '0201LF'  | 'CHIP'   | 'CS22201JE00'(!)        = ''              | ''                 | 'CS22201JE00'           |'R0201'| '(SMR0201AW)'                  | '2.2K'    | '5%'    | '1/20W'  | 'DISCRETE' | 'RES CHIP 2.2K 1/20W +-5%(0201)'                   | 'CHIPR0201'    | ''          | ''            | '20180803'
 '2.2K'       | '5%'      | '1/20W'  | '0201LF'  | 'EMPTY'  | 'CS22201JE00'(!)        = ''              | ''                 | 'CS22201JE00'           |'R0201'| '(SMR0201AW)'                  | '2.2K'    | '5%'    | '1/20W'  | 'IO'       | 'RES CHIP 2.2K 1/20W +-5%(0201)'                   | 'CHIPR0201'    | ''          | ''            | '20180803'
 '2.21K'      | '1%'      | '1/20W'  | '0201LF'  | 'CHIP'   | 'CS22211FE09'(!)        = ''              | ''                 | 'CS22211FE09'           |'R0201'| '(SMR0201AW)'                  | '2.21K'   | '1%'    | '1/20W'  | 'DISCRETE' | 'RES CHIP 2.21K 1/20W +-1%(0201)'                  | 'CHIPR0201'    | ''          | ''            | '20180806'
 '2.21K'      | '1%'      | '1/20W'  | '0201LF'  | 'EMPTY'  | 'CS22211FE09'(!)        = ''              | ''                 | 'CS22211FE09'           |'R0201'| '(SMR0201AW)'                  | '2.21K'   | '1%'    | '1/20W'  | 'IO'       | 'RES CHIP 2.21K 1/20W +-1%(0201)'                  | 'CHIPR0201'    | ''          | ''            | '20180806'
 '2.2'        | '1%'      | '1/20W'  | '0201LF'  | 'CHIP'   | 'CS-2201FE01'(!)        = 'End of Design' | 'Comp-Approve'     | 'CS-2201FE01'           |'R0201'| '(SMR0201AW)'                  | '2.2'     | '1%'    | '1/20W'  | 'DISCRETE' | 'RES CHIP 2.2 1/20W +-1%(0201)'                    | 'CHIPR0201'    | ''          | ''            | '20180806'
 '2.2'        | '1%'      | '1/20W'  | '0201LF'  | 'EMPTY'  | 'CS-2201FE01'(!)        = 'End of Design' | 'Comp-Approve'     | 'CS-2201FE01'           |'R0201'| '(SMR0201AW)'                  | '2.2'     | '1%'    | '1/20W'  | 'IO'       | 'RES CHIP 2.2 1/20W +-1%(0201)'                    | 'CHIPR0201'    | ''          | ''            | '20180806'
 '24.9'       | '1%'      | '1/20W'  | '0201LF'  | 'CHIP'   | 'CS02491FE00'(!)        = ''              | ''                 | 'CS02491FE00'           |'R0201'| '(SMR0201AW)'                  | '24.9'    | '1%'    | '1/20W'  | 'DISCRETE' | 'RES CHIP 24.9 1/20W +-1%(0201)'                   | 'CHIPR0201'    | ''          | ''            | '20180806'
 '24.9'       | '1%'      | '1/20W'  | '0201LF'  | 'EMPTY'  | 'CS02491FE00'(!)        = ''              | ''                 | 'CS02491FE00'           |'R0201'| '(SMR0201AW)'                  | '24.9'    | '1%'    | '1/20W'  | 'IO'       | 'RES CHIP 24.9 1/20W +-1%(0201)'                   | 'CHIPR0201'    | ''          | ''            | '20180806'
 '27.4'       | '1%'      | '1/20W'  | '0201LF'  | 'CHIP'   | 'CS02741FE07'(!)        = ''              | ''                 | 'CS02741FE07'           |'R0201'| '(SMR0201AW)'                  | '27.4'    | '1%'    | '1/20W'  | 'DISCRETE' | 'RES CHIP 27.4 1/20W +-1%(0201)'                   | 'CHIPR0201'    | ''          | ''            | '20180806'
 '27.4'       | '1%'      | '1/20W'  | '0201LF'  | 'EMPTY'  | 'CS02741FE07'(!)        = ''              | ''                 | 'CS02741FE07'           |'R0201'| '(SMR0201AW)'                  | '27.4'    | '1%'    | '1/20W'  | 'IO'       | 'RES CHIP 27.4 1/20W +-1%(0201)'                   | 'CHIPR0201'    | ''          | ''            | '20180806'
 '113'        | '1%'      | '1/20W'  | '0201LF'  | 'CHIP'   | 'CS11131FE01'(!)        = ''              | ''                 | 'CS11131FE01'           |'R0201'| '(SMR0201AW)'                  | '113'     | '1%'    | '1/20W'  | 'DISCRETE' | 'RES CHIP 113(1/20W,+-1%,0201)'                    | 'CHIPR0201'    | ''          | ''            | '20180806'
 '113'        | '1%'      | '1/20W'  | '0201LF'  | 'EMPTY'  | 'CS11131FE01'(!)        = ''              | ''                 | 'CS11131FE01'           |'R0201'| '(SMR0201AW)'                  | '113'     | '1%'    | '1/20W'  | 'IO'       | 'RES CHIP 113(1/20W,+-1%,0201)'                    | 'CHIPR0201'    | ''          | ''            | '20180806'
 '130'        | '1%'      | '1/20W'  | '0201LF'  | 'CHIP'   | 'CS11301FE03'(!)        = ''              | ''                 | 'CS11301FE03'           |'R0201'| '(SMR0201AW)'                  | '130'     | '1%'    | '1/20W'  | 'DISCRETE' | 'RES CHIP 130(1/20W,+-1%,0201)'                    | 'CHIPR0201'    | ''          | ''            | '20180806'
 '130'        | '1%'      | '1/20W'  | '0201LF'  | 'EMPTY'  | 'CS11301FE03'(!)        = ''              | ''                 | 'CS11301FE03'           |'R0201'| '(SMR0201AW)'                  | '130'     | '1%'    | '1/20W'  | 'IO'       | 'RES CHIP 130(1/20W,+-1%,0201)'                    | 'CHIPR0201'    | ''          | ''            | '20180806'
 '499'        | '1%'      | '1/20W'  | '0201LF'  | 'CHIP'   | 'CS14991FE00'(!)        = ''              | ''                 | 'CS14991FE00'           |'R0201'| '(SMR0201AW)'                  | '499'     | '1%'    | '1/20W'  | 'DISCRETE' | 'RES CHIP 499 1/20W +-1%(0201)'                    | 'CHIPR0201'    | ''          | ''            | '20180806'
 '499'        | '1%'      | '1/20W'  | '0201LF'  | 'EMPTY'  | 'CS14991FE00'(!)        = ''              | ''                 | 'CS14991FE00'           |'R0201'| '(SMR0201AW)'                  | '499'     | '1%'    | '1/20W'  | 'IO'       | 'RES CHIP 499 1/20W +-1%(0201)'                    | 'CHIPR0201'    | ''          | ''            | '20180806'
 '1.21K'      | '1%'      | '1/20W'  | '0201LF'  | 'CHIP'   | 'CS21211FE00'(!)        = ''              | ''                 | 'CS21211FE00'           |'R0201'| '(SMR0201AW)'                  | '1.21K'   | '1%'    | '1/20W'  | 'DISCRETE' | 'RES CHIP 1.21K 1/20W +-1%(0201)'                  | 'CHIPR0201'    | ''          | ''            | '20180806'
 '1.21K'      | '1%'      | '1/20W'  | '0201LF'  | 'EMPTY'  | 'CS21211FE00'(!)        = ''              | ''                 | 'CS21211FE00'           |'R0201'| '(SMR0201AW)'                  | '1.21K'   | '1%'    | '1/20W'  | 'IO'       | 'RES CHIP 1.21K 1/20W +-1%(0201)'                  | 'CHIPR0201'    | ''          | ''            | '20180806'
 '2.7K'       | '1%'      | '1/20W'  | '0201LF'  | 'CHIP'   | 'CS22701FE02'(!)        = ''              | ''                 | 'CS22701FE02'           |'R0201'| '(SMR0201AW)'                  | '2.7K'    | '1%'    | '1/20W'  | 'DISCRETE' | 'RES CHIP 2.7K(1/20W,+-1%,0201)'                   | 'CHIPR0201'    | ''          | ''            | '20180806'
 '2.7K'       | '1%'      | '1/20W'  | '0201LF'  | 'EMPTY'  | 'CS22701FE02'(!)        = ''              | ''                 | 'CS22701FE02'           |'R0201'| '(SMR0201AW)'                  | '2.7K'    | '1%'    | '1/20W'  | 'IO'       | 'RES CHIP 2.7K(1/20W,+-1%,0201)'                   | 'CHIPR0201'    | ''          | ''            | '20180806'
 '5.36K'      | '1%'      | '1/20W'  | '0201LF'  | 'CHIP'   | 'CS25361FE00'(!)        = ''              | ''                 | 'CS25361FE00'           |'R0201'| '(SMR0201AW)'                  | '5.36K'   | '1%'    | '1/20W'  | 'DISCRETE' | 'RES CHIP 5.36K 1/20W +-1%(0201)'                  | 'CHIPR0201'    | ''          | ''            | '20180806'
 '5.36K'      | '1%'      | '1/20W'  | '0201LF'  | 'EMPTY'  | 'CS25361FE00'(!)        = ''              | ''                 | 'CS25361FE00'           |'R0201'| '(SMR0201AW)'                  | '5.36K'   | '1%'    | '1/20W'  | 'IO'       | 'RES CHIP 5.36K 1/20W +-1%(0201)'                  | 'CHIPR0201'    | ''          | ''            | '20180806'
 '6.49K'      | '1%'      | '1/20W'  | '0201LF'  | 'CHIP'   | 'CS26491FE00'(!)        = ''              | ''                 | 'CS26491FE00'           |'R0201'| '(SMR0201AW)'                  | '6.49K'   | '1%'    | '1/20W'  | 'DISCRETE' | 'RES CHIP 6.49K 1/20W +-1%(0201)'                  | 'CHIPR0201'    | ''          | ''            | '20180806'
 '6.49K'      | '1%'      | '1/20W'  | '0201LF'  | 'EMPTY'  | 'CS26491FE00'(!)        = ''              | ''                 | 'CS26491FE00'           |'R0201'| '(SMR0201AW)'                  | '6.49K'   | '1%'    | '1/20W'  | 'IO'       | 'RES CHIP 6.49K 1/20W +-1%(0201)'                  | 'CHIPR0201'    | ''          | ''            | '20180806'
 '6.65K'      | '1%'      | '1/20W'  | '0201LF'  | 'CHIP'   | 'CS26651FE01'(!)        = ''              | ''                 | 'CS26651FE01'           |'R0201'| '(SMR0201AW)'                  | '6.65K'   | '1%'    | '1/20W'  | 'DISCRETE' | 'RES CHIP 6.65K 1/20W +-1%(0201)'                  | 'CHIPR0201'    | ''          | ''            | '20180806'
 '6.65K'      | '1%'      | '1/20W'  | '0201LF'  | 'EMPTY'  | 'CS26651FE01'(!)        = ''              | ''                 | 'CS26651FE01'           |'R0201'| '(SMR0201AW)'                  | '6.65K'   | '1%'    | '1/20W'  | 'IO'       | 'RES CHIP 6.65K 1/20W +-1%(0201)'                  | 'CHIPR0201'    | ''          | ''            | '20180806'
 '6.98K'      | '1%'      | '1/20W'  | '0201LF'  | 'CHIP'   | 'CS26981FE00'(!)        = ''              | ''                 | 'CS26981FE00'           |'R0201'| '(SMR0201AW)'                  | '6.98K'   | '1%'    | '1/20W'  | 'DISCRETE' | 'RES CHIP 6.98K 1/20W +-1%(0201)'                  | 'CHIPR0201'    | ''          | ''            | '20180806'
 '6.98K'      | '1%'      | '1/20W'  | '0201LF'  | 'EMPTY'  | 'CS26981FE00'(!)        = ''              | ''                 | 'CS26981FE00'           |'R0201'| '(SMR0201AW)'                  | '6.98K'   | '1%'    | '1/20W'  | 'IO'       | 'RES CHIP 6.98K 1/20W +-1%(0201)'                  | 'CHIPR0201'    | ''          | ''            | '20180806'
 '9.09K'      | '1'       | '1/20W'  | '0201LF'  | 'CHIP'   | 'CS29091FE00'(!)        = ''              | ''                 | 'CS29091FE00'           |'R0201'| '(SMR0201AW)'                  | '9.09K'   | '1'     | '1/20W'  | 'DISCRETE' | 'RES CHIP 9.09K 1/20W +-1(0201)'                   | 'CHIPR0201'    | ''          | ''            | '20180806'
 '9.09K'      | '1'       | '1/20W'  | '0201LF'  | 'EMPTY'  | 'CS29091FE00'(!)        = ''              | ''                 | 'CS29091FE00'           |'R0201'| '(SMR0201AW)'                  | '9.09K'   | '1'     | '1/20W'  | 'IO'       | 'RES CHIP 9.09K 1/20W +-1(0201)'                   | 'CHIPR0201'    | ''          | ''            | '20180806'
 '11.3K'      | '1%'      | '1/20W'  | '0201LF'  | 'CHIP'   | 'CS31131FE03'(!)        = ''              | ''                 | 'CS31131FE03'           |'R0201'| '(SMR0201AW)'                  | '11.3K'   | '1%'    | '1/20W'  | 'DISCRETE' | 'RES CHIP 11.3K(1/20W,+-1%,0201)'                  | 'CHIPR0201'    | ''          | ''            | '20180806'
 '11.3K'      | '1%'      | '1/20W'  | '0201LF'  | 'EMPTY'  | 'CS31131FE03'(!)        = ''              | ''                 | 'CS31131FE03'           |'R0201'| '(SMR0201AW)'                  | '11.3K'   | '1%'    | '1/20W'  | 'IO'       | 'RES CHIP 11.3K(1/20W,+-1%,0201)'                  | 'CHIPR0201'    | ''          | ''            | '20180806'
 '22.1K'      | '1%'      | '1/20W'  | '0201LF'  | 'CHIP'   | 'CS32211FE00'(!)        = ''              | ''                 | 'CS32211FE00'           |'R0201'| '(SMR0201AW)'                  | '22.1K'   | '1%'    | '1/20W'  | 'DISCRETE' | 'RES CHIP 22.1K 1/20W +-1%(0201)'                  | 'CHIPR0201'    | ''          | ''            | '20180806'
 '22.1K'      | '1%'      | '1/20W'  | '0201LF'  | 'EMPTY'  | 'CS32211FE00'(!)        = ''              | ''                 | 'CS32211FE00'           |'R0201'| '(SMR0201AW)'                  | '22.1K'   | '1%'    | '1/20W'  | 'IO'       | 'RES CHIP 22.1K 1/20W +-1%(0201)'                  | 'CHIPR0201'    | ''          | ''            | '20180806'
 '22.6K'      | '1%'      | '1/20W'  | '0201LF'  | 'CHIP'   | 'CS32261FE01'(!)        = ''              | ''                 | 'CS32261FE01'           |'R0201'| '(SMR0201AW)'                  | '22.6K'   | '1%'    | '1/20W'  | 'DISCRETE' | 'RES CHIP 22.6K 1/20W +-1%(0201)'                  | 'CHIPR0201'    | ''          | ''            | '20180806'
 '22.6K'      | '1%'      | '1/20W'  | '0201LF'  | 'EMPTY'  | 'CS32261FE01'(!)        = ''              | ''                 | 'CS32261FE01'           |'R0201'| '(SMR0201AW)'                  | '22.6K'   | '1%'    | '1/20W'  | 'IO'       | 'RES CHIP 22.6K 1/20W +-1%(0201)'                  | 'CHIPR0201'    | ''          | ''            | '20180806'
 '2.49K'      | '1%'      | '1/20W'  | '0201LF'  | 'CHIP'   | 'CS22491FE02'(!)        = ''              | ''                 | 'CS22491FE02'           |'R0201'| '(SMR0201AW)'                  | '2.49K'   | '1%'    | '1/20W'  | 'DISCRETE' | 'RES CHIP 2.49K(1/20W,+-1%,0201)'                  | 'CHIPR0201'    | ''          | ''            | '20180806'
 '2.49K'      | '1%'      | '1/20W'  | '0201LF'  | 'EMPTY'  | 'CS22491FE02'(!)        = ''              | ''                 | 'CS22491FE02'           |'R0201'| '(SMR0201AW)'                  | '2.49K'   | '1%'    | '1/20W'  | 'IO'       | 'RES CHIP 2.49K(1/20W,+-1%,0201)'                  | 'CHIPR0201'    | ''          | ''            | '20180806'
 '2.87K'      | '1%'      | '1/20W'  | '0201LF'  | 'CHIP'   | 'CS22871FE01'(!)        = ''              | ''                 | 'CS22871FE01'           |'R0201'| '(SMR0201AW)'                  | '2.87K'   | '1%'    | '1/20W'  | 'DISCRETE' | 'RES CHIP 2.87K(1/20W,+-1%,0201)'                  | 'CHIPR0201'    | ''          | ''            | '20180806'
 '2.87K'      | '1%'      | '1/20W'  | '0201LF'  | 'EMPTY'  | 'CS22871FE01'(!)        = ''              | ''                 | 'CS22871FE01'           |'R0201'| '(SMR0201AW)'                  | '2.87K'   | '1%'    | '1/20W'  | 'IO'       | 'RES CHIP 2.87K(1/20W,+-1%,0201)'                  | 'CHIPR0201'    | ''          | ''            | '20180806'
 '3.3K'       | '5%'      | '1/20W'  | '0201LF'  | 'CHIP'   | 'CS23301JE02'(!)        = ''              | ''                 | 'CS23301JE02'           |'R0201'| '(SMR0201AW)'                  | '3.3K'    | '5%'    | '1/20W'  | 'DISCRETE' | 'RES CHIP 3.3K 1/20W +-5%(0201)'                   | 'CHIPR0201'    | ''          | ''            | '20180806'
 '3.3K'       | '5%'      | '1/20W'  | '0201LF'  | 'EMPTY'  | 'CS23301JE02'(!)        = ''              | ''                 | 'CS23301JE02'           |'R0201'| '(SMR0201AW)'                  | '3.3K'    | '5%'    | '1/20W'  | 'IO'       | 'RES CHIP 3.3K 1/20W +-5%(0201)'                   | 'CHIPR0201'    | ''          | ''            | '20180806'
 '3.32K'      | '1%'      | '1/20W'  | '0201LF'  | 'CHIP'   | 'CS23321FE00'(!)        = ''              | ''                 | 'CS23321FE00'           |'R0201'| '(SMR0201AW)'                  | '3.32K'   | '1%'    | '1/20W'  | 'DISCRETE' | 'RES CHIP 3.32K 1/20W +-1%(0201)'                  | 'CHIPR0201'    | ''          | ''            | '20180806'
 '3.32K'      | '1%'      | '1/20W'  | '0201LF'  | 'EMPTY'  | 'CS23321FE00'(!)        = ''              | ''                 | 'CS23321FE00'           |'R0201'| '(SMR0201AW)'                  | '3.32K'   | '1%'    | '1/20W'  | 'IO'       | 'RES CHIP 3.32K 1/20W +-1%(0201)'                  | 'CHIPR0201'    | ''          | ''            | '20180806'
 '49.9K'      | '1%'      | '1/20W'  | '0201LF'  | 'CHIP'   | 'CS34991FE02'(!)        = ''              | ''                 | 'CS34991FE02'           |'R0201'| '(SMR0201AW)'                  | '49.9K'   | '1%'    | '1/20W'  | 'DISCRETE' | 'RES CHIP 49.9K 1/20W +-1%(0201)'                  | 'CHIPR0201'    | ''          | ''            | '20180806'
 '49.9K'      | '1%'      | '1/20W'  | '0201LF'  | 'EMPTY'  | 'CS34991FE02'(!)        = ''              | ''                 | 'CS34991FE02'           |'R0201'| '(SMR0201AW)'                  | '49.9K'   | '1%'    | '1/20W'  | 'IO'       | 'RES CHIP 49.9K 1/20W +-1%(0201)'                  | 'CHIPR0201'    | ''          | ''            | '20180806'
 '5.62K'      | '1%'      | '1/20W'  | '0201LF'  | 'CHIP'   | 'CS25621FE06'(!)        = ''              | ''                 | 'CS25621FE06'           |'R0201'| '(SMR0201AW)'                  | '5.62K'   | '1%'    | '1/20W'  | 'DISCRETE' | 'RES CHIP 5.62K(1/20W,+-1%,0201)'                  | 'CHIPR0201'    | ''          | ''            | '20180806'
 '5.62K'      | '1%'      | '1/20W'  | '0201LF'  | 'EMPTY'  | 'CS25621FE06'(!)        = ''              | ''                 | 'CS25621FE06'           |'R0201'| '(SMR0201AW)'                  | '5.62K'   | '1%'    | '1/20W'  | 'IO'       | 'RES CHIP 5.62K(1/20W,+-1%,0201)'                  | 'CHIPR0201'    | ''          | ''            | '20180806'
 '56K'        | '1%'      | '1/20W'  | '0201LF'  | 'CHIP'   | 'CS35601FE00'(!)        = 'End of Design' | 'Comp-Approve'     | 'CS35601FE00'           |'R0201'| '(SMR0201AW)'                  | '56K'     | '1%'    | '1/20W'  | 'DISCRETE' | 'RES CHIP 56K 1/20W +-1%(0201)'                    | 'CHIPR0201'    | ''          | ''            | '20180806'
 '56K'        | '1%'      | '1/20W'  | '0201LF'  | 'EMPTY'  | 'CS35601FE00'(!)        = 'End of Design' | 'Comp-Approve'     | 'CS35601FE00'           |'R0201'| '(SMR0201AW)'                  | '56K'     | '1%'    | '1/20W'  | 'IO'       | 'RES CHIP 56K 1/20W +-1%(0201)'                    | 'CHIPR0201'    | ''          | ''            | '20180806'
 '8.25K'      | '1%'      | '1/20W'  | '0201LF'  | 'CHIP'   | 'CS28251FE00'(!)        = ''              | ''                 | 'CS28251FE00'           |'R0201'| '(SMR0201AW)'                  | '8.25K'   | '1%'    | '1/20W'  | 'DISCRETE' | 'RES CHIP 8.25K 1/20W +-1%(0201)'                  | 'CHIPR0201'    | ''          | ''            | '20180806'
 '8.25K'      | '1%'      | '1/20W'  | '0201LF'  | 'EMPTY'  | 'CS28251FE00'(!)        = ''              | ''                 | 'CS28251FE00'           |'R0201'| '(SMR0201AW)'                  | '8.25K'   | '1%'    | '1/20W'  | 'IO'       | 'RES CHIP 8.25K 1/20W +-1%(0201)'                  | 'CHIPR0201'    | ''          | ''            | '20180806'
 '10K'        | '5%'      | '1/20W'  | '0201LF'  | 'CHIP'   | 'CS31001JE16'(!)        = ''              | ''                 | 'CS31001JE16'           |'R0201'| '(SMR0201AW)'                  | '10K'     | '5%'    | '1/20W'  | 'DISCRETE' | 'RES CHIP 10K 1/20W +-5%(0201)'                    | 'CHIPR0201'    | ''          | ''            | '20140819'
 '10K'        | '5%'      | '1/20W'  | '0201LF'  | 'EMPTY'  | 'CS31001JE16'(!)        = ''              | ''                 | 'CS31001JE16'           |'R0201'| '(SMR0201AW)'                  | '10K'     | '5%'    | '1/20W'  | 'IO'       | 'RES CHIP 10K 1/20W +-5%(0201)'                    | 'CHIPR0201'    | ''          | ''            | '20140819'
 '10.2K'      | '1%'      | '1/20W'  | '0201LF'  | 'CHIP'   | 'CS31021FE00'(!)        = ''              | ''                 | 'CS31021FE00'           |'R0201'| '(SMR0201AW)'                  | '10.2K'   | '1%'    | '1/20W'  | 'DISCRETE' | 'RES CHIP 10.2K 1/20W +-1%(0201)'                  | 'CHIPR0201'    | ''          | ''            | '20180806'
 '10.2K'      | '1%'      | '1/20W'  | '0201LF'  | 'EMPTY'  | 'CS31021FE00'(!)        = ''              | ''                 | 'CS31021FE00'           |'R0201'| '(SMR0201AW)'                  | '10.2K'   | '1%'    | '1/20W'  | 'IO'       | 'RES CHIP 10.2K 1/20W +-1%(0201)'                  | 'CHIPR0201'    | ''          | ''            | '20180806'
 '150K'       | '1%'      | '1/20W'  | '0201LF'  | 'CHIP'   | 'CS41501FE06'(!)        = ''              | ''                 | 'CS41501FE06'           |'R0201'| '(SMR0201AW)'                  | '150K'    | '1%'    | '1/20W'  | 'DISCRETE' | 'RES CHIP 150K(1/20W,+-1%,0201)'                   | 'CHIPR0201'    | ''          | ''            | '20180806'
 '150K'       | '1%'      | '1/20W'  | '0201LF'  | 'EMPTY'  | 'CS41501FE06'(!)        = ''              | ''                 | 'CS41501FE06'           |'R0201'| '(SMR0201AW)'                  | '150K'    | '1%'    | '1/20W'  | 'IO'       | 'RES CHIP 150K(1/20W,+-1%,0201)'                   | 'CHIPR0201'    | ''          | ''            | '20180806'
 '11.5K'      | '1%'      | '1/20W'  | '0201LF'  | 'CHIP'   | 'CS31151FE03'(!)        = ''              | ''                 | 'CS31151FE03'           |'R0201'| '(SMR0201AW)'                  | '11.5K'   | '1%'    | '1/20W'  | 'DISCRETE' | 'RES CHIP 11.5K(1/20W,+-1%,0201)'                  | 'CHIPR0201'    | ''          | ''            | '20180806'
 '11.5K'      | '1%'      | '1/20W'  | '0201LF'  | 'EMPTY'  | 'CS31151FE03'(!)        = ''              | ''                 | 'CS31151FE03'           |'R0201'| '(SMR0201AW)'                  | '11.5K'   | '1%'    | '1/20W'  | 'IO'       | 'RES CHIP 11.5K(1/20W,+-1%,0201)'                  | 'CHIPR0201'    | ''          | ''            | '20180806'
 '154K'       | '1%'      | '1/20W'  | '0201LF'  | 'CHIP'   | 'CS41541FE00'(!)        = ''              | ''                 | 'CS41541FE00'           |'R0201'| '(SMR0201AW)'                  | '154K'    | '1%'    | '1/20W'  | 'DISCRETE' | 'RES CHIP 154K 1/20W +-1%(0201)'                   | 'CHIPR0201'    | ''          | ''            | '20180806'
 '154K'       | '1%'      | '1/20W'  | '0201LF'  | 'EMPTY'  | 'CS41541FE00'(!)        = ''              | ''                 | 'CS41541FE00'           |'R0201'| '(SMR0201AW)'                  | '154K'    | '1%'    | '1/20W'  | 'IO'       | 'RES CHIP 154K 1/20W +-1%(0201)'                   | 'CHIPR0201'    | ''          | ''            | '20180806'
 '12K'        | '1%'      | '1/20W'  | '0201LF'  | 'CHIP'   | 'CS31201FE00'(!)        = 'End of Design' | 'Comp-Approve'     | 'CS31201FE00'           |'R0201'| '(SMR0201AW)'                  | '12K'     | '1%'    | '1/20W'  | 'DISCRETE' | 'RES CHIP 12K 1/20W +-1%(0201)'                    | 'CHIPR0201'    | ''          | ''            | '20180806'
 '12K'        | '1%'      | '1/20W'  | '0201LF'  | 'EMPTY'  | 'CS31201FE00'(!)        = 'End of Design' | 'Comp-Approve'     | 'CS31201FE00'           |'R0201'| '(SMR0201AW)'                  | '12K'     | '1%'    | '1/20W'  | 'IO'       | 'RES CHIP 12K 1/20W +-1%(0201)'                    | 'CHIPR0201'    | ''          | ''            | '20180806'
 '200K'       | '1%'      | '1/20W'  | '0201LF'  | 'CHIP'   | 'CS42001FE00'(!)        = ''              | ''                 | 'CS42001FE00'           |'R0201'| '(SMR0201AW)'                  | '200K'    | '1%'    | '1/20W'  | 'DISCRETE' | 'RES CHIP 200K 1/20W +-1%(0201)'                   | 'CHIPR0201'    | ''          | ''            | '20180806'
 '200K'       | '1%'      | '1/20W'  | '0201LF'  | 'EMPTY'  | 'CS42001FE00'(!)        = ''              | ''                 | 'CS42001FE00'           |'R0201'| '(SMR0201AW)'                  | '200K'    | '1%'    | '1/20W'  | 'IO'       | 'RES CHIP 200K 1/20W +-1%(0201)'                   | 'CHIPR0201'    | ''          | ''            | '20180806'
 '15K'        | '1%'      | '1/20W'  | '0201LF'  | 'CHIP'   | 'CS31501FE00'(!)        = ''              | ''                 | 'CS31501FE00'           |'R0201'| '(SMR0201AW)'                  | '15K'     | '1%'    | '1/20W'  | 'DISCRETE' | 'RES CHIP 15K 1/20W +-1%(0201)'                    | 'CHIPR0201'    | ''          | ''            | '20180806'
 '15K'        | '1%'      | '1/20W'  | '0201LF'  | 'EMPTY'  | 'CS31501FE00'(!)        = ''              | ''                 | 'CS31501FE00'           |'R0201'| '(SMR0201AW)'                  | '15K'     | '1%'    | '1/20W'  | 'IO'       | 'RES CHIP 15K 1/20W +-1%(0201)'                    | 'CHIPR0201'    | ''          | ''            | '20180806'
 '15.8K'      | '1%'      | '1/20W'  | '0201LF'  | 'CHIP'   | 'CS31581FE00'(!)        = ''              | ''                 | 'CS31581FE00'           |'R0201'| '(SMR0201AW)'                  | '15.8K'   | '1%'    | '1/20W'  | 'DISCRETE' | 'RES CHIP 15.8K 1/20W +-1%(0201)'                  | 'CHIPR0201'    | ''          | ''            | '20180806'
 '15.8K'      | '1%'      | '1/20W'  | '0201LF'  | 'EMPTY'  | 'CS31581FE00'(!)        = ''              | ''                 | 'CS31581FE00'           |'R0201'| '(SMR0201AW)'                  | '15.8K'   | '1%'    | '1/20W'  | 'IO'       | 'RES CHIP 15.8K 1/20W +-1%(0201)'                  | 'CHIPR0201'    | ''          | ''            | '20180806'
 '475K'       | '1%'      | '1/20W'  | '0201LF'  | 'CHIP'   | 'CS44751FE01'(!)        = ''              | ''                 | 'CS44751FE01'           |'R0201'| '(SMR0201AW)'                  | '475K'    | '1%'    | '1/20W'  | 'DISCRETE' | 'RES CHIP 475K 1/20W +-1%(0201)'                   | 'CHIPR0201'    | ''          | ''            | '20180806'
 '475K'       | '1%'      | '1/20W'  | '0201LF'  | 'EMPTY'  | 'CS44751FE01'(!)        = ''              | ''                 | 'CS44751FE01'           |'R0201'| '(SMR0201AW)'                  | '475K'    | '1%'    | '1/20W'  | 'IO'       | 'RES CHIP 475K 1/20W +-1%(0201)'                   | 'CHIPR0201'    | ''          | ''            | '20180806'
 '10M'        | '5%'      | '1/20W'  | '0201LF'  | 'CHIP'   | 'CS61001JE00'(!)        = ''              | ''                 | 'CS61001JE00'           |'R0201'| '(SMR0201AW)'                  | '10M'     | '5%'    | '1/20W'  | 'DISCRETE' | 'RES CHIP 10M 1/20W +-5%(0201)'                    | 'CHIPR0201'    | ''          | ''            | '20180806'
 '10M'        | '5%'      | '1/20W'  | '0201LF'  | 'EMPTY'  | 'CS61001JE00'(!)        = ''              | ''                 | 'CS61001JE00'           |'R0201'| '(SMR0201AW)'                  | '10M'     | '5%'    | '1/20W'  | 'IO'       | 'RES CHIP 10M 1/20W +-5%(0201)'                    | 'CHIPR0201'    | ''          | ''            | '20180806'
 '18K'        | '1%'      | '1/20W'  | '0201LF'  | 'CHIP'   | 'CS31801FE01'(!)        = ''              | ''                 | 'CS31801FE01'           |'R0201'| '(SMR0201AW)'                  | '18K'     | '1%'    | '1/20W'  | 'DISCRETE' | 'RES CHIP 18K 1/20W +-1%(0201)'                    | 'CHIPR0201'    | ''          | ''            | '20180806'
 '18K'        | '1%'      | '1/20W'  | '0201LF'  | 'EMPTY'  | 'CS31801FE01'(!)        = ''              | ''                 | 'CS31801FE01'           |'R0201'| '(SMR0201AW)'                  | '18K'     | '1%'    | '1/20W'  | 'IO'       | 'RES CHIP 18K 1/20W +-1%(0201)'                    | 'CHIPR0201'    | ''          | ''            | '20180806'
 '1.24K'      | '1%'      | '1/20W'  | '0201LF'  | 'CHIP'   | 'CS21241FE00'(!)        = ''              | ''                 | 'CS21241FE00'           |'R0201'| '(SMR0201AW)'                  | '1.24K'   | '1%'    | '1/20W'  | 'DISCRETE' | 'RES CHIP 1.24K(1/20W,+-1%,0201)'                  | 'CHIPR0201'    | ''          | ''            | '20180806'
 '1.24K'      | '1%'      | '1/20W'  | '0201LF'  | 'EMPTY'  | 'CS21241FE00'(!)        = ''              | ''                 | 'CS21241FE00'           |'R0201'| '(SMR0201AW)'                  | '1.24K'   | '1%'    | '1/20W'  | 'IO'       | 'RES CHIP 1.24K(1/20W,+-1%,0201)'                  | 'CHIPR0201'    | ''          | ''            | '20180806'
 '20K'        | '1%'      | '1/20W'  | '0201LF'  | 'CHIP'   | 'CS32001FE00'(!)        = ''              | ''                 | 'CS32001FE00'           |'R0201'| '(SMR0201AW)'                  | '20K'     | '1%'    | '1/20W'  | 'DISCRETE' | 'RES CHIP 20K 1/20W +-1%(0201)'                    | 'CHIPR0201'    | ''          | ''            | '20180806'
 '20K'        | '1%'      | '1/20W'  | '0201LF'  | 'EMPTY'  | 'CS32001FE00'(!)        = ''              | ''                 | 'CS32001FE00'           |'R0201'| '(SMR0201AW)'                  | '20K'     | '1%'    | '1/20W'  | 'IO'       | 'RES CHIP 20K 1/20W +-1%(0201)'                    | 'CHIPR0201'    | ''          | ''            | '20180806'
 '20K'        | '5%'      | '1/20W'  | '0201LF'  | 'CHIP'   | 'CS32001JE01'(!)        = ''              | ''                 | 'CS32001JE01'           |'R0201'| '(SMR0201AW)'                  | '20K'     | '5%'    | '1/20W'  | 'DISCRETE' | 'RES CHIP 20K 1/20W +-5%(0201)'                    | 'CHIPR0201'    | ''          | ''            | '20180806'
 '20K'        | '5%'      | '1/20W'  | '0201LF'  | 'EMPTY'  | 'CS32001JE01'(!)        = ''              | ''                 | 'CS32001JE01'           |'R0201'| '(SMR0201AW)'                  | '20K'     | '5%'    | '1/20W'  | 'IO'       | 'RES CHIP 20K 1/20W +-5%(0201)'                    | 'CHIPR0201'    | ''          | ''            | '20180806'
 '23.2K'      | '1%'      | '1/20W'  | '0201LF'  | 'CHIP'   | 'CS32321FE00'(!)        = ''              | ''                 | 'CS32321FE00'           |'R0201'| '(SMR0201AW)'                  | '23.2K'   | '1%'    | '1/20W'  | 'DISCRETE' | 'RES CHIP 23.2K 1/20W +-1%(0201)'                  | 'CHIPR0201'    | ''          | ''            | '20180806'
 '23.2K'      | '1%'      | '1/20W'  | '0201LF'  | 'EMPTY'  | 'CS32321FE00'(!)        = ''              | ''                 | 'CS32321FE00'           |'R0201'| '(SMR0201AW)'                  | '23.2K'   | '1%'    | '1/20W'  | 'IO'       | 'RES CHIP 23.2K 1/20W +-1%(0201)'                  | 'CHIPR0201'    | ''          | ''            | '20180806'
 '24.3K'      | '1%'      | '1/20W'  | '0201LF'  | 'CHIP'   | 'CS32431FE01'(!)        = ''              | ''                 | 'CS32431FE01'           |'R0201'| '(SMR0201AW)'                  | '24.3K'   | '1%'    | '1/20W'  | 'DISCRETE' | 'RES CHIP 24.3K 1/20W(+-1%,0201)'                  | 'CHIPR0201'    | ''          | ''            | '20180807'
 '24.3K'      | '1%'      | '1/20W'  | '0201LF'  | 'EMPTY'  | 'CS32431FE01'(!)        = ''              | ''                 | 'CS32431FE01'           |'R0201'| '(SMR0201AW)'                  | '24.3K'   | '1%'    | '1/20W'  | 'IO'       | 'RES CHIP 24.3K 1/20W(+-1%,0201)'                  | 'CHIPR0201'    | ''          | ''            | '20180807'
 '24.9K'      | '1%'      | '1/20W'  | '0201LF'  | 'CHIP'   | 'CS32491FE04'(!)        = ''              | ''                 | 'CS32491FE04'           |'R0201'| '(SMR0201AW)'                  | '24.9K'   | '1%'    | '1/20W'  | 'DISCRETE' | 'RES CHIP 24.9K 1/20W +-1%(0201)'                  | 'CHIPR0201'    | ''          | ''            | '20180807'
 '24.9K'      | '1%'      | '1/20W'  | '0201LF'  | 'EMPTY'  | 'CS32491FE04'(!)        = ''              | ''                 | 'CS32491FE04'           |'R0201'| '(SMR0201AW)'                  | '24.9K'   | '1%'    | '1/20W'  | 'IO'       | 'RES CHIP 24.9K 1/20W +-1%(0201)'                  | 'CHIPR0201'    | ''          | ''            | '20180807'
 '25.5K'      | '1%'      | '1/20W'  | '0201LF'  | 'CHIP'   | 'CS32551FE00'(!)        = ''              | ''                 | 'CS32551FE00'           |'R0201'| '(SMR0201AW)'                  | '25.5K'   | '1%'    | '1/20W'  | 'DISCRETE' | 'RES CHIP 25.5K 1/20W +-1%(0201)'                  | 'CHIPR0201'    | ''          | ''            | '20180807'
 '25.5K'      | '1%'      | '1/20W'  | '0201LF'  | 'EMPTY'  | 'CS32551FE00'(!)        = ''              | ''                 | 'CS32551FE00'           |'R0201'| '(SMR0201AW)'                  | '25.5K'   | '1%'    | '1/20W'  | 'IO'       | 'RES CHIP 25.5K 1/20W +-1%(0201)'                  | 'CHIPR0201'    | ''          | ''            | '20180807'
 '100K'       | '1%'      | '1/20W'  | '0201LF'  | 'CHIP'   | 'CS41001FE08'(!)        = ''              | ''                 | 'CS41001FE08'           |'R0201'| '(SMR0201AW)'                  | '100K'    | '1%'    | '1/20W'  | 'DISCRETE' | 'RES CHIP 100K(1/20W,+-1%,0201)'                   | 'CHIPR0201'    | ''          | ''            | '20180807'
 '100K'       | '1%'      | '1/20W'  | '0201LF'  | 'EMPTY'  | 'CS41001FE08'(!)        = ''              | ''                 | 'CS41001FE08'           |'R0201'| '(SMR0201AW)'                  | '100K'    | '1%'    | '1/20W'  | 'IO'       | 'RES CHIP 100K(1/20W,+-1%,0201)'                   | 'CHIPR0201'    | ''          | ''            | '20180807'
 '133K'       | '1%'      | '1/20W'  | '0201LF'  | 'CHIP'   | 'CS41331FE00'(!)        = ''              | ''                 | 'CS41331FE00'           |'R0201'| '(SMR0201AW)'                  | '133K'    | '1%'    | '1/20W'  | 'DISCRETE' | 'RES CHIP 133K 1/20W +-1%(0201)'                   | 'CHIPR0201'    | ''          | ''            | '20180807'
 '133K'       | '1%'      | '1/20W'  | '0201LF'  | 'EMPTY'  | 'CS41331FE00'(!)        = ''              | ''                 | 'CS41331FE00'           |'R0201'| '(SMR0201AW)'                  | '133K'    | '1%'    | '1/20W'  | 'IO'       | 'RES CHIP 133K 1/20W +-1%(0201)'                   | 'CHIPR0201'    | ''          | ''            | '20180807'
 '169K'       | '1%'      | '1/20W'  | '0201LF'  | 'CHIP'   | 'CS41691FE00'(!)        = ''              | ''                 | 'CS41691FE00'           |'R0201'| '(SMR0201AW)'                  | '169K'    | '1%'    | '1/20W'  | 'DISCRETE' | 'RES CHIP 169K 1/20W +-1%(0201)'                   | 'CHIPR0201'    | ''          | ''            | '20180807'
 '169K'       | '1%'      | '1/20W'  | '0201LF'  | 'EMPTY'  | 'CS41691FE00'(!)        = ''              | ''                 | 'CS41691FE00'           |'R0201'| '(SMR0201AW)'                  | '169K'    | '1%'    | '1/20W'  | 'IO'       | 'RES CHIP 169K 1/20W +-1%(0201)'                   | 'CHIPR0201'    | ''          | ''            | '20180807'
 '249K'       | '1%'      | '1/20W'  | '0201LF'  | 'CHIP'   | 'CS42491FE01'(!)        = ''              | ''                 | 'CS42491FE01'           |'R0201'| '(SMR0201AW)'                  | '249K'    | '1%'    | '1/20W'  | 'DISCRETE' | 'RES CHIP 249K 1/20W +-1%(0201)'                   | 'CHIPR0201'    | ''          | ''            | '20180807'
 '249K'       | '1%'      | '1/20W'  | '0201LF'  | 'EMPTY'  | 'CS42491FE01'(!)        = ''              | ''                 | 'CS42491FE01'           |'R0201'| '(SMR0201AW)'                  | '249K'    | '1%'    | '1/20W'  | 'IO'       | 'RES CHIP 249K 1/20W +-1%(0201)'                   | 'CHIPR0201'    | ''          | ''            | '20180807'
 '1M'         | '1%'      | '1/20W'  | '0201LF'  | 'CHIP'   | 'CS51001FE00'(!)        = ''              | ''                 | 'CS51001FE00'           |'R0201'| '(SMR0201AW)'                  | '1M'      | '1%'    | '1/20W'  | 'DISCRETE' | 'RES CHIP 1M 1/20W +-1%(0201)'                     | 'CHIPR0201'    | ''          | ''            | '20180807'
 '1M'         | '1%'      | '1/20W'  | '0201LF'  | 'EMPTY'  | 'CS51001FE00'(!)        = ''              | ''                 | 'CS51001FE00'           |'R0201'| '(SMR0201AW)'                  | '1M'      | '1%'    | '1/20W'  | 'IO'       | 'RES CHIP 1M 1/20W +-1%(0201)'                     | 'CHIPR0201'    | ''          | ''            | '20180807'
 '10'         | '1%'      | '1/20W'  | '0201LF'  | 'CHIP'   | 'CS01001FE00'(!)        = ''              | ''                 | 'CS01001FE00'           |'R0201'| '(SMR0201AW)'                  | '10'      | '1%'    | '1/20W'  | 'DISCRETE' | 'RES CHIP 10 1/20W +-1%(0201)'                     | 'CHIPR0201'    | ''          | ''            | '20180807'
 '10'         | '1%'      | '1/20W'  | '0201LF'  | 'EMPTY'  | 'CS01001FE00'(!)        = ''              | ''                 | 'CS01001FE00'           |'R0201'| '(SMR0201AW)'                  | '10'      | '1%'    | '1/20W'  | 'IO'       | 'RES CHIP 10 1/20W +-1%(0201)'                     | 'CHIPR0201'    | ''          | ''            | '20180807'
 '510'        | '5%'      | '1/20W'  | '0201LF'  | 'CHIP'   | 'CS15101JE00'(!)        = ''              | ''                 | 'CS15101JE00'           |'R0201'| '(SMR0201AW)'                  | '510'     | '5%'    | '1/20W'  | 'DISCRETE' | 'RES CHIP 510(1/20W,+-5%,0201)'                    | 'CHIPR0201'    | ''          | ''            | '20180807'
 '510'        | '5%'      | '1/20W'  | '0201LF'  | 'EMPTY'  | 'CS15101JE00'(!)        = ''              | ''                 | 'CS15101JE00'           |'R0201'| '(SMR0201AW)'                  | '510'     | '5%'    | '1/20W'  | 'IO'       | 'RES CHIP 510(1/20W,+-5%,0201)'                    | 'CHIPR0201'    | ''          | ''            | '20180807'
 '68.1'       | '1%'      | '1/20W'  | '0201LF'  | 'CHIP'   | 'CS06811FE01'(!)        = ''              | ''                 | 'CS06811FE01'           |'R0201'| '(SMR0201AW)'                  | '68.1'    | '1%'    | '1/20W'  | 'DISCRETE' | 'RES CHIP 68.1 1/20W +-1%(0201)'                   | 'CHIPR0201'    | ''          | ''            | '20180807'
 '68.1'       | '1%'      | '1/20W'  | '0201LF'  | 'EMPTY'  | 'CS06811FE01'(!)        = ''              | ''                 | 'CS06811FE01'           |'R0201'| '(SMR0201AW)'                  | '68.1'    | '1%'    | '1/20W'  | 'IO'       | 'RES CHIP 68.1 1/20W +-1%(0201)'                   | 'CHIPR0201'    | ''          | ''            | '20180807'
 '750'        | '1%'      | '1/20W'  | '0201LF'  | 'CHIP'   | 'CS17501FE00'(!)        = ''              | ''                 | 'CS17501FE00'           |'R0201'| '(SMR0201AW)'                  | '750'     | '1%'    | '1/20W'  | 'DISCRETE' | 'RES CHIP 750 1/20W +-1%(0201)'                    | 'CHIPR0201'    | ''          | ''            | '20180807'
 '750'        | '1%'      | '1/20W'  | '0201LF'  | 'EMPTY'  | 'CS17501FE00'(!)        = ''              | ''                 | 'CS17501FE00'           |'R0201'| '(SMR0201AW)'                  | '750'     | '1%'    | '1/20W'  | 'IO'       | 'RES CHIP 750 1/20W +-1%(0201)'                    | 'CHIPR0201'    | ''          | ''            | '20180807'
 '8.45K'      | '1%'      | '1/20W'  | '0201LF'  | 'CHIP'   | 'CS28451FE01'(!)        = ''              | ''                 | 'CS28451FE01'           |'R0201'| '(SMR0201AW)'                  | '8.45K'   | '1%'    | '1/20W'  | 'DISCRETE' | 'RES CHIP 8.45K 1/20W +-1%(0201)'                  | 'CHIPR0201'    | ''          | ''            | '20180807'
 '8.45K'      | '1%'      | '1/20W'  | '0201LF'  | 'EMPTY'  | 'CS28451FE01'(!)        = ''              | ''                 | 'CS28451FE01'           |'R0201'| '(SMR0201AW)'                  | '8.45K'   | '1%'    | '1/20W'  | 'IO'       | 'RES CHIP 8.45K 1/20W +-1%(0201)'                  | 'CHIPR0201'    | ''          | ''            | '20180807'
 '12.4K'      | '1%'      | '1/20W'  | '0201LF'  | 'CHIP'   | 'CS31241FE02'(!)        = ''              | ''                 | 'CS31241FE02'           |'R0201'| '(SMR0201AW)'                  | '12.4K'   | '1%'    | '1/20W'  | 'DISCRETE' | 'RES CHIP 12.4K 1/20W +-1% (0201) '                | 'CHIPR0201'    | ''          | ''            | '20180807'
 '12.4K'      | '1%'      | '1/20W'  | '0201LF'  | 'EMPTY'  | 'CS31241FE02'(!)        = ''              | ''                 | 'CS31241FE02'           |'R0201'| '(SMR0201AW)'                  | '12.4K'   | '1%'    | '1/20W'  | 'IO'       | 'RES CHIP 12.4K 1/20W +-1% (0201) '                | 'CHIPR0201'    | ''          | ''            | '20180807'
 '19.6K'      | '1%'      | '1/20W'  | '0201LF'  | 'CHIP'   | 'CS31961FE01'(!)        = ''              | ''                 | 'CS31961FE01'           |'R0201'| '(SMR0201AW)'                  | '19.6K'   | '1%'    | '1/20W'  | 'DISCRETE' | 'RES CHIP 19.6K 1/20W +-1%(0201)'                  | 'CHIPR0201'    | ''          | ''            | '20180807'
 '19.6K'      | '1%'      | '1/20W'  | '0201LF'  | 'EMPTY'  | 'CS31961FE01'(!)        = ''              | ''                 | 'CS31961FE01'           |'R0201'| '(SMR0201AW)'                  | '19.6K'   | '1%'    | '1/20W'  | 'IO'       | 'RES CHIP 19.6K 1/20W +-1%(0201)'                  | 'CHIPR0201'    | ''          | ''            | '20180807'
 '44.2'       | '1%'      | '1/20W'  | '0201LF'  | 'CHIP'   | 'CS04421FE00'(!)        = ''              | ''                 | 'CS04421FE00'           |'R0201'| '(SMR0201AW)'                  | '44.2'    | '1%'    | '1/20W'  | 'DISCRETE' | 'RES CHIP 44.2 1/20W +-1%(0201)'                   | 'CHIPR0201'    | ''          | ''            | '20180807'
 '44.2'       | '1%'      | '1/20W'  | '0201LF'  | 'EMPTY'  | 'CS04421FE00'(!)        = ''              | ''                 | 'CS04421FE00'           |'R0201'| '(SMR0201AW)'                  | '44.2'    | '1%'    | '1/20W'  | 'IO'       | 'RES CHIP 44.2 1/20W +-1%(0201)'                   | 'CHIPR0201'    | ''          | ''            | '20180807'
 '33K'        | '1%'      | '1/20W'  | '0201LF'  | 'CHIP'   | 'CS33301FE00'(!)        = ''              | ''                 | 'CS33301FE00'           |'R0201'| '(SMR0201AW)'                  | '33K'     | '1%'    | '1/20W'  | 'DISCRETE' | 'RES CHIP 33K(1/20W,+-1%,0201)'                    | 'CHIPR0201'    | ''          | ''            | '20180807'
 '33K'        | '1%'      | '1/20W'  | '0201LF'  | 'EMPTY'  | 'CS33301FE00'(!)        = ''              | ''                 | 'CS33301FE00'           |'R0201'| '(SMR0201AW)'                  | '33K'     | '1%'    | '1/20W'  | 'IO'       | 'RES CHIP 33K(1/20W,+-1%,0201)'                    | 'CHIPR0201'    | ''          | ''            | '20180807'
 '37.4K'      | '1%'      | '1/20W'  | '0201LF'  | 'CHIP'   | 'CS33741FE01'(!)        = ''              | ''                 | 'CS33741FE01'           |'R0201'| '(SMR0201AW)'                  | '37.4K'   | '1%'    | '1/20W'  | 'DISCRETE' | 'RES CHIP 37.4K(1/20W,+-1%,0201)'                  | 'CHIPR0201'    | ''          | ''            | '20180807'
 '37.4K'      | '1%'      | '1/20W'  | '0201LF'  | 'EMPTY'  | 'CS33741FE01'(!)        = ''              | ''                 | 'CS33741FE01'           |'R0201'| '(SMR0201AW)'                  | '37.4K'   | '1%'    | '1/20W'  | 'IO'       | 'RES CHIP 37.4K(1/20W,+-1%,0201)'                  | 'CHIPR0201'    | ''          | ''            | '20180807'
 '39.2K'      | '1%'      | '1/20W'  | '0201LF'  | 'CHIP'   | 'CS33921FE00'(!)        = ''              | ''                 | 'CS33921FE00'           |'R0201'| '(SMR0201AW)'                  | '39.2K'   | '1%'    | '1/20W'  | 'DISCRETE' | 'RES CHIP 39.2K 1/20W +-1%(0201)'                  | 'CHIPR0201'    | ''          | ''            | '20180807'
 '39.2K'      | '1%'      | '1/20W'  | '0201LF'  | 'EMPTY'  | 'CS33921FE00'(!)        = ''              | ''                 | 'CS33921FE00'           |'R0201'| '(SMR0201AW)'                  | '39.2K'   | '1%'    | '1/20W'  | 'IO'       | 'RES CHIP 39.2K 1/20W +-1%(0201)'                  | 'CHIPR0201'    | ''          | ''            | '20180807'
 '47.5K'      | '1%'      | '1/20W'  | '0201LF'  | 'CHIP'   | 'CS34751FE02'(!)        = ''              | ''                 | 'CS34751FE02'           |'R0201'| '(SMR0201AW)'                  | '47.5K'   | '1%'    | '1/20W'  | 'DISCRETE' | 'RES CHIP 47.5K 1/20W +-1%(0201)'                  | 'CHIPR0201'    | ''          | ''            | '20180807'
 '47.5K'      | '1%'      | '1/20W'  | '0201LF'  | 'EMPTY'  | 'CS34751FE02'(!)        = ''              | ''                 | 'CS34751FE02'           |'R0201'| '(SMR0201AW)'                  | '47.5K'   | '1%'    | '1/20W'  | 'IO'       | 'RES CHIP 47.5K 1/20W +-1%(0201)'                  | 'CHIPR0201'    | ''          | ''            | '20180807'
 '52.3K'      | '1%'      | '1/20W'  | '0201LF'  | 'CHIP'   | 'CS35231FE01'(!)        = ''              | ''                 | 'CS35231FE01'           |'R0201'| '(SMR0201AW)'                  | '52.3K'   | '1%'    | '1/20W'  | 'DISCRETE' | 'RES CHIP 52.3K 1/20W +-1%(0201)'                  | 'CHIPR0201'    | ''          | ''            | '20180807'
 '52.3K'      | '1%'      | '1/20W'  | '0201LF'  | 'EMPTY'  | 'CS35231FE01'(!)        = ''              | ''                 | 'CS35231FE01'           |'R0201'| '(SMR0201AW)'                  | '52.3K'   | '1%'    | '1/20W'  | 'IO'       | 'RES CHIP 52.3K 1/20W +-1%(0201)'                  | 'CHIPR0201'    | ''          | ''            | '20180807'
 '64.9K'      | '1%'      | '1/20W'  | '0201LF'  | 'CHIP'   | 'CS36491FE00'(!)        = ''              | ''                 | 'CS36491FE00'           |'R0201'| '(SMR0201AW)'                  | '64.9K'   | '1%'    | '1/20W'  | 'DISCRETE' | 'RES CHIP 64.9K 1/20W +-1%(0201)'                  | 'CHIPR0201'    | ''          | ''            | '20180807'
 '64.9K'      | '1%'      | '1/20W'  | '0201LF'  | 'EMPTY'  | 'CS36491FE00'(!)        = ''              | ''                 | 'CS36491FE00'           |'R0201'| '(SMR0201AW)'                  | '64.9K'   | '1%'    | '1/20W'  | 'IO'       | 'RES CHIP 64.9K 1/20W +-1%(0201)'                  | 'CHIPR0201'    | ''          | ''            | '20180807'
 '66.5K'      | '1%'      | '1/20W'  | '0201LF'  | 'CHIP'   | 'CS36651FE04'(!)        = ''              | ''                 | 'CS36651FE04'           |'R0201'| '(SMR0201AW)'                  | '66.5K'   | '1%'    | '1/20W'  | 'DISCRETE' | 'RES CHIP 66.5K 1/20W +-1%(0201)'                  | 'CHIPR0201'    | ''          | ''            | '20180807'
 '66.5K'      | '1%'      | '1/20W'  | '0201LF'  | 'EMPTY'  | 'CS36651FE04'(!)        = ''              | ''                 | 'CS36651FE04'           |'R0201'| '(SMR0201AW)'                  | '66.5K'   | '1%'    | '1/20W'  | 'IO'       | 'RES CHIP 66.5K 1/20W +-1%(0201)'                  | 'CHIPR0201'    | ''          | ''            | '20180807'
 '97.6K'      | '1%'      | '1/20W'  | '0201LF'  | 'CHIP'   | 'CS39761FE00'(!)        = ''              | ''                 | 'CS39761FE00'           |'R0201'| '(SMR0201AW)'                  | '97.6K'   | '1%'    | '1/20W'  | 'DISCRETE' | 'RES CHIP 97.6K 1/20W,+-1%(0201)'                  | 'CHIPR0201'    | ''          | ''            | '20180807'
 '97.6K'      | '1%'      | '1/20W'  | '0201LF'  | 'EMPTY'  | 'CS39761FE00'(!)        = ''              | ''                 | 'CS39761FE00'           |'R0201'| '(SMR0201AW)'                  | '97.6K'   | '1%'    | '1/20W'  | 'IO'       | 'RES CHIP 97.6K 1/20W,+-1%(0201)'                  | 'CHIPR0201'    | ''          | ''            | '20180807'
 '107K'       | '1%'      | '1/20W'  | '0201LF'  | 'CHIP'   | 'CS41071FE00'(!)        = ''              | ''                 | 'CS41071FE00'           |'R0201'| '(SMR0201AW)'                  | '107K'    | '1%'    | '1/20W'  | 'DISCRETE' | 'RES CHIP 107K 1/20W +-1%(0201)'                   | 'CHIPR0201'    | ''          | ''            | '20180807'
 '107K'       | '1%'      | '1/20W'  | '0201LF'  | 'EMPTY'  | 'CS41071FE00'(!)        = ''              | ''                 | 'CS41071FE00'           |'R0201'| '(SMR0201AW)'                  | '107K'    | '1%'    | '1/20W'  | 'IO'       | 'RES CHIP 107K 1/20W +-1%(0201)'                   | 'CHIPR0201'    | ''          | ''            | '20180807'
 '124K'       | '1%'      | '1/20W'  | '0201LF'  | 'CHIP'   | 'CS41241FE01'(!)        = ''              | ''                 | 'CS41241FE01'           |'R0201'| '(SMR0201AW)'                  | '124K'    | '1%'    | '1/20W'  | 'DISCRETE' | 'RES CHIP 124K 1/20W +-1%(0201)'                   | 'CHIPR0201'    | ''          | ''            | '20180807'
 '124K'       | '1%'      | '1/20W'  | '0201LF'  | 'EMPTY'  | 'CS41241FE01'(!)        = ''              | ''                 | 'CS41241FE01'           |'R0201'| '(SMR0201AW)'                  | '124K'    | '1%'    | '1/20W'  | 'IO'       | 'RES CHIP 124K 1/20W +-1%(0201)'                   | 'CHIPR0201'    | ''          | ''            | '20180807'
 '130K'       | '1%'      | '1/20W'  | '0201LF'  | 'CHIP'   | 'CS41301FE00'(!)        = ''              | ''                 | 'CS41301FE00'           |'R0201'| '(SMR0201AW)'                  | '130K'    | '1%'    | '1/20W'  | 'DISCRETE' | 'RES CHIP 130K 1/20W +-1%(0201)'                   | 'CHIPR0201'    | ''          | ''            | '20180807'
 '130K'       | '1%'      | '1/20W'  | '0201LF'  | 'EMPTY'  | 'CS41301FE00'(!)        = ''              | ''                 | 'CS41301FE00'           |'R0201'| '(SMR0201AW)'                  | '130K'    | '1%'    | '1/20W'  | 'IO'       | 'RES CHIP 130K 1/20W +-1%(0201)'                   | 'CHIPR0201'    | ''          | ''            | '20180807'
 '412K'       | '1%'      | '1/20W'  | '0201LF'  | 'CHIP'   | 'CS44121FE00'(!)        = ''              | ''                 | 'CS44121FE00'           |'R0201'| '(SMR0201AW)'                  | '412K'    | '1%'    | '1/20W'  | 'DISCRETE' | 'RES CHIP 412K 1/20W +1%(0201)'                    | 'CHIPR0201'    | ''          | ''            | '20180807'
 '412K'       | '1%'      | '1/20W'  | '0201LF'  | 'EMPTY'  | 'CS44121FE00'(!)        = ''              | ''                 | 'CS44121FE00'           |'R0201'| '(SMR0201AW)'                  | '412K'    | '1%'    | '1/20W'  | 'IO'       | 'RES CHIP 412K 1/20W +1%(0201)'                    | 'CHIPR0201'    | ''          | ''            | '20180807'
 '470K'       | '1%'      | '1/20W'  | '0201LF'  | 'CHIP'   | 'CS44701FE00'(!)        = 'End of Design' | 'Comp-Approve'     | 'CS44701FE00'           |'R0201'| '(SMR0201AW)'                  | '470K'    | '1%'    | '1/20W'  | 'DISCRETE' | 'RES CHIP 470K 1/20W +-1%(0201)'                   | 'CHIPR0201'    | ''          | ''            | '20180807'
 '470K'       | '1%'      | '1/20W'  | '0201LF'  | 'EMPTY'  | 'CS44701FE00'(!)        = 'End of Design' | 'Comp-Approve'     | 'CS44701FE00'           |'R0201'| '(SMR0201AW)'                  | '470K'    | '1%'    | '1/20W'  | 'IO'       | 'RES CHIP 470K 1/20W +-1%(0201)'                   | 'CHIPR0201'    | ''          | ''            | '20180807'
 '510K'       | '5%'      | '1/20W'  | '0201LF'  | 'CHIP'   | 'CS45101JE00'(!)        = ''              | ''                 | 'CS45101JE00'           |'R0201'| '(SMR0201AW)'                  | '510K'    | '5%'    | '1/20W'  | 'DISCRETE' | 'RES CHIP 510K 1/20W +-5%(0201)'                   | 'CHIPR0201'    | ''          | ''            | '20180807'
 '510K'       | '5%'      | '1/20W'  | '0201LF'  | 'EMPTY'  | 'CS45101JE00'(!)        = ''              | ''                 | 'CS45101JE00'           |'R0201'| '(SMR0201AW)'                  | '510K'    | '5%'    | '1/20W'  | 'IO'       | 'RES CHIP 510K 1/20W +-5%(0201)'                   | 'CHIPR0201'    | ''          | ''            | '20180807'
 '562K'       | '1%'      | '1/20W'  | '0201LF'  | 'CHIP'   | 'CS45621FE00'(!)        = ''              | ''                 | 'CS45621FE00'           |'R0201'| '(SMR0201AW)'                  | '562K'    | '1%'    | '1/20W'  | 'DISCRETE' | 'RES CHIP 562K 1/20W +-1%(0201)'                   | 'CHIPR0201'    | ''          | ''            | '20180807'
 '562K'       | '1%'      | '1/20W'  | '0201LF'  | 'EMPTY'  | 'CS45621FE00'(!)        = ''              | ''                 | 'CS45621FE00'           |'R0201'| '(SMR0201AW)'                  | '562K'    | '1%'    | '1/20W'  | 'IO'       | 'RES CHIP 562K 1/20W +-1%(0201)'                   | 'CHIPR0201'    | ''          | ''            | '20180807'
 '10M'        | '1%'      | '1/20W'  | '0201LF'  | 'CHIP'   | 'CS61001FE00'(!)        = ''              | ''                 | 'CS61001FE00'           |'R0201'| '(SMR0201AW)'                  | '10M'     | '1%'    | '1/20W'  | 'DISCRETE' | 'RES CHIP 10M 1/20W +-1%(0201)'                    | 'CHIPR0201'    | ''          | ''            | '20180807'
 '10M'        | '1%'      | '1/20W'  | '0201LF'  | 'EMPTY'  | 'CS61001FE00'(!)        = ''              | ''                 | 'CS61001FE00'           |'R0201'| '(SMR0201AW)'                  | '10M'     | '1%'    | '1/20W'  | 'IO'       | 'RES CHIP 10M 1/20W +-1%(0201)'                    | 'CHIPR0201'    | ''          | ''            | '20180807'
 '27K'        | '1%'      | '1/20W'  | '0201LF'  | 'CHIP'   | 'CS32701FE01'(!)        = ''              | ''                 | 'CS32701FE01'           |'R0201'| '(SMR0201AW)'                  | '27K'     | '1%'    | '1/20W'  | 'DISCRETE' | 'RES CHIP 27K(1/20W,+-1%,0201)'                    | 'CHIPR0201'    | ''          | ''            | '20180807'
 '27K'        | '1%'      | '1/20W'  | '0201LF'  | 'EMPTY'  | 'CS32701FE01'(!)        = ''              | ''                 | 'CS32701FE01'           |'R0201'| '(SMR0201AW)'                  | '27K'     | '1%'    | '1/20W'  | 'IO'       | 'RES CHIP 27K(1/20W,+-1%,0201)'                    | 'CHIPR0201'    | ''          | ''            | '20180807'
 '30.1K'      | '1%'      | '1/20W'  | '0201LF'  | 'CHIP'   | 'CS33011FE00'(!)        = 'End of Design' | 'Comp-Approve'     | 'CS33011FE00'           |'R0201'| '(SMR0201AW)'                  | '30.1K'   | '1%'    | '1/20W'  | 'DISCRETE' | 'RES CHIP 30.1K 1/20W +-1%(0201)'                  | 'CHIPR0201'    | ''          | ''            | '20180807'
 '30.1K'      | '1%'      | '1/20W'  | '0201LF'  | 'EMPTY'  | 'CS33011FE00'(!)        = 'End of Design' | 'Comp-Approve'     | 'CS33011FE00'           |'R0201'| '(SMR0201AW)'                  | '30.1K'   | '1%'    | '1/20W'  | 'IO'       | 'RES CHIP 30.1K 1/20W +-1%(0201)'                  | 'CHIPR0201'    | ''          | ''            | '20180807'
 '220K'       | '5%'      | '1/20W'  | '0201LF'  | 'CHIP'   | 'CS42201JE00'(!)        = ''              | ''                 | 'CS42201JE00'           |'R0201'| '(SMR0201AW)'                  | '220K'    | '5%'    | '1/20W'  | 'DISCRETE' | 'RES CHIP 220K 1/20W +-5% (0201)'                  | 'CHIPR0201'    | ''          | ''            | '20180807'
 '220K'       | '5%'      | '1/20W'  | '0201LF'  | 'EMPTY'  | 'CS42201JE00'(!)        = ''              | ''                 | 'CS42201JE00'           |'R0201'| '(SMR0201AW)'                  | '220K'    | '5%'    | '1/20W'  | 'IO'       | 'RES CHIP 220K 1/20W +-5% (0201)'                  | 'CHIPR0201'    | ''          | ''            | '20180807'
 '20'         | '1%'      | '1/20W'  | '0201LF'  | 'CHIP'   | 'CS02001FE00'(!)        = ''              | ''                 | 'CS02001FE00'           |'R0201'| '(SMR0201AW)'                  | '20'      | '1%'    | '1/20W'  | 'DISCRETE' | 'RES CHIP 20 1/20W +-1%(0201)'                     | 'CHIPR0201'    | ''          | ''            | '20120118'
 '20'         | '1%'      | '1/20W'  | '0201LF'  | 'EMPTY'  | 'CS02001FE00'(!)        = ''              | ''                 | 'CS02001FE00'           |'R0201'| '(SMR0201AW)'                  | '20'      | '1%'    | '1/20W'  | 'IO'       | 'RES CHIP 20 1/20W +-1%(0201)'                     | 'CHIPR0201'    | ''          | ''            | '20120118'
 '121'        | '1%'      | '1/20W'  | '0201LF'  | 'CHIP'   | 'CS11211FE00'(!)        = ''              | ''                 | 'CS11211FE00'           |'R0201'| '(SMR0201AW)'                  | '121'     | '1%'    | '1/20W'  | 'DISCRETE' | 'RES CHIP 121 1/20W +-1%(0201)'                    | 'CHIPR0201'    | ''          | ''            | '20180808'
 '121'        | '1%'      | '1/20W'  | '0201LF'  | 'EMPTY'  | 'CS11211FE00'(!)        = ''              | ''                 | 'CS11211FE00'           |'R0201'| '(SMR0201AW)'                  | '121'     | '1%'    | '1/20W'  | 'IO'       | 'RES CHIP 121 1/20W +-1%(0201)'                    | 'CHIPR0201'    | ''          | ''            | '20180808'
 '2.4K'       | '1%'      | '1/20W'  | '0201LF'  | 'CHIP'   | 'CS22401FE00'(!)        = ''              | ''                 | 'CS22401FE00'           |'R0201'| '(SMR0201AW)'                  | '2.4K'    | '1%'    | '1/20W'  | 'DISCRETE' | 'RES CHIP 2.4K 1/20W +-1%(0201)'                   | 'CHIPR0201'    | ''          | ''            | '20180808'
 '2.4K'       | '1%'      | '1/20W'  | '0201LF'  | 'EMPTY'  | 'CS22401FE00'(!)        = ''              | ''                 | 'CS22401FE00'           |'R0201'| '(SMR0201AW)'                  | '2.4K'    | '1%'    | '1/20W'  | 'IO'       | 'RES CHIP 2.4K 1/20W +-1%(0201)'                   | 'CHIPR0201'    | ''          | ''            | '20180808'
 '2.49K'      | '1%'      | '1/20W'  | '0201LF'  | 'CHIP'   | 'CS22491FE00'(!)        = 'End of Design' | 'Comp-Approve'     | 'CS22491FE00'           |'R0201'| '(SMR0201AW)'                  | '2.49K'   | '1%'    | '1/20W'  | 'DISCRETE' | 'RES CHIP 2.49K(1/20W.+-1%.0201)HF'                | 'CHIPR0201'    | ''          | ''            | '20110106'
 '2.49K'      | '1%'      | '1/20W'  | '0201LF'  | 'EMPTY'  | 'CS22491FE00'(!)        = 'End of Design' | 'Comp-Approve'     | 'CS22491FE00'           |'R0201'| '(SMR0201AW)'                  | '2.49K'   | '1%'    | '1/20W'  | 'IO'       | 'RES CHIP 2.49K(1/20W.+-1%.0201)HF'                | 'CHIPR0201'    | ''          | ''            | '20110106'
 '2.7K'       | '5%'      | '1/20W'  | '0201LF'  | 'CHIP'   | 'CS22701JE00'(!)        = ''              | ''                 | 'CS22701JE00'           |'R0201'| '(SMR0201AW)'                  | '2.7K'    | '5%'    | '1/20W'  | 'DISCRETE' | 'RES CHIP 2.7K 1/20W +-5%(0201)'                   | 'CHIPR0201'    | ''          | ''            | '20180808'
 '2.7K'       | '5%'      | '1/20W'  | '0201LF'  | 'EMPTY'  | 'CS22701JE00'(!)        = ''              | ''                 | 'CS22701JE00'           |'R0201'| '(SMR0201AW)'                  | '2.7K'    | '5%'    | '1/20W'  | 'IO'       | 'RES CHIP 2.7K 1/20W +-5%(0201)'                   | 'CHIPR0201'    | ''          | ''            | '20180808'
 '4.02K'      | '1%'      | '1/20W'  | '0201LF'  | 'CHIP'   | 'CS24021FE01'(!)        = ''              | ''                 | 'CS24021FE01'           |'R0201'| '(SMR0201AW)'                  | '4.02K'   | '1%'    | '1/20W'  | 'DISCRETE' | 'RES CHIP 4.02K 1/20W +-1%(0201)'                  | 'CHIPR0201'    | ''          | ''            | '20180808'
 '4.02K'      | '1%'      | '1/20W'  | '0201LF'  | 'EMPTY'  | 'CS24021FE01'(!)        = ''              | ''                 | 'CS24021FE01'           |'R0201'| '(SMR0201AW)'                  | '4.02K'   | '1%'    | '1/20W'  | 'IO'       | 'RES CHIP 4.02K 1/20W +-1%(0201)'                  | 'CHIPR0201'    | ''          | ''            | '20180808'
 '4.42K'      | '1%'      | '1/20W'  | '0201LF'  | 'CHIP'   | 'CS24421FE01'(!)        = ''              | ''                 | 'CS24421FE01'           |'R0201'| '(SMR0201AW)'                  | '4.42K'   | '1%'    | '1/20W'  | 'DISCRETE' | 'RES CHIP 4.42K 1/20W +-1%(0201)'                  | 'CHIPR0201'    | ''          | ''            | '20180808'
 '4.42K'      | '1%'      | '1/20W'  | '0201LF'  | 'EMPTY'  | 'CS24421FE01'(!)        = ''              | ''                 | 'CS24421FE01'           |'R0201'| '(SMR0201AW)'                  | '4.42K'   | '1%'    | '1/20W'  | 'IO'       | 'RES CHIP 4.42K 1/20W +-1%(0201)'                  | 'CHIPR0201'    | ''          | ''            | '20180808'
 '4.75K'      | '1%'      | '1/20W'  | '0201LF'  | 'CHIP'   | 'CS24751FE01'(!)        = ''              | ''                 | 'CS24751FE01'           |'R0201'| '(SMR0201AW)'                  | '4.75K'   | '1%'    | '1/20W'  | 'DISCRETE' | 'RES CHIP 4.75K (1/20W,+-1%,0201)'                 | 'CHIPR0201'    | ''          | ''            | '20180808'
 '4.75K'      | '1%'      | '1/20W'  | '0201LF'  | 'EMPTY'  | 'CS24751FE01'(!)        = ''              | ''                 | 'CS24751FE01'           |'R0201'| '(SMR0201AW)'                  | '4.75K'   | '1%'    | '1/20W'  | 'IO'       | 'RES CHIP 4.75K (1/20W,+-1%,0201)'                 | 'CHIPR0201'    | ''          | ''            | '20180808'
 '4.87K'      | '1%'      | '1/20W'  | '0201LF'  | 'CHIP'   | 'CS24871FE00'(!)        = ''              | ''                 | 'CS24871FE00'           |'R0201'| '(SMR0201AW)'                  | '4.87K'   | '1%'    | '1/20W'  | 'DISCRETE' | 'RES CHIP 4.87K 1/20W +-1%(0201)'                  | 'CHIPR0201'    | ''          | ''            | '20180808'
 '4.87K'      | '1%'      | '1/20W'  | '0201LF'  | 'EMPTY'  | 'CS24871FE00'(!)        = ''              | ''                 | 'CS24871FE00'           |'R0201'| '(SMR0201AW)'                  | '4.87K'   | '1%'    | '1/20W'  | 'IO'       | 'RES CHIP 4.87K 1/20W +-1%(0201)'                  | 'CHIPR0201'    | ''          | ''            | '20180808'
 '34.8K'      | '1%'      | '1/20W'  | '0201LF'  | 'CHIP'   | 'CS33481FE01'(!)        = ''              | ''                 | 'CS33481FE01'           |'R0201'| '(SMR0201AW)'                  | '34.8K'   | '1%'    | '1/20W'  | 'DISCRETE' | 'RES CHIP 34.8K 1/20W +-1%(0201)'                  | 'CHIPR0201'    | ''          | ''            | '20180808'
 '34.8K'      | '1%'      | '1/20W'  | '0201LF'  | 'EMPTY'  | 'CS33481FE01'(!)        = ''              | ''                 | 'CS33481FE01'           |'R0201'| '(SMR0201AW)'                  | '34.8K'   | '1%'    | '1/20W'  | 'IO'       | 'RES CHIP 34.8K 1/20W +-1%(0201)'                  | 'CHIPR0201'    | ''          | ''            | '20180808'
 '6.19K'      | '1%'      | '1/20W'  | '0201LF'  | 'CHIP'   | 'CS26191FE00'(!)        = ''              | ''                 | 'CS26191FE00'           |'R0201'| '(SMR0201AW)'                  | '6.19K'   | '1%'    | '1/20W'  | 'DISCRETE' | 'RES CHIP 6.19K 1/20W +-1%(0201)'                  | 'CHIPR0201'    | ''          | ''            | '20180808'
 '6.19K'      | '1%'      | '1/20W'  | '0201LF'  | 'EMPTY'  | 'CS26191FE00'(!)        = ''              | ''                 | 'CS26191FE00'           |'R0201'| '(SMR0201AW)'                  | '6.19K'   | '1%'    | '1/20W'  | 'IO'       | 'RES CHIP 6.19K 1/20W +-1%(0201)'                  | 'CHIPR0201'    | ''          | ''            | '20180808'
 '402'        | '1%'      | '1/20W'  | '0201LF'  | 'CHIP'   | 'CS14021FE01'(!)        = ''              | ''                 | 'CS14021FE01'           |'R0201'| '(SMR0201AW)'                  | '402'     | '1%'    | '1/20W'  | 'DISCRETE' | 'RES CHIP 402 1/20W +-1%(0201)'                    | 'CHIPR0201'    | ''          | ''            | '20180808'
 '402'        | '1%'      | '1/20W'  | '0201LF'  | 'EMPTY'  | 'CS14021FE01'(!)        = ''              | ''                 | 'CS14021FE01'           |'R0201'| '(SMR0201AW)'                  | '402'     | '1%'    | '1/20W'  | 'IO'       | 'RES CHIP 402 1/20W +-1%(0201)'                    | 'CHIPR0201'    | ''          | ''            | '20180808'
 '6.81K'      | '1%'      | '1/20W'  | '0201LF'  | 'CHIP'   | 'CS26811FE00'(!)        = ''              | ''                 | 'CS26811FE00'           |'R0201'| '(SMR0201AW)'                  | '6.81K'   | '1%'    | '1/20W'  | 'DISCRETE' | 'RES CHIP 6.81K 1/20W +-1%(0201)'                  | 'CHIPR0201'    | ''          | ''            | '20180808'
 '6.81K'      | '1%'      | '1/20W'  | '0201LF'  | 'EMPTY'  | 'CS26811FE00'(!)        = ''              | ''                 | 'CS26811FE00'           |'R0201'| '(SMR0201AW)'                  | '6.81K'   | '1%'    | '1/20W'  | 'IO'       | 'RES CHIP 6.81K 1/20W +-1%(0201)'                  | 'CHIPR0201'    | ''          | ''            | '20180808'
 '7.5K'       | '1%'      | '1/20W'  | '0201LF'  | 'CHIP'   | 'CS27501FE00'(!)        = ''              | ''                 | 'CS27501FE00'           |'R0201'| '(SMR0201AW)'                  | '7.5K'    | '1%'    | '1/20W'  | 'DISCRETE' | 'RES CHIP 7.5K 1/20W +-1%(0201)'                   | 'CHIPR0201'    | ''          | ''            | '20180808'
 '7.5K'       | '1%'      | '1/20W'  | '0201LF'  | 'EMPTY'  | 'CS27501FE00'(!)        = ''              | ''                 | 'CS27501FE00'           |'R0201'| '(SMR0201AW)'                  | '7.5K'    | '1%'    | '1/20W'  | 'IO'       | 'RES CHIP 7.5K 1/20W +-1%(0201)'                   | 'CHIPR0201'    | ''          | ''            | '20180808'
 '8.66K'      | '1%'      | '1/20W'  | '0201LF'  | 'CHIP'   | 'CS28661FE00'(!)        = ''              | ''                 | 'CS28661FE00'           |'R0201'| '(SMR0201AW)'                  | '8.66K'   | '1%'    | '1/20W'  | 'DISCRETE' | 'RES CHIP 8.66K 1/20W,+-1%(0201)'                  | 'CHIPR0201'    | ''          | ''            | '20180808'
 '8.66K'      | '1%'      | '1/20W'  | '0201LF'  | 'EMPTY'  | 'CS28661FE00'(!)        = ''              | ''                 | 'CS28661FE00'           |'R0201'| '(SMR0201AW)'                  | '8.66K'   | '1%'    | '1/20W'  | 'IO'       | 'RES CHIP 8.66K 1/20W,+-1%(0201)'                  | 'CHIPR0201'    | ''          | ''            | '20180808'
 '11K'        | '1%'      | '1/20W'  | '0201LF'  | 'CHIP'   | 'CS31101FE00'(!)        = ''              | ''                 | 'CS31101FE00'           |'R0201'| '(SMR0201AW)'                  | '11K'     | '1%'    | '1/20W'  | 'DISCRETE' | 'RES CHIP 11K 1/20W +-1% (0201)'                   | 'CHIPR0201'    | ''          | ''            | '20180808'
 '11K'        | '1%'      | '1/20W'  | '0201LF'  | 'EMPTY'  | 'CS31101FE00'(!)        = ''              | ''                 | 'CS31101FE00'           |'R0201'| '(SMR0201AW)'                  | '11K'     | '1%'    | '1/20W'  | 'IO'       | 'RES CHIP 11K 1/20W +-1% (0201)'                   | 'CHIPR0201'    | ''          | ''            | '20180808'
 '11.8K'      | '1%'      | '1/20W'  | '0201LF'  | 'CHIP'   | 'CS31181FE01'(!)        = ''              | ''                 | 'CS31181FE01'           |'R0201'| '(SMR0201AW)'                  | '11.8K'   | '1%'    | '1/20W'  | 'DISCRETE' | 'RES CHIP 11.8K 1/20W +-1%(0201)'                  | 'CHIPR0201'    | ''          | ''            | '20180809'
 '11.8K'      | '1%'      | '1/20W'  | '0201LF'  | 'EMPTY'  | 'CS31181FE01'(!)        = ''              | ''                 | 'CS31181FE01'           |'R0201'| '(SMR0201AW)'                  | '11.8K'   | '1%'    | '1/20W'  | 'IO'       | 'RES CHIP 11.8K 1/20W +-1%(0201)'                  | 'CHIPR0201'    | ''          | ''            | '20180809'
 '12.1K'      | '1%'      | '1/20W'  | '0201LF'  | 'CHIP'   | 'CS31211FE08'(!)        = ''              | ''                 | 'CS31211FE08'           |'R0201'| '(SMR0201AW)'                  | '12.1K'   | '1%'    | '1/20W'  | 'DISCRETE' | 'RES CHIP 12.1K 1/20W +-1%(0201)'                  | 'CHIPR0201'    | ''          | ''            | '20180809'
 '12.1K'      | '1%'      | '1/20W'  | '0201LF'  | 'EMPTY'  | 'CS31211FE08'(!)        = ''              | ''                 | 'CS31211FE08'           |'R0201'| '(SMR0201AW)'                  | '12.1K'   | '1%'    | '1/20W'  | 'IO'       | 'RES CHIP 12.1K 1/20W +-1%(0201)'                  | 'CHIPR0201'    | ''          | ''            | '20180809'
 '13K'        | '1%'      | '1/20W'  | '0201LF'  | 'CHIP'   | 'CS31301FE01'(!)        = ''              | ''                 | 'CS31301FE01'           |'R0201'| '(SMR0201AW)'                  | '13K'     | '1%'    | '1/20W'  | 'DISCRETE' | 'RES CHIP 13K 1/20W +-1%(0201)'                    | 'CHIPR0201'    | ''          | ''            | '20180808'
 '13K'        | '1%'      | '1/20W'  | '0201LF'  | 'EMPTY'  | 'CS31301FE01'(!)        = ''              | ''                 | 'CS31301FE01'           |'R0201'| '(SMR0201AW)'                  | '13K'     | '1%'    | '1/20W'  | 'IO'       | 'RES CHIP 13K 1/20W +-1%(0201)'                    | 'CHIPR0201'    | ''          | ''            | '20180808'
 '14K'        | '1%'      | '1/20W'  | '0201LF'  | 'CHIP'   | 'CS31401FE01'(!)        = ''              | ''                 | 'CS31401FE01'           |'R0201'| '(SMR0201AW)'                  | '14K'     | '1%'    | '1/20W'  | 'DISCRETE' | 'RES CHIP 14K 1/20W +-1%(0201)'                    | 'CHIPR0201'    | ''          | ''            | '20180808'
 '14K'        | '1%'      | '1/20W'  | '0201LF'  | 'EMPTY'  | 'CS31401FE01'(!)        = ''              | ''                 | 'CS31401FE01'           |'R0201'| '(SMR0201AW)'                  | '14K'     | '1%'    | '1/20W'  | 'IO'       | 'RES CHIP 14K 1/20W +-1%(0201)'                    | 'CHIPR0201'    | ''          | ''            | '20180808'
 '14.3K'      | '1%'      | '1/20W'  | '0201LF'  | 'CHIP'   | 'CS31431FE00'(!)        = ''              | ''                 | 'CS31431FE00'           |'R0201'| '(SMR0201AW)'                  | '14.3K'   | '1%'    | '1/20W'  | 'DISCRETE' | 'RES CHIP 14.3K 1/20W +-1%(0201)'                  | 'CHIPR0201'    | ''          | ''            | '20180808'
 '14.3K'      | '1%'      | '1/20W'  | '0201LF'  | 'EMPTY'  | 'CS31431FE00'(!)        = ''              | ''                 | 'CS31431FE00'           |'R0201'| '(SMR0201AW)'                  | '14.3K'   | '1%'    | '1/20W'  | 'IO'       | 'RES CHIP 14.3K 1/20W +-1%(0201)'                  | 'CHIPR0201'    | ''          | ''            | '20180808'
 '47.5'       | '1%'      | '1/20W'  | '0201LF'  | 'CHIP'   | 'CS04751FE00'(!)        = ''              | ''                 | 'CS04751FE00'           |'R0201'| '(SMR0201AW)'                  | '47.5'    | '1%'    | '1/20W'  | 'DISCRETE' | 'RES CHIP 47.5 1/20W +-1%(0201)'                   | 'CHIPR0201'    | ''          | ''            | '20180808'
 '47.5'       | '1%'      | '1/20W'  | '0201LF'  | 'EMPTY'  | 'CS04751FE00'(!)        = ''              | ''                 | 'CS04751FE00'           |'R0201'| '(SMR0201AW)'                  | '47.5'    | '1%'    | '1/20W'  | 'IO'       | 'RES CHIP 47.5 1/20W +-1%(0201)'                   | 'CHIPR0201'    | ''          | ''            | '20180808'
 '21K'        | '1%'      | '1/20W'  | '0201LF'  | 'CHIP'   | 'CS32101FE00'(!)        = ''              | ''                 | 'CS32101FE00'           |'R0201'| '(SMR0201AW)'                  | '21K'     | '1%'    | '1/20W'  | 'DISCRETE' | 'RES CHIP 21K(1/20W,+-1%,0201)'                    | 'CHIPR0201'    | ''          | ''            | '20180808'
 '21K'        | '1%'      | '1/20W'  | '0201LF'  | 'EMPTY'  | 'CS32101FE00'(!)        = ''              | ''                 | 'CS32101FE00'           |'R0201'| '(SMR0201AW)'                  | '21K'     | '1%'    | '1/20W'  | 'IO'       | 'RES CHIP 21K(1/20W,+-1%,0201)'                    | 'CHIPR0201'    | ''          | ''            | '20180808'
 '22K'        | '1%'      | '1/20W'  | '0201LF'  | 'CHIP'   | 'CS32201FE00'(!)        = 'End of Design' | 'Comp-Approve'     | 'CS32201FE00'           |'R0201'| '(SMR0201AW)'                  | '22K'     | '1%'    | '1/20W'  | 'DISCRETE' | 'RES CHIP 22K 1/20W +-1%(0201)'                    | 'CHIPR0201'    | ''          | ''            | '20180808'
 '22K'        | '1%'      | '1/20W'  | '0201LF'  | 'EMPTY'  | 'CS32201FE00'(!)        = 'End of Design' | 'Comp-Approve'     | 'CS32201FE00'           |'R0201'| '(SMR0201AW)'                  | '22K'     | '1%'    | '1/20W'  | 'IO'       | 'RES CHIP 22K 1/20W +-1%(0201)'                    | 'CHIPR0201'    | ''          | ''            | '20180808'
 '26.1K'      | '1%'      | '1/20W'  | '0201LF'  | 'CHIP'   | 'CS32611FE01'(!)        = ''              | ''                 | 'CS32611FE01'           |'R0201'| '(SMR0201AW)'                  | '26.1K'   | '1%'    | '1/20W'  | 'DISCRETE' | 'RES CHIP 26.1K 1/20W +-1%(0201)'                  | 'CHIPR0201'    | ''          | ''            | '20180808'
 '26.1K'      | '1%'      | '1/20W'  | '0201LF'  | 'EMPTY'  | 'CS32611FE01'(!)        = ''              | ''                 | 'CS32611FE01'           |'R0201'| '(SMR0201AW)'                  | '26.1K'   | '1%'    | '1/20W'  | 'IO'       | 'RES CHIP 26.1K 1/20W +-1%(0201)'                  | 'CHIPR0201'    | ''          | ''            | '20180808'
 '26.7K'      | '1%'      | '1/20W'  | '0201LF'  | 'CHIP'   | 'CS32671FE00'(!)        = ''              | ''                 | 'CS32671FE00'           |'R0201'| '(SMR0201AW)'                  | '26.7K'   | '1%'    | '1/20W'  | 'DISCRETE' | 'RES CHIP 26.7K 1/20W +-1%(0201)'                  | 'CHIPR0201'    | ''          | ''            | '20180809'
 '26.7K'      | '1%'      | '1/20W'  | '0201LF'  | 'EMPTY'  | 'CS32671FE00'(!)        = ''              | ''                 | 'CS32671FE00'           |'R0201'| '(SMR0201AW)'                  | '26.7K'   | '1%'    | '1/20W'  | 'IO'       | 'RES CHIP 26.7K 1/20W +-1%(0201)'                  | 'CHIPR0201'    | ''          | ''            | '20180809'
 '1K'         | '5%'      | '1/20W'  | '0201LF'  | 'CHIP'   | 'CS21001JE14'(!)        = ''              | ''                 | 'CS21001JE14'           |'R0201'| '(SMR0201AW)'                  | '1K'      | '5%'    | '1/20W'  | 'DISCRETE' | 'RES CHIP 1K(1/20W,+-5%,0201)'                     | 'CHIPR0201'    | ''          | ''            | '20180808'
 '1K'         | '5%'      | '1/20W'  | '0201LF'  | 'EMPTY'  | 'CS21001JE14'(!)        = ''              | ''                 | 'CS21001JE14'           |'R0201'| '(SMR0201AW)'                  | '1K'      | '5%'    | '1/20W'  | 'IO'       | 'RES CHIP 1K(1/20W,+-5%,0201)'                     | 'CHIPR0201'    | ''          | ''            | '20180808'
 '8.2K'       | '5%'      | '1/20W'  | '0201LF'  | 'CHIP'   | 'CS28201JE00'(!)        = ''              | ''                 | 'CS28201JE00'           |'R0201'| '(SMR0201AW)'                  | '8.2K'    | '5%'    | '1/20W'  | 'DISCRETE' | 'RES CHIP 8.2K 1/20W +-5%(0201)'                   | 'CHIPR0201'    | ''          | ''            | '20180808'
 '8.2K'       | '5%'      | '1/20W'  | '0201LF'  | 'EMPTY'  | 'CS28201JE00'(!)        = ''              | ''                 | 'CS28201JE00'           |'R0201'| '(SMR0201AW)'                  | '8.2K'    | '5%'    | '1/20W'  | 'IO'       | 'RES CHIP 8.2K 1/20W +-5%(0201)'                   | 'CHIPR0201'    | ''          | ''            | '20180808'
 '47'         | '1%'      | '1/20W'  | '0201LF'  | 'CHIP'   | 'CS04701FE01'(!)        = ''              | ''                 | 'CS04701FE01'           |'R0201'| '(SMR0201AW)'                  | '47'      | '1%'    | '1/20W'  | 'DISCRETE' | 'RES CHIP 47 1/20W +-1%(0201)'                     | 'CHIPR0201'    | ''          | ''            | '20180809'
 '47'         | '1%'      | '1/20W'  | '0201LF'  | 'EMPTY'  | 'CS04701FE01'(!)        = ''              | ''                 | 'CS04701FE01'           |'R0201'| '(SMR0201AW)'                  | '47'      | '1%'    | '1/20W'  | 'IO'       | 'RES CHIP 47 1/20W +-1%(0201)'                     | 'CHIPR0201'    | ''          | ''            | '20180809'
 '1'          | '1%'      | '1/20W'  | '0201LF'  | 'CHIP'   | 'CS-1001FE00'(!)        = ''              | ''                 | 'CS-1001FE00'           |'R0201'| '(SMR0201AW)'                  | '1'       | '1%'    | '1/20W'  | 'DISCRETE' | 'RES CHIP 1 1/20W +-1%(0201)'                      | 'CHIPR0201'    | ''          | ''            | '20180809'
 '1'          | '1%'      | '1/20W'  | '0201LF'  | 'EMPTY'  | 'CS-1001FE00'(!)        = ''              | ''                 | 'CS-1001FE00'           |'R0201'| '(SMR0201AW)'                  | '1'       | '1%'    | '1/20W'  | 'IO'       | 'RES CHIP 1 1/20W +-1%(0201)'                      | 'CHIPR0201'    | ''          | ''            | '20180809'
 '5.9K'       | '0.1%'    | '1/20W'  | '0201LF'  | 'CHIP'   | 'CS25901BE00'(!)        = ''              | ''                 | 'CS25901BE00'           |'R0201'| '(SMR0201AW)'                  | '5.9K'    | '0.1%'  | '1/20W'  | 'DISCRETE' | 'RES CHIP 5.9K 1/20W +-0.1%(0201) '                | 'CHIPR0201'    | ''          | ''            | '20180809'
 '5.9K'       | '0.1%'    | '1/20W'  | '0201LF'  | 'EMPTY'  | 'CS25901BE00'(!)        = ''              | ''                 | 'CS25901BE00'           |'R0201'| '(SMR0201AW)'                  | '5.9K'    | '0.1%'  | '1/20W'  | 'IO'       | 'RES CHIP 5.9K 1/20W +-0.1%(0201) '                | 'CHIPR0201'    | ''          | ''            | '20180809'
 '10K'        | '0.1%'    | '1/20W'  | '0201LF'  | 'CHIP'   | 'CS31001BE02'(!)        = ''              | ''                 | 'CS31001BE02'           |'R0201'| '(SMR0201AW)'                  | '10K'     | '0.1%'  | '1/20W'  | 'DISCRETE' | 'RES CHIP 10K 1/20W +-0.1%(0201) '                 | 'CHIPR0201'    | ''          | ''            | '20180809'
 '10K'        | '0.1%'    | '1/20W'  | '0201LF'  | 'EMPTY'  | 'CS31001BE02'(!)        = ''              | ''                 | 'CS31001BE02'           |'R0201'| '(SMR0201AW)'                  | '10K'     | '0.1%'  | '1/20W'  | 'IO'       | 'RES CHIP 10K 1/20W +-0.1%(0201) '                 | 'CHIPR0201'    | ''          | ''            | '20180809'
 '249'        | '1%'      | '1/20W'  | '0201LF'  | 'CHIP'   | 'CS12491FE00'(!)        = ''              | ''                 | 'CS12491FE00'           |'R0201'| '(SMR0201AW)'                  | '249'     | '1%'    | '1/20W'  | 'DISCRETE' | 'RES CHIP 249 1/20W +-1%(0201)'                    | 'CHIPR0201'    | ''          | ''            | '20180809'
 '249'        | '1%'      | '1/20W'  | '0201LF'  | 'EMPTY'  | 'CS12491FE00'(!)        = ''              | ''                 | 'CS12491FE00'           |'R0201'| '(SMR0201AW)'                  | '249'     | '1%'    | '1/20W'  | 'IO'       | 'RES CHIP 249 1/20W +-1%(0201)'                    | 'CHIPR0201'    | ''          | ''            | '20180809'
 '562'        | '1%'      | '1/20W'  | '0201LF'  | 'CHIP'   | 'CS15621FE00'(!)        = ''              | ''                 | 'CS15621FE00'           |'R0201'| '(SMR0201AW)'                  | '562'     | '1%'    | '1/20W'  | 'DISCRETE' | 'RES CHIP 562 1/20W +-1% (0201)  '                 | 'CHIPR0201'    | ''          | ''            | '20180809'
 '562'        | '1%'      | '1/20W'  | '0201LF'  | 'EMPTY'  | 'CS15621FE00'(!)        = ''              | ''                 | 'CS15621FE00'           |'R0201'| '(SMR0201AW)'                  | '562'     | '1%'    | '1/20W'  | 'IO'       | 'RES CHIP 562 1/20W +-1% (0201)  '                 | 'CHIPR0201'    | ''          | ''            | '20180809'
 '1K'         | '0.1%'    | '1/20W'  | '0201LF'  | 'CHIP'   | 'CS21001BE01'(!)        = ''              | ''                 | 'CS21001BE01'           |'R0201'| '(SMR0201AW)'                  | '1K'      | '0.1%'  | '1/20W'  | 'DISCRETE' | 'RES CHIP 1K 1/20W +-0.1%(0201) '                  | 'CHIPR0201'    | ''          | ''            | '20180809'
 '1K'         | '0.1%'    | '1/20W'  | '0201LF'  | 'EMPTY'  | 'CS21001BE01'(!)        = ''              | ''                 | 'CS21001BE01'           |'R0201'| '(SMR0201AW)'                  | '1K'      | '0.1%'  | '1/20W'  | 'IO'       | 'RES CHIP 1K 1/20W +-0.1%(0201) '                  | 'CHIPR0201'    | ''          | ''            | '20180809'
 '1.02K'      | '1%'      | '1/20W'  | '0201LF'  | 'CHIP'   | 'CS21021FE00'(!)        = ''              | ''                 | 'CS21021FE00'           |'R0201'| '(SMR0201AW)'                  | '1.02K'   | '1%'    | '1/20W'  | 'DISCRETE' | 'RES CHIP 1.02K 1/20W +-1%(0201)'                  | 'CHIPR0201'    | ''          | ''            | '20180809'
 '1.02K'      | '1%'      | '1/20W'  | '0201LF'  | 'EMPTY'  | 'CS21021FE00'(!)        = ''              | ''                 | 'CS21021FE00'           |'R0201'| '(SMR0201AW)'                  | '1.02K'   | '1%'    | '1/20W'  | 'IO'       | 'RES CHIP 1.02K 1/20W +-1%(0201)'                  | 'CHIPR0201'    | ''          | ''            | '20180809'
 '1.82K'      | '1%'      | '1/20W'  | '0201LF'  | 'CHIP'   | 'CS21821FE00'(!)        = ''              | ''                 | 'CS21821FE00'           |'R0201'| '(SMR0201AW)'                  | '1.82K'   | '1%'    | '1/20W'  | 'DISCRETE' | 'RES CHIP 1.82K 1/20W +-1%(0201)'                  | 'CHIPR0201'    | ''          | ''            | '20180809'
 '1.82K'      | '1%'      | '1/20W'  | '0201LF'  | 'EMPTY'  | 'CS21821FE00'(!)        = ''              | ''                 | 'CS21821FE00'           |'R0201'| '(SMR0201AW)'                  | '1.82K'   | '1%'    | '1/20W'  | 'IO'       | 'RES CHIP 1.82K 1/20W +-1%(0201)'                  | 'CHIPR0201'    | ''          | ''            | '20180809'
 '27'         | '1%'      | '1/20W'  | '0201LF'  | 'CHIP'   | 'CS02701FE00'(!)        = 'End of Design' | 'Comp-Approve'     | 'CS02701FE00'           |'R0201'| '(SMR0201AW)'                  | '27'      | '1%'    | '1/20W'  | 'DISCRETE' | 'RES CHIP 27 1/20W +-1% (0201)'                    | 'CHIPR0201'    | ''          | ''            | '20180809'
 '27'         | '1%'      | '1/20W'  | '0201LF'  | 'EMPTY'  | 'CS02701FE00'(!)        = 'End of Design' | 'Comp-Approve'     | 'CS02701FE00'           |'R0201'| '(SMR0201AW)'                  | '27'      | '1%'    | '1/20W'  | 'IO'       | 'RES CHIP 27 1/20W +-1% (0201)'                    | 'CHIPR0201'    | ''          | ''            | '20180809'
 '1.43K'      | '1%'      | '1/20W'  | '0201LF'  | 'CHIP'   | 'CS21431FE01'(!)        = ''              | ''                 | 'CS21431FE01'           |'R0201'| '(SMR0201AW)'                  | '1.43K'   | '1%'    | '1/20W'  | 'DISCRETE' | 'RES CHIP 1.43K 1/20W +-1%(0201)'                  | 'CHIPR0201'    | ''          | ''            | '20180809'
 '1.43K'      | '1%'      | '1/20W'  | '0201LF'  | 'EMPTY'  | 'CS21431FE01'(!)        = ''              | ''                 | 'CS21431FE01'           |'R0201'| '(SMR0201AW)'                  | '1.43K'   | '1%'    | '1/20W'  | 'IO'       | 'RES CHIP 1.43K 1/20W +-1%(0201)'                  | 'CHIPR0201'    | ''          | ''            | '20180809'
 '2.21K'      | '1%'      | '1/20W'  | '0201LF'  | 'CHIP'   | 'CS22211FE00'(!)        = ''              | ''                 | 'CS22211FE00'           |'R0201'| '(SMR0201AW)'                  | '2.21K'   | '1%'    | '1/20W'  | 'DISCRETE' | 'RES CHIP 2.21K 1/20W +-1%(0201)HF'                | 'CHIPR0201'    | ''          | ''            | '20180809'
 '2.21K'      | '1%'      | '1/20W'  | '0201LF'  | 'EMPTY'  | 'CS22211FE00'(!)        = ''              | ''                 | 'CS22211FE00'           |'R0201'| '(SMR0201AW)'                  | '2.21K'   | '1%'    | '1/20W'  | 'IO'       | 'RES CHIP 2.21K 1/20W +-1%(0201)HF'                | 'CHIPR0201'    | ''          | ''            | '20180809'
 '54.9K'      | '1%'      | '1/20W'  | '0201LF'  | 'CHIP'   | 'CS35491FE01'(!)        = ''              | ''                 | 'CS35491FE01'           |'R0201'| '(SMR0201AW)'                  | '54.9K'   | '1%'    | '1/20W'  | 'DISCRETE' | 'RES CHIP 54.9K 1/20W +-1% (0201)'                 | 'CHIPR0201'    | ''          | ''            | '20180809'
 '54.9K'      | '1%'      | '1/20W'  | '0201LF'  | 'EMPTY'  | 'CS35491FE01'(!)        = ''              | ''                 | 'CS35491FE01'           |'R0201'| '(SMR0201AW)'                  | '54.9K'   | '1%'    | '1/20W'  | 'IO'       | 'RES CHIP 54.9K 1/20W +-1% (0201)'                 | 'CHIPR0201'    | ''          | ''            | '20180809'
 '36K'        | '1%'      | '1/20W'  | '0201LF'  | 'CHIP'   | 'CS33601FE02'(!)        = 'End of Design' | 'Comp-Approve'     | 'CS33601FE02'           |'R0201'| '(SMR0201AW)'                  | '36K'     | '1%'    | '1/20W'  | 'DISCRETE' | 'RES CHIP 36K 1/20W +-1%(0201)'                    | 'CHIPR0201'    | ''          | ''            | '20180809'
 '36K'        | '1%'      | '1/20W'  | '0201LF'  | 'EMPTY'  | 'CS33601FE02'(!)        = 'End of Design' | 'Comp-Approve'     | 'CS33601FE02'           |'R0201'| '(SMR0201AW)'                  | '36K'     | '1%'    | '1/20W'  | 'IO'       | 'RES CHIP 36K 1/20W +-1%(0201)'                    | 'CHIPR0201'    | ''          | ''            | '20180809'
 '165K'       | '1%'      | '1/20W'  | '0201LF'  | 'CHIP'   | 'CS41651FE01'(!)        = ''              | ''                 | 'CS41651FE01'           |'R0201'| '(SMR0201AW)'                  | '165K'    | '1%'    | '1/20W'  | 'DISCRETE' | 'RES CHIP 165K 1/20W +-1%(0201)'                   | 'CHIPR0201'    | ''          | ''            | '20180809'
 '165K'       | '1%'      | '1/20W'  | '0201LF'  | 'EMPTY'  | 'CS41651FE01'(!)        = ''              | ''                 | 'CS41651FE01'           |'R0201'| '(SMR0201AW)'                  | '165K'    | '1%'    | '1/20W'  | 'IO'       | 'RES CHIP 165K 1/20W +-1%(0201)'                   | 'CHIPR0201'    | ''          | ''            | '20180809'
 '100'        | '0.1%'    | '1/20W'  | '0201LF'  | 'CHIP'   | 'CS11001BE00'(!)        = ''              | ''                 | 'CS11001BE00'           |'R0201'| '(SMR0201AW)'                  | '100'     | '0.1%'  | '1/20W'  | 'DISCRETE' | 'RES CHIP 100 1/20W +-0.1%(0201) '                 | 'CHIPR0201'    | ''          | ''            | '20180809'
 '100'        | '0.1%'    | '1/20W'  | '0201LF'  | 'EMPTY'  | 'CS11001BE00'(!)        = ''              | ''                 | 'CS11001BE00'           |'R0201'| '(SMR0201AW)'                  | '100'     | '0.1%'  | '1/20W'  | 'IO'       | 'RES CHIP 100 1/20W +-0.1%(0201) '                 | 'CHIPR0201'    | ''          | ''            | '20180809'
 '2K'         | '0.1%'    | '1/20W'  | '0201LF'  | 'CHIP'   | 'CS22001BE00'(!)        = ''              | ''                 | 'CS22001BE00'           |'R0201'| '(SMR0201AW)'                  | '2K'      | '0.1%'  | '1/20W'  | 'DISCRETE' | 'RES CHIP 2K 1/20W +-0.1%(0201) '                  | 'CHIPR0201'    | ''          | ''            | '20180809'
 '2K'         | '0.1%'    | '1/20W'  | '0201LF'  | 'EMPTY'  | 'CS22001BE00'(!)        = ''              | ''                 | 'CS22001BE00'           |'R0201'| '(SMR0201AW)'                  | '2K'      | '0.1%'  | '1/20W'  | 'IO'       | 'RES CHIP 2K 1/20W +-0.1%(0201) '                  | 'CHIPR0201'    | ''          | ''            | '20180809'
 '249'        | '0.1%'    | '1/20W'  | '0201LF'  | 'CHIP'   | 'CS12491BE00'(!)        = ''              | ''                 | 'CS12491BE00'           |'R0201'| '(SMR0201AW)'                  | '249'     | '0.1%'  | '1/20W'  | 'DISCRETE' | 'RES CHIP 249 1/20W +-0.1%(0201) '                 | 'CHIPR0201'    | ''          | ''            | '20180809'
 '249'        | '0.1%'    | '1/20W'  | '0201LF'  | 'EMPTY'  | 'CS12491BE00'(!)        = ''              | ''                 | 'CS12491BE00'           |'R0201'| '(SMR0201AW)'                  | '249'     | '0.1%'  | '1/20W'  | 'IO'       | 'RES CHIP 249 1/20W +-0.1%(0201) '                 | 'CHIPR0201'    | ''          | ''            | '20180809'
 '22'         | '5%'      | '1/20W'  | '0201LF'  | 'CHIP'   | 'CS02201JE00'(!)        = ''              | ''                 | 'CS02201JE00'           |'R0201'| '(SMR0201AW)'                  | '22'      | '5%'    | '1/20W'  | 'DISCRETE' | 'RES CHIP 22 1/20W +-5%(0201)'                     | 'CHIPR0201'    | ''          | ''            | '20180809'
 '22'         | '5%'      | '1/20W'  | '0201LF'  | 'EMPTY'  | 'CS02201JE00'(!)        = ''              | ''                 | 'CS02201JE00'           |'R0201'| '(SMR0201AW)'                  | '22'      | '5%'    | '1/20W'  | 'IO'       | 'RES CHIP 22 1/20W +-5%(0201)'                     | 'CHIPR0201'    | ''          | ''            | '20180809'
 '49.9'       | '0.1%'    | '1/20W'  | '0201LF'  | 'CHIP'   | 'CS04991BE00'(!)        = ''              | ''                 | 'CS04991BE00'           |'R0201'| '(SMR0201AW)'                  | '49.9'    | '0.1%'  | '1/20W'  | 'DISCRETE' | 'RES CHIP 49.9 1/20W +-0.1%(0201) '                | 'CHIPR0201'    | ''          | ''            | '20180809'
 '49.9'       | '0.1%'    | '1/20W'  | '0201LF'  | 'EMPTY'  | 'CS04991BE00'(!)        = ''              | ''                 | 'CS04991BE00'           |'R0201'| '(SMR0201AW)'                  | '49.9'    | '0.1%'  | '1/20W'  | 'IO'       | 'RES CHIP 49.9 1/20W +-0.1%(0201) '                | 'CHIPR0201'    | ''          | ''            | '20180809'
 '86.6K'      | '1%'      | '1/20W'  | '0201LF'  | 'CHIP'   | 'CS38661FE00'(!)        = ''              | ''                 | 'CS38661FE00'           |'R0201'| '(SMR0201AW)'                  | '86.6K'   | '1%'    | '1/20W'  | 'DISCRETE' | 'RES CHIP 86.6K 1/20W +-1%(0201)'                  | 'CHIPR0201'    | ''          | ''            | '20180810'
 '86.6K'      | '1%'      | '1/20W'  | '0201LF'  | 'EMPTY'  | 'CS38661FE00'(!)        = ''              | ''                 | 'CS38661FE00'           |'R0201'| '(SMR0201AW)'                  | '86.6K'   | '1%'    | '1/20W'  | 'IO'       | 'RES CHIP 86.6K 1/20W +-1%(0201)'                  | 'CHIPR0201'    | ''          | ''            | '20180810'
 '470'        | '5%'      | '1/20W'  | '0201LF'  | 'CHIP'   | 'CS14701JE00'(!)        = ''              | ''                 | 'CS14701JE00'           |'R0201'| '(SMR0201AW)'                  | '470'     | '5%'    | '1/20W'  | 'DISCRETE' | 'RES CHIP 470 1/20W +-5%(0201)'                    | 'CHIPR0201'    | ''          | ''            | '20180810'
 '470'        | '5%'      | '1/20W'  | '0201LF'  | 'EMPTY'  | 'CS14701JE00'(!)        = ''              | ''                 | 'CS14701JE00'           |'R0201'| '(SMR0201AW)'                  | '470'     | '5%'    | '1/20W'  | 'IO'       | 'RES CHIP 470 1/20W +-5%(0201)'                    | 'CHIPR0201'    | ''          | ''            | '20180810'
 '165'        | '1%'      | '1/20W'  | '0201LF'  | 'CHIP'   | 'CS11651FE00'(!)        = ''              | ''                 | 'CS11651FE00'           |'R0201'| '(SMR0201AW)'                  | '165'     | '1%'    | '1/20W'  | 'DISCRETE' | 'RES CHIP 165 1/20W +-1%(0201)'                    | 'CHIPR0201'    | ''          | ''            | '20180823'
 '165'        | '1%'      | '1/20W'  | '0201LF'  | 'EMPTY'  | 'CS11651FE00'(!)        = ''              | ''                 | 'CS11651FE00'           |'R0201'| '(SMR0201AW)'                  | '165'     | '1%'    | '1/20W'  | 'IO'       | 'RES CHIP 165 1/20W +-1%(0201)'                    | 'CHIPR0201'    | ''          | ''            | '20180823'
 '3K'         | '1%'      | '1/20W'  | '0201LF'  | 'CHIP'   | 'CS23001FE02'(!)        = ''              | ''                 | 'CS23001FE02'           |'R0201'| '(SMR0201AW)'                  | '3K'      | '1%'    | '1/20W'  | 'DISCRETE' | 'RES CHIP 3K 1/20W+-1%(0201)'                      | 'CHIPR0201'    | ''          | ''            | '20180823'
 '3K'         | '1%'      | '1/20W'  | '0201LF'  | 'EMPTY'  | 'CS23001FE02'(!)        = ''              | ''                 | 'CS23001FE02'           |'R0201'| '(SMR0201AW)'                  | '3K'      | '1%'    | '1/20W'  | 'IO'       | 'RES CHIP 3K 1/20W+-1%(0201)'                      | 'CHIPR0201'    | ''          | ''            | '20180823'
 '665'        | '1%'      | '1/20W'  | '0201LF'  | 'CHIP'   | 'CS16651FE00'(!)        = ''              | ''                 | 'CS16651FE00'           |'R0201'| '(SMR0201AW)'                  | '665'     | '1%'    | '1/20W'  | 'DISCRETE' | 'RES CHIP 665 1/20W +-1%(0201) '                   | 'CHIPR0201'    | ''          | ''            | '20180823'
 '665'        | '1%'      | '1/20W'  | '0201LF'  | 'EMPTY'  | 'CS16651FE00'(!)        = ''              | ''                 | 'CS16651FE00'           |'R0201'| '(SMR0201AW)'                  | '665'     | '1%'    | '1/20W'  | 'IO'       | 'RES CHIP 665 1/20W +-1%(0201) '                   | 'CHIPR0201'    | ''          | ''            | '20180823'
 '549K'       | '1%'      | '1/16W'  | '0402LF'  | 'CHIP'   | 'CS45492FB16'(!)        = 'End of Design' | 'Comp-Approve'     | 'CS45492FB16'           |'R0402'| '(R0402-0201)'                 | '549K'    | '1%'    | '1/16W'  | 'DISCRETE' | 'RES CHIP 549K 1/16W +-1%( 0402)'                  | 'CHIPR0402'    | ''          | ''            | '20180830'
 '549K'       | '1%'      | '1/16W'  | '0402LF'  | 'EMPTY'  | 'CS45492FB16'(!)        = 'End of Design' | 'Comp-Approve'     | 'CS45492FB16'           |'R0402'| '(R0402-0201)'                 | '549K'    | '1%'    | '1/16W'  | 'IO'       | 'RES CHIP 549K 1/16W +-1%( 0402)'                  | 'CHIPR0402'    | ''          | ''            | '20180830'
 '1.74K'      | '1%'      | '1/20W'  | '0201LF'  | 'CHIP'   | 'CS21741FE00'(!)        = ''              | ''                 | 'CS21741FE00'           |'R0201'| '(SMR0201AW)'                  | '1.74K'   | '1%'    | '1/20W'  | 'DISCRETE' | 'RES CHIP 1.74K 1/20W +-1%(0201) '                 | 'CHIPR0201'    | ''          | ''            | '20180830'
 '1.74K'      | '1%'      | '1/20W'  | '0201LF'  | 'EMPTY'  | 'CS21741FE00'(!)        = ''              | ''                 | 'CS21741FE00'           |'R0201'| '(SMR0201AW)'                  | '1.74K'   | '1%'    | '1/20W'  | 'IO'       | 'RES CHIP 1.74K 1/20W +-1%(0201) '                 | 'CHIPR0201'    | ''          | ''            | '20180830'
 '15.4K'      | '1%'      | '1/20W'  | '0201LF'  | 'CHIP'   | 'CS31541FE00'(!)        = ''              | ''                 | 'CS31541FE00'           |'R0201'| '(SMR0201AW)'                  | '15.4K'   | '1%'    | '1/20W'  | 'DISCRETE' | 'RES CHIP 15.4K 1/20W +-1%(0201)'                  | 'CHIPR0201'    | ''          | ''            | '20180830'
 '15.4K'      | '1%'      | '1/20W'  | '0201LF'  | 'EMPTY'  | 'CS31541FE00'(!)        = ''              | ''                 | 'CS31541FE00'           |'R0201'| '(SMR0201AW)'                  | '15.4K'   | '1%'    | '1/20W'  | 'IO'       | 'RES CHIP 15.4K 1/20W +-1%(0201)'                  | 'CHIPR0201'    | ''          | ''            | '20180830'
 '19.1K'      | '1%'      | '1/20W'  | '0201LF'  | 'CHIP'   | 'CS31911FE01'(!)        = ''              | ''                 | 'CS31911FE01'           |'R0201'| '(SMR0201AW)'                  | '19.1K'   | '1%'    | '1/20W'  | 'DISCRETE' | 'RES CHIP 19.1K 1/20W +-1%(0201)'                  | 'CHIPR0201'    | ''          | ''            | '20180830'
 '19.1K'      | '1%'      | '1/20W'  | '0201LF'  | 'EMPTY'  | 'CS31911FE01'(!)        = ''              | ''                 | 'CS31911FE01'           |'R0201'| '(SMR0201AW)'                  | '19.1K'   | '1%'    | '1/20W'  | 'IO'       | 'RES CHIP 19.1K 1/20W +-1%(0201)'                  | 'CHIPR0201'    | ''          | ''            | '20180830'
 '3.74K'      | '1%'      | '1/20W'  | '0201LF'  | 'CHIP'   | 'CS23741FE01'(!)        = ''              | ''                 | 'CS23741FE01'           |'R0201'| '(SMR0201AW)'                  | '3.74K'   | '1%'    | '1/20W'  | 'DISCRETE' | 'RES CHIP 3.74K 1/20W +-1%(0201)'                  | 'CHIPR0201'    | ''          | ''            | '20180830'
 '3.74K'      | '1%'      | '1/20W'  | '0201LF'  | 'EMPTY'  | 'CS23741FE01'(!)        = ''              | ''                 | 'CS23741FE01'           |'R0201'| '(SMR0201AW)'                  | '3.74K'   | '1%'    | '1/20W'  | 'IO'       | 'RES CHIP 3.74K 1/20W +-1%(0201)'                  | 'CHIPR0201'    | ''          | ''            | '20180830'
 '42.2K'      | '1%'      | '1/20W'  | '0201LF'  | 'CHIP'   | 'CS34221FE01'(!)        = ''              | ''                 | 'CS34221FE01'           |'R0201'| '(SMR0201AW)'                  | '42.2K'   | '1%'    | '1/20W'  | 'DISCRETE' | 'RES CHIP 42.2K 1/20W +-1%(0201)'                  | 'CHIPR0201'    | ''          | ''            | '20180830'
 '42.2K'      | '1%'      | '1/20W'  | '0201LF'  | 'EMPTY'  | 'CS34221FE01'(!)        = ''              | ''                 | 'CS34221FE01'           |'R0201'| '(SMR0201AW)'                  | '42.2K'   | '1%'    | '1/20W'  | 'IO'       | 'RES CHIP 42.2K 1/20W +-1%(0201)'                  | 'CHIPR0201'    | ''          | ''            | '20180830'
 '75K'        | '1%'      | '1/20W'  | '0201LF'  | 'CHIP'   | 'CS37501FE00'(!)        = ''              | ''                 | 'CS37501FE00'           |'R0201'| '(SMR0201AW)'                  | '75K'     | '1%'    | '1/20W'  | 'DISCRETE' | 'RES CHIP 75K 1/20W +-1%(0201)'                    | 'CHIPR0201'    | ''          | ''            | '20180830'
 '75K'        | '1%'      | '1/20W'  | '0201LF'  | 'EMPTY'  | 'CS37501FE00'(!)        = ''              | ''                 | 'CS37501FE00'           |'R0201'| '(SMR0201AW)'                  | '75K'     | '1%'    | '1/20W'  | 'IO'       | 'RES CHIP 75K 1/20W +-1%(0201)'                    | 'CHIPR0201'    | ''          | ''            | '20180830'
 '84.5K'      | '1%'      | '1/20W'  | '0201LF'  | 'CHIP'   | 'CS38451FE00'(!)        = ''              | ''                 | 'CS38451FE00'           |'R0201'| '(SMR0201AW)'                  | '84.5K'   | '1%'    | '1/20W'  | 'DISCRETE' | 'RES CHIP 84.5K 1/20W,+-1%(0201)'                  | 'CHIPR0201'    | ''          | ''            | '20180830'
 '84.5K'      | '1%'      | '1/20W'  | '0201LF'  | 'EMPTY'  | 'CS38451FE00'(!)        = ''              | ''                 | 'CS38451FE00'           |'R0201'| '(SMR0201AW)'                  | '84.5K'   | '1%'    | '1/20W'  | 'IO'       | 'RES CHIP 84.5K 1/20W,+-1%(0201)'                  | 'CHIPR0201'    | ''          | ''            | '20180830'
 '9.76K'      | '1%'      | '1/20W'  | '0201LF'  | 'CHIP'   | 'CS29761FE00'(!)        = ''              | ''                 | 'CS29761FE00'           |'R0201'| '(SMR0201AW)'                  | '9.76K'   | '1%'    | '1/20W'  | 'DISCRETE' | 'RES CHIP 9.76K 1/20W +-1%(0201)'                  | 'CHIPR0201'    | ''          | ''            | '20180831'
 '9.76K'      | '1%'      | '1/20W'  | '0201LF'  | 'EMPTY'  | 'CS29761FE00'(!)        = ''              | ''                 | 'CS29761FE00'           |'R0201'| '(SMR0201AW)'                  | '9.76K'   | '1%'    | '1/20W'  | 'IO'       | 'RES CHIP 9.76K 1/20W +-1%(0201)'                  | 'CHIPR0201'    | ''          | ''            | '20180831'
 '45.3K'      | '1%'      | '1/20W'  | '0201LF'  | 'CHIP'   | 'CS34531FE01'(!)        = ''              | ''                 | 'CS34531FE01'           |'R0201'| '(SMR0201AW)'                  | '45.3K'   | '1%'    | '1/20W'  | 'DISCRETE' | 'RES CHIP 45.3K 1/20W +-1%(0201)'                  | 'CHIPR0201'    | ''          | ''            | '20180831'
 '45.3K'      | '1%'      | '1/20W'  | '0201LF'  | 'EMPTY'  | 'CS34531FE01'(!)        = ''              | ''                 | 'CS34531FE01'           |'R0201'| '(SMR0201AW)'                  | '45.3K'   | '1%'    | '1/20W'  | 'IO'       | 'RES CHIP 45.3K 1/20W +-1%(0201)'                  | 'CHIPR0201'    | ''          | ''            | '20180831'
 '147K'       | '1%'      | '1/20W'  | '0201LF'  | 'CHIP'   | 'CS41471FE00'(!)        = ''              | ''                 | 'CS41471FE00'           |'R0201'| '(SMR0201AW)'                  | '147K'    | '1%'    | '1/20W'  | 'DISCRETE' | 'RES CHIP 147K 1/20W +-1%(0201)'                   | 'CHIPR0201'    | ''          | ''            | '20180903'
 '147K'       | '1%'      | '1/20W'  | '0201LF'  | 'EMPTY'  | 'CS41471FE00'(!)        = ''              | ''                 | 'CS41471FE00'           |'R0201'| '(SMR0201AW)'                  | '147K'    | '1%'    | '1/20W'  | 'IO'       | 'RES CHIP 147K 1/20W +-1%(0201)'                   | 'CHIPR0201'    | ''          | ''            | '20180903'
 '28K'        | '1%'      | '1/20W'  | '0201LF'  | 'CHIP'   | 'CS32801FE00'(!)        = ''              | ''                 | 'CS32801FE00'           |'R0201'| '(SMR0201AW)'                  | '28K'     | '1%'    | '1/20W'  | 'DISCRETE' | 'RES CHIP 28K 1/20W +-1%(0201)'                    | 'CHIPR0201'    | ''          | ''            | '20180903'
 '28K'        | '1%'      | '1/20W'  | '0201LF'  | 'EMPTY'  | 'CS32801FE00'(!)        = ''              | ''                 | 'CS32801FE00'           |'R0201'| '(SMR0201AW)'                  | '28K'     | '1%'    | '1/20W'  | 'IO'       | 'RES CHIP 28K 1/20W +-1%(0201)'                    | 'CHIPR0201'    | ''          | ''            | '20180903'
 '7.68K'      | '1%'      | '1/20W'  | '0201LF'  | 'CHIP'   | 'CS27681FE00'(!)        = ''              | ''                 | 'CS27681FE00'           |'R0201'| '(SMR0201AW)'                  | '7.68K'   | '1%'    | '1/20W'  | 'DISCRETE' | 'RES CHIP 7.68K 1/20W +-1%(0201)'                  | 'CHIPR0201'    | ''          | ''            | '20180903'
 '7.68K'      | '1%'      | '1/20W'  | '0201LF'  | 'EMPTY'  | 'CS27681FE00'(!)        = ''              | ''                 | 'CS27681FE00'           |'R0201'| '(SMR0201AW)'                  | '7.68K'   | '1%'    | '1/20W'  | 'IO'       | 'RES CHIP 7.68K 1/20W +-1%(0201)'                  | 'CHIPR0201'    | ''          | ''            | '20180903'
 '38.3K'      | '1%'      | '1/20W'  | '0201LF'  | 'CHIP'   | 'CS33831FE01'(!)        = ''              | ''                 | 'CS33831FE01'           |'R0201'| '(SMR0201AW)'                  | '38.3K'   | '1%'    | '1/20W'  | 'DISCRETE' | 'RES CHIP 38.3K 1/20W +-1%(0201)'                  | 'CHIPR0201'    | ''          | ''            | '20180903'
 '38.3K'      | '1%'      | '1/20W'  | '0201LF'  | 'EMPTY'  | 'CS33831FE01'(!)        = ''              | ''                 | 'CS33831FE01'           |'R0201'| '(SMR0201AW)'                  | '38.3K'   | '1%'    | '1/20W'  | 'IO'       | 'RES CHIP 38.3K 1/20W +-1%(0201)'                  | 'CHIPR0201'    | ''          | ''            | '20180903'
 '63.4K'      | '1%'      | '1/20W'  | '0201LF'  | 'CHIP'   | 'CS36341FE00'(!)        = ''              | ''                 | 'CS36341FE00'           |'R0201'| '(SMR0201AW)'                  | '63.4K'   | '1%'    | '1/20W'  | 'DISCRETE' | 'RES CHIP 63.4K 1/20W +-1% (0201) '                | 'CHIPR0201'    | ''          | ''            | '20180903'
 '63.4K'      | '1%'      | '1/20W'  | '0201LF'  | 'EMPTY'  | 'CS36341FE00'(!)        = ''              | ''                 | 'CS36341FE00'           |'R0201'| '(SMR0201AW)'                  | '63.4K'   | '1%'    | '1/20W'  | 'IO'       | 'RES CHIP 63.4K 1/20W +-1% (0201) '                | 'CHIPR0201'    | ''          | ''            | '20180903'
 '560'        | '1%'      | '1/16W'  | '0402LF'  | 'CHIP'   | 'CS15602FB17'(!)        = 'End of Design' | 'Comp-Approve'     | 'CS15602FB17'           |'R0402'| '(R0402-0201)'                 | '560'     | '1%'    | '1/16W'  | 'DISCRETE' | 'RES CHIP 560 1/16W +-1%(0402)'                    | 'CHIPR0402'    | ''          | ''            | '20100429'
 '560'        | '1%'      | '1/16W'  | '0402LF'  | 'EMPTY'  | 'CS15602FB17'(!)        = 'End of Design' | 'Comp-Approve'     | 'CS15602FB17'           |'R0402'| '(R0402-0201)'                 | '560'     | '1%'    | '1/16W'  | 'IO'       | 'RES CHIP 560 1/16W +-1%(0402)'                    | 'CHIPR0402'    | ''          | ''            | '20100429'
 '2K'         | '0.1%'    | '1/16W'  | '0402LF'  | 'CHIP'   | 'CS22002BB01'(!)        = ''              | ''                 | 'CS22002BB01'           |'R0402'| '(R0402-0201)'                 | '2K'      | '0.1%'  | '1/16W'  | 'DISCRETE' | 'RES CHIP 2K 1/16W +-0.1% (0402)'                  | 'CHIPR0402'    | ''          | ''            | '20150911'
 '2K'         | '0.1%'    | '1/16W'  | '0402LF'  | 'EMPTY'  | 'CS22002BB01'(!)        = ''              | ''                 | 'CS22002BB01'           |'R0402'| '(R0402-0201)'                 | '2K'      | '0.1%'  | '1/16W'  | 'IO'       | 'RES CHIP 2K 1/16W +-0.1% (0402)'                  | 'CHIPR0402'    | ''          | ''            | '20150911'
 '220'        | '5%'      | '1/20W'  | '0201LF'  | 'CHIP '  | 'CS12201JE04'(!)        = ''              | ''                 | 'CS12201JE04'           |'R0201'| '(SMR0201AW)'                  | '220'     | '5%'    | '1/20W'  | 'DISCRETE' | 'RES CHIP 220(1/20W,+-5%,0201)'                    | 'CHIPR0201'    | ''          | ''            | '20181024'
 '220'        | '5%'      | '1/20W'  | '0201LF'  | 'EMPTY'  | 'CS12201JE04'(!)        = ''              | ''                 | 'CS12201JE04'           |'R0201'| '(SMR0201AW)'                  | '220'     | '5%'    | '1/20W'  | 'IO'       | 'RES CHIP 220(1/20W,+-5%,0201)'                    | 'CHIPR0201'    | ''          | ''            | '20181024'
 '330'        | '1%'      | '1/4W'   | '1206LF'  | 'CHIP'   | 'CS13306F200'(!)        = ''              | ''                 | 'CS13306F200'           |'R1206XJ'| '(SMR1206AW)'                  | '330'     | '1%'    | '1/4W'   | 'DISCRETE' | 'RES CHIP 330 1/4W+-1%(1206)'                      | 'CHIPR1206'    | ''          | ''            | '20100429'
 '330'        | '1%'      | '1/4W'   | '1206LF'  | 'EMPTY'  | 'CS13306F200'(!)        = ''              | ''                 | 'CS13306F200'           |'R1206XJ'| '(SMR1206AW)'                  | '330'     | '1%'    | '1/4W'   | 'IO'       | 'RES CHIP 330 1/4W+-1%(1206)'                      | 'CHIPR1206'    | ''          | ''            | '20100429'
 '249'        | '1%'      | '1/4W'   | '1206LF'  | 'CHIP'   | 'CS12496F200'(!)        = ''              | ''                 | 'CS12496F200'           |'R1206XJ'| '(SMR1206AW)'                  | '249'     | '1%'    | '1/4W'   | 'DISCRETE' | 'RES CHIP 249 1/4W +-1%(1206)'                     | 'CHIPR1206'    | ''          | ''            | '20181031'
 '249'        | '1%'      | '1/4W'   | '1206LF'  | 'EMPTY'  | 'CS12496F200'(!)        = ''              | ''                 | 'CS12496F200'           |'R1206XJ'| '(SMR1206AW)'                  | '249'     | '1%'    | '1/4W'   | 'IO'       | 'RES CHIP 249 1/4W +-1%(1206)'                     | 'CHIPR1206'    | ''          | ''            | '20181031'
 '910K'       | '1%'      | '1/16W'  | '0402LF'  | 'CHIP'   | 'CS49102FB07'(!)        = 'End of Design' | 'Comp-Approve'     | 'CS49102FB07'           |'R0402'| '(R0402-0201)'                 | '910K'    | '1%'    | '1/16W'  | 'DISCRETE' | 'RES CHIP 910K 1/16W +-1%(0402)'                   | 'CHIPR0402'    | ''          | ''            | '20181031'
 '910K'       | '1%'      | '1/16W'  | '0402LF'  | 'EMPTY'  | 'CS49102FB07'(!)        = 'End of Design' | 'Comp-Approve'     | 'CS49102FB07'           |'R0402'| '(R0402-0201)'                 | '910K'    | '1%'    | '1/16W'  | 'IO'       | 'RES CHIP 910K 1/16W +-1%(0402)'                   | 'CHIPR0402'    | ''          | ''            | '20181031'
 '1.78M'      | '1%'      | '1/16W'  | '0402LF'  | 'CHIP'   | 'CS51782FB00'(!)        = ''              | ''                 | 'CS51782FB00'           |'R0402'| '(R0402-0201)'                 | '1.78M'   | '1%'    | '1/16W'  | 'DISCRETE' | 'RES CHIP 1.78M 1/16W +-1%(0402)'                  | 'CHIPR0402'    | ''          | ''            | '20181101'
 '1.78M'      | '1%'      | '1/16W'  | '0402LF'  | 'EMPTY'  | 'CS51782FB00'(!)        = ''              | ''                 | 'CS51782FB00'           |'R0402'| '(R0402-0201)'                 | '1.78M'   | '1%'    | '1/16W'  | 'IO'       | 'RES CHIP 1.78M 1/16W +-1%(0402)'                  | 'CHIPR0402'    | ''          | ''            | '20181101'
 '0.005'      | '1%'      | '1W'     | '1206LF'  | 'CHIP'   | 'CS+0058F200'(!)        = ''              | ''                 | 'CS+0058F200'           |'R1206XK'| '(SMR1206AW)'                  | '0.005'   | '1%'    | '1W'     | 'DISCRETE' | 'RES CHIP  0.005  1W +-1%(1206)'                   | 'CHIPR1206'    | ''          | ''            | '20181113'
 '0.005'      | '1%'      | '1W'     | '1206LF'  | 'EMPTY'  | 'CS+0058F200'(!)        = ''              | ''                 | 'CS+0058F200'           |'R1206XK'| '(SMR1206AW)'                  | '0.005'   | '1%'    | '1W'     | 'IO'       | 'RES CHIP  0.005  1W +-1%(1206)'                   | 'CHIPR1206'    | ''          | ''            | '20181113'
 '316'        | '1%'      | '1/16W'  | '0402LF'  | 'CHIP'   | 'CS13162FB02'(!)        = 'End of Design' | 'Comp-Approve'     | 'CS13162FB02'           |'R0402'| '(R0402-0201)'                 | '316'     | '1%'    | '1/16W'  | 'DISCRETE' | 'RES CHIP 316 1/16W +-1%(0402)'                    | 'CHIPR0402'    | ''          | ''            | '20181113'
 '316'        | '1%'      | '1/16W'  | '0402LF'  | 'EMPTY'  | 'CS13162FB02'(!)        = 'End of Design' | 'Comp-Approve'     | 'CS13162FB02'           |'R0402'| '(R0402-0201)'                 | '316'     | '1%'    | '1/16W'  | 'IO'       | 'RES CHIP 316 1/16W +-1%(0402)'                    | 'CHIPR0402'    | ''          | ''            | '20181113'
 '1.69K'      | '1%'      | '1/4W'   | '1206LF'  | 'CHIP'   | 'CS21696F200'(!)        = 'End of Design' | 'Comp-Approve'     | 'CS21696F200'           |'R1206XB'| '(SMR1206AW)'                  | '1.69K'   | '1%'    | '1/4W'   | 'DISCRETE' | 'RES CHIP 1.69K 1/4W +-1% (1206)'                  | 'CHIPR1206'    | ''          | ''            | '20150413'
 '1.69K'      | '1%'      | '1/4W'   | '1206LF'  | 'EMPTY'  | 'CS21696F200'(!)        = 'End of Design' | 'Comp-Approve'     | 'CS21696F200'           |'R1206XB'| '(SMR1206AW)'                  | '1.69K'   | '1%'    | '1/4W'   | 'IO'       | 'RES CHIP 1.69K 1/4W +-1% (1206)'                  | 'CHIPR1206'    | ''          | ''            | '20150413'
 '1.47K'      | '1%'      | '1/4W'   | '1206LF'  | 'CHIP'   | 'CS21476F200'(!)        = ''              | ''                 | 'CS21476F200'           |'R1206XI'| '(SMR1206AW)'                  | '1.47K'   | '1%'    | '1/4W'   | 'DISCRETE' | 'RES CHIP 1.47K 1/4W +-1%(1206)'                   | 'CHIPR1206'    | ''          | ''            | '20181113'
 '1.47K'      | '1%'      | '1/4W'   | '1206LF'  | 'EMPTY'  | 'CS21476F200'(!)        = ''              | ''                 | 'CS21476F200'           |'R1206XI'| '(SMR1206AW)'                  | '1.47K'   | '1%'    | '1/4W'   | 'IO'       | 'RES CHIP 1.47K 1/4W +-1%(1206)'                   | 'CHIPR1206'    | ''          | ''            | '20181113'
 '866'        | '1%'      | '1/4W'   | '1206LF'  | 'CHIP'   | 'CS18666F200'(!)        = ''              | ''                 | 'CS18666F200'           |'R1206XF'| '(SMR1206AW)'                  | '866'     | '1%'    | '1/4W'   | 'DISCRETE' | 'RES CHIP 866 1/4W +-1%(1206)'                     | 'CHIPR1206'    | ''          | ''            | '20181122'
 '866'        | '1%'      | '1/4W'   | '1206LF'  | 'EMPTY'  | 'CS18666F200'(!)        = ''              | ''                 | 'CS18666F200'           |'R1206XF'| '(SMR1206AW)'                  | '866'     | '1%'    | '1/4W'   | 'IO'       | 'RES CHIP 866 1/4W +-1%(1206)'                     | 'CHIPR1206'    | ''          | ''            | '20181122'
 '910'        | '1%'      | '1/4W'   | '1206LF'  | 'CHIP'   | 'CS19106F200'(!)        = ''              | ''                 | 'CS19106F200'           |'R1206XF'| '(SMR1206AW)'                  | '910'     | '1%'    | '1/4W'   | 'DISCRETE' | 'RES CHIP 910 1/4W +-1%(1206)'                     | 'CHIPR1206'    | ''          | ''            | '20181122'
 '910'        | '1%'      | '1/4W'   | '1206LF'  | 'EMPTY'  | 'CS19106F200'(!)        = ''              | ''                 | 'CS19106F200'           |'R1206XF'| '(SMR1206AW)'                  | '910'     | '1%'    | '1/4W'   | 'IO'       | 'RES CHIP 910 1/4W +-1%(1206)'                     | 'CHIPR1206'    | ''          | ''            | '20181122'
 '237K'       | '1%'      | '1/8W'   | '0805LF'  | 'CHIP'   | 'CS42374FA19'(!)        = ''              | ''                 | 'CS42374FA19'           |'R0805'| '(SMR0805AW)'                  | '237K'    | '1%'    | '1/8W'   | 'DISCRETE' | 'RES CHIP 237K 1/8W +-1%(2012)'                    | 'CHIPR0805'    | ''          | ''            | '20181122'
 '237K'       | '1%'      | '1/8W'   | '0805LF'  | 'EMPTY'  | 'CS42374FA19'(!)        = ''              | ''                 | 'CS42374FA19'           |'R0805'| '(SMR0805AW)'                  | '237K'    | '1%'    | '1/8W'   | 'IO'       | 'RES CHIP 237K 1/8W +-1%(2012)'                    | 'CHIPR0805'    | ''          | ''            | '20181122'
 '7.32K'      | '1%'      | '1/20W'  | '0201LF'  | 'CHIP'   | 'CS27321FE01'(!)        = ''              | ''                 | 'CS27321FE01'           |'R0201'| '(SMR0201AW)'                  | '7.32K'   | '1%'    | '1/20W'  | 'DISCRETE' | 'RES CHIP 7.32K 1/20W +-1%(0201)'                  | 'CHIPR0201'    | ''          | ''            | '20181219'
 '7.32K'      | '1%'      | '1/20W'  | '0201LF'  | 'EMPTY'  | 'CS27321FE01'(!)        = ''              | ''                 | 'CS27321FE01'           |'R0201'| '(SMR0201AW)'                  | '7.32K'   | '1%'    | '1/20W'  | 'IO'       | 'RES CHIP 7.32K 1/20W +-1%(0201)'                  | 'CHIPR0201'    | ''          | ''            | '20181219'
 '0.01'       | '1%'      | '2W'     | '2512LF'  | 'CHIP'   | 'CS+010AFR01'(!)        = ''              | ''                 | 'CS+010AFR01'           |'R2512XT'| '(SMR2512AW)'                  | '0.01'    | '1%'    | '2W'     | 'DISCRETE' | 'RES CHIP 0.01 2W +-1%(2512)AEC'                   | 'CHIP2512'     | ''          | ''            | '20190103'
 '0.01'       | '1%'      | '2W'     | '2512LF'  | 'EMPTY'  | 'CS+010AFR01'(!)        = ''              | ''                 | 'CS+010AFR01'           |'R2512XT'| '(SMR2512AW)'                  | '0.01'    | '1%'    | '2W'     | 'IO'       | 'RES CHIP 0.01 2W +-1%(2512)AEC'                   | 'CHIP2512'     | ''          | ''            | '20190103'
 '360'        | '1%'      | '1/8W'   | '0805LF'  | 'CHIP'   | 'CS13604FA00'(!)        = ''              | ''                 | 'CS13604FA00'           |'R0805'| '(SMR0805AW)'                  | '360'     | '1%'    | '1/8W'   | 'DISCRETE' | 'RES CHIP 360 1/8W +-1%(0805)'                     | 'CHIPR0805'    | ''          | ''            | '20190103'
 '360'        | '1%'      | '1/8W'   | '0805LF'  | 'EMPTY'  | 'CS13604FA00'(!)        = ''              | ''                 | 'CS13604FA00'           |'R0805'| '(SMR0805AW)'                  | '360'     | '1%'    | '1/8W'   | 'IO'       | 'RES CHIP 360 1/8W +-1%(0805)'                     | 'CHIPR0805'    | ''          | ''            | '20190103'
 '887'        | '1%'      | '1/8W'   | '0805LF'  | 'CHIP'   | 'CS18874FA00'(!)        = ''              | ''                 | 'CS18874FA00'           |'R0805'| '(SMR0805AW)'                  | '887'     | '1%'    | '1/8W'   | 'DISCRETE' | 'RES CHIP 887 1/8W +-1%(0805)'                     | 'CHIPR0805'    | ''          | ''            | '20190104'
 '887'        | '1%'      | '1/8W'   | '0805LF'  | 'EMPTY'  | 'CS18874FA00'(!)        = ''              | ''                 | 'CS18874FA00'           |'R0805'| '(SMR0805AW)'                  | '887'     | '1%'    | '1/8W'   | 'IO'       | 'RES CHIP 887 1/8W +-1%(0805)'                     | 'CHIPR0805'    | ''          | ''            | '20190104'
 '43.2K'      | '1%'      | '1/16W'  | '0402LF'  | 'CHIP'   | 'CS34322FB00'(!)        = 'End of Design' | 'Comp-Approve'     | 'CS34322FB00'           |'R0402'| '(R0402-0201)'                 | '43.2K'   | '1%'    | '1/16W'  | 'DISCRETE' | 'RES CHIP 43.2K 1/16W +-1%(0402)'                  | 'CHIPR0402'    | ''          | ''            | '20190107'
 '43.2K'      | '1%'      | '1/16W'  | '0402LF'  | 'EMPTY'  | 'CS34322FB00'(!)        = 'End of Design' | 'Comp-Approve'     | 'CS34322FB00'           |'R0402'| '(R0402-0201)'                 | '43.2K'   | '1%'    | '1/16W'  | 'IO'       | 'RES CHIP 43.2K 1/16W +-1%(0402)'                  | 'CHIPR0402'    | ''          | ''            | '20190107'
 '21K'        | '1%'      | '1/10W'  | '0603LF'  | 'CHIP'   | 'CS32103F911'(!)        = ''              | ''                 | 'CS32103F911'           |'R0603'| '(SMR0603AW)'                  | '21K'     | '1%'    | '1/10W'  | 'DISCRETE' | 'RES CHIP 21K 1/10W+-1%(0603)'                     | 'CHIPR0603'    | ''          | ''            | '20190111'
 '21K'        | '1%'      | '1/10W'  | '0603LF'  | 'EMPTY'  | 'CS32103F911'(!)        = ''              | ''                 | 'CS32103F911'           |'R0603'| '(SMR0603AW)'                  | '21K'     | '1%'    | '1/10W'  | 'IO'       | 'RES CHIP 21K 1/10W+-1%(0603)'                     | 'CHIPR0603'    | ''          | ''            | '20190111'
 '909'        | '0.1%'    | '1/16W'  | '0402LF'  | 'CHIP'   | 'CS19092BB00'(!)        = ''              | ''                 | 'CS19092BB00'           |'R0402'| '(R0402-0201)'                 | '909'     | '0.1%'  | '1/16W'  | 'DISCRETE' | 'RES CHIP 909 1/16W +-0.1%(0402)EF'                | 'CHIPR0402'    | ''          | ''            | '20190115'
 '909'        | '0.1%'    | '1/16W'  | '0402LF'  | 'EMPTY'  | 'CS19092BB00'(!)        = ''              | ''                 | 'CS19092BB00'           |'R0402'| '(R0402-0201)'                 | '909'     | '0.1%'  | '1/16W'  | 'IO'       | 'RES CHIP 909 1/16W +-0.1%(0402)EF'                | 'CHIPR0402'    | ''          | ''            | '20190115'
 '90.9K'      | '0.1%'    | '1/16W'  | '0402LF'  | 'CHIP'   | 'CS39092BB00'(!)        = ''              | ''                 | 'CS39092BB00'           |'R0402'| '(R0402-0201)'                 | '90.9K'   | '0.1%'  | '1/16W'  | 'DISCRETE' | 'RES CHIP 90.9K 1/16W +-0.1%(0402)EF'              | 'CHIPR0402'    | ''          | ''            | '20190115'
 '90.9K'      | '0.1%'    | '1/16W'  | '0402LF'  | 'EMPTY'  | 'CS39092BB00'(!)        = ''              | ''                 | 'CS39092BB00'           |'R0402'| '(R0402-0201)'                 | '90.9K'   | '0.1%'  | '1/16W'  | 'IO'       | 'RES CHIP 90.9K 1/16W +-0.1%(0402)EF'              | 'CHIPR0402'    | ''          | ''            | '20190115'
 '240'        | '0.5%'    | '1/16W'  | '0402LF'  | 'CHIP'   | 'CS12402DB00'(!)        = 'End of Design' | 'Comp-Approve'     | 'CS12402DB00'           |'R0402'| '(R0402-0201)'                 | '240'     | '0.5%'  | '1/16W'  | 'DISCRETE' | 'RES CHIP 240 1/16W +-0.5%(0402)'                  | 'CHIPR0402'    | ''          | ''            | '20190115'
 '240'        | '0.5%'    | '1/16W'  | '0402LF'  | 'EMPTY'  | 'CS12402DB00'(!)        = 'End of Design' | 'Comp-Approve'     | 'CS12402DB00'           |'R0402'| '(R0402-0201)'                 | '240'     | '0.5%'  | '1/16W'  | 'IO'       | 'RES CHIP 240 1/16W +-0.5%(0402)'                  | 'CHIPR0402'    | ''          | ''            | '20190115'
 '11.8K'      | '0.1%'    | '1/16W'  | '0402LF'  | 'CHIP'   | 'CS31182BB00'(!)        = ''              | ''                 | 'CS31182BB00'           |'R0402'| '(R0402-0201)'                 | '11.8K'   | '0.1%'  | '1/16W'  | 'DISCRETE' | 'RES CHIP 11.8K 1/16W +-0.1%(0402)'                | 'CHIPR0402'    | ''          | ''            | '20190117'
 '11.8K'      | '0.1%'    | '1/16W'  | '0402LF'  | 'EMPTY'  | 'CS31182BB00'(!)        = ''              | ''                 | 'CS31182BB00'           |'R0402'| '(R0402-0201)'                 | '11.8K'   | '0.1%'  | '1/16W'  | 'IO'       | 'RES CHIP 11.8K 1/16W +-0.1%(0402)'                | 'CHIPR0402'    | ''          | ''            | '20190117'
 '12.4K'      | '0.1%'    | '1/16W'  | '0402LF'  | 'CHIP'   | 'CS31242BB00'(!)        = 'End of Design' | 'Comp-Approve'     | 'CS31242BB00'           |'R0402'| '(R0402-0201)'                 | '12.4K'   | '0.1%'  | '1/16W'  | 'DISCRETE' | 'RES CHIP 12.4K 1/16W +-0.1%( 0402)'               | 'CHIPR0402'    | ''          | ''            | '20190117'
 '12.4K'      | '0.1%'    | '1/16W'  | '0402LF'  | 'EMPTY'  | 'CS31242BB00'(!)        = 'End of Design' | 'Comp-Approve'     | 'CS31242BB00'           |'R0402'| '(R0402-0201)'                 | '12.4K'   | '0.1%'  | '1/16W'  | 'IO'       | 'RES CHIP 12.4K 1/16W +-0.1%( 0402)'               | 'CHIPR0402'    | ''          | ''            | '20190117'
 '42.2'       | '1%'      | '1/20W'  | '0201LF'  | 'CHIP'   | 'CS04221FE00'(!)        = ''              | ''                 | 'CS04221FE00'           |'R0201'| '(SMR0201AW)'                  | '42.2'    | '1%'    | '1/20W'  | 'DISCRETE' | 'RES CHIP 42.2 (1/20W,+-1%,0201)'                  | 'CHIPR0201'    | ''          | ''            | '20190123'
 '42.2'       | '1%'      | '1/20W'  | '0201LF'  | 'EMPTY'  | 'CS04221FE00'(!)        = ''              | ''                 | 'CS04221FE00'           |'R0201'| '(SMR0201AW)'                  | '42.2'    | '1%'    | '1/20W'  | 'IO'       | 'RES CHIP 42.2 (1/20W,+-1%,0201)'                  | 'CHIPR0201'    | ''          | ''            | '20190123'
 '43.2'       | '1%'      | '1/20W'  | '0201LF'  | 'CHIP'   | 'CS04321FE01'(!)        = ''              | ''                 | 'CS04321FE01'           |'R0201'| '(SMR0201AW)'                  | '43.2'    | '1%'    | '1/20W'  | 'DISCRETE' | 'RES CHIP 43.2 1/20W +-1%(0201)'                   | 'CHIPR0201'    | ''          | ''            | '20190124'
 '43.2'       | '1%'      | '1/20W'  | '0201LF'  | 'EMPTY'  | 'CS04321FE01'(!)        = ''              | ''                 | 'CS04321FE01'           |'R0201'| '(SMR0201AW)'                  | '43.2'    | '1%'    | '1/20W'  | 'IO'       | 'RES CHIP 43.2 1/20W +-1%(0201)'                   | 'CHIPR0201'    | ''          | ''            | '20190124'
 '4.75K'      | '1%'      | '1/16W'  | '0402LF'  | 'CHIP'   | 'CS24752FB03'(!)        = 'End of Design' | 'Comp-Approve'     | 'CS24752FB03'           |'R0402'| '(R0402-0201)'                 | '4.75K'   | '1%'    | '1/16W'  | 'DISCRETE' | 'RES CHIP 4.75K 1/16W +-1%(0402)EF'                | 'CHIPR0402'    | ''          | ''            | '20190124'
 '4.75K'      | '1%'      | '1/16W'  | '0402LF'  | 'EMPTY'  | 'CS24752FB03'(!)        = 'End of Design' | 'Comp-Approve'     | 'CS24752FB03'           |'R0402'| '(R0402-0201)'                 | '4.75K'   | '1%'    | '1/16W'  | 'IO'       | 'RES CHIP 4.75K 1/16W +-1%(0402)EF'                | 'CHIPR0402'    | ''          | ''            | '20190124'
 '15'         | '1%'      | '1/16W'  | '0402LF'  | 'CHIP'   | 'CS01502FB03'(!)        = 'End of Design' | 'Comp-Approve'     | 'CS01502FB03'           |'R0402'| '(R0402-0201)'                 | '15'      | '1%'    | '1/16W'  | 'DISCRETE' | 'RES CHIP 15 1/16W +-1%(0402)EF'                   | 'CHIPR0402'    | ''          | ''            | '20190212'
 '15'         | '1%'      | '1/16W'  | '0402LF'  | 'EMPTY'  | 'CS01502FB03'(!)        = 'End of Design' | 'Comp-Approve'     | 'CS01502FB03'           |'R0402'| '(R0402-0201)'                 | '15'      | '1%'    | '1/16W'  | 'IO'       | 'RES CHIP 15 1/16W +-1%(0402)EF'                   | 'CHIPR0402'    | ''          | ''            | '20190212'
 '825'        | '1%'      | '1/4W'   | '1206LF'  | 'CHIP'   | 'CS18256F200'(!)        = ''              | ''                 | 'CS18256F200'           |'R1206XF'| '(SMR1206AW)'                  | '825'     | '1%'    | '1/4W'   | 'DISCRETE' | 'RES CHIP 825 1/4W +-1%(1206)'                     | 'CHIPR1206'    | ''          | ''            | '20190214'
 '825'        | '1%'      | '1/4W'   | '1206LF'  | 'EMPTY'  | 'CS18256F200'(!)        = ''              | ''                 | 'CS18256F200'           |'R1206XF'| '(SMR1206AW)'                  | '825'     | '1%'    | '1/4W'   | 'IO'       | 'RES CHIP 825 1/4W +-1%(1206)'                     | 'CHIPR1206'    | ''          | ''            | '20190214'
 '20M'        | '5%'      | '1/10W'  | '0603LF'  | 'CHIP'   | 'CS62003J914'(!)        = ''              | ''                 | 'CS62003J914'           |'R0603'| '(SMR0603AW)'                  | '20M'     | '5%'    | '1/10W'  | 'DISCRETE' | 'RES CHIP 20M  1/10W +-5%(0603)'                   | 'CHIPR0603'    | ''          | ''            | '20100429'
 '20M'        | '5%'      | '1/10W'  | '0603LF'  | 'EMPTY'  | 'CS62003J914'(!)        = ''              | ''                 | 'CS62003J914'           |'R0603'| '(SMR0603AW)'                  | '20M'     | '5%'    | '1/10W'  | 'IO'       | 'RES CHIP 20M  1/10W +-5%(0603)'                   | 'CHIPR0603'    | ''          | ''            | '20100429'
 '3.3K'       | '5%'      | '1/8W'   | '0805LF'  | 'CHIP'   | 'CS23304JA01'(!)        = ''              | ''                 | 'CS23304JA01'           |'R0805'| '(SMR0805AW)'                  | '3.3K'    | '5%'    | '1/8W'   | 'DISCRETE' | 'RES CHIP 3.3K 1/8W +-5%(0805)'                    | 'CHIPR0805'    | ''          | ''            | '20190318'
 '3.3K'       | '5%'      | '1/8W'   | '0805LF'  | 'EMPTY'  | 'CS23304JA01'(!)        = ''              | ''                 | 'CS23304JA01'           |'R0805'| '(SMR0805AW)'                  | '3.3K'    | '5%'    | '1/8W'   | 'IO'       | 'RES CHIP 3.3K 1/8W +-5%(0805)'                    | 'CHIPR0805'    | ''          | ''            | '20190318'
 '162'        | '1%'      | '1/16W'  | '0402LF'  | 'CHIP'   | 'CS11622FB01'(!)        = 'End of Design' | 'Comp-Approve'     | 'CS11622FB01'           |'R0402'| '(R0402-0201)'                 | '162'     | '1%'    | '1/16W'  | 'DISCRETE' | 'RES CHIP 162 1/16W +-1%(0402)EF'                  | 'CHIPR0402'    | ''          | ''            | '20190325'
 '162'        | '1%'      | '1/16W'  | '0402LF'  | 'EMPTY'  | 'CS11622FB01'(!)        = 'End of Design' | 'Comp-Approve'     | 'CS11622FB01'           |'R0402'| '(R0402-0201)'                 | '162'     | '1%'    | '1/16W'  | 'IO'       | 'RES CHIP 162 1/16W +-1%(0402)EF'                  | 'CHIPR0402'    | ''          | ''            | '20190325'
 '681'        | '1%'      | '1/16W'  | '0402LF'  | 'CHIP'   | 'CS16812FB02'(!)        = 'End of Design' | 'Comp-Approve'     | 'CS16812FB02'           |'R0402'| '(R0402-0201)'                 | '681'     | '1%'    | '1/16W'  | 'DISCRETE' | 'RES CHIP 681 1/16W +-1%(0402)EF'                  | 'CHIPR0402'    | ''          | ''            | '20190325'
 '681'        | '1%'      | '1/16W'  | '0402LF'  | 'EMPTY'  | 'CS16812FB02'(!)        = 'End of Design' | 'Comp-Approve'     | 'CS16812FB02'           |'R0402'| '(R0402-0201)'                 | '681'     | '1%'    | '1/16W'  | 'IO'       | 'RES CHIP 681 1/16W +-1%(0402)EF'                  | 'CHIPR0402'    | ''          | ''            | '20190325'
 '1.82M'      | '1%'      | '1/16W'  | '0402LF'  | 'CHIP'   | 'CS51822FB00'(!)        = ''              | ''                 | 'CS51822FB00'           |'R0402'| '(R0402-0201)'                 | '1.82M'   | '1%'    | '1/16W'  | 'DISCRETE' | 'RES CHIP 1.82M 1/16W +-1%(0402)'                  | 'CHIPR0402'    | ''          | ''            | '20190429'
 '1.82M'      | '1%'      | '1/16W'  | '0402LF'  | 'EMPTY'  | 'CS51822FB00'(!)        = ''              | ''                 | 'CS51822FB00'           |'R0402'| '(R0402-0201)'                 | '1.82M'   | '1%'    | '1/16W'  | 'IO'       | 'RES CHIP 1.82M 1/16W +-1%(0402)'                  | 'CHIPR0402'    | ''          | ''            | '20190429'
 '240'        | '1%'      | '1/8W'   | '0805LF'  | 'CHIP'   | 'CS12404FA01'(!)        = ''              | ''                 | 'CS12404FA01'           |'R0805'| '(SMR0805AW)'                  | '240'     | '1%'    | '1/8W'   | 'DISCRETE' | 'RES CHIP 240 1/8W +-1%(0805)'                     | 'CHIPR0805'    | ''          | ''            | '20190521'
 '240'        | '1%'      | '1/8W'   | '0805LF'  | 'EMPTY'  | 'CS12404FA01'(!)        = ''              | ''                 | 'CS12404FA01'           |'R0805'| '(SMR0805AW)'                  | '240'     | '1%'    | '1/8W'   | 'IO'       | 'RES CHIP 240 1/8W +-1%(0805)'                     | 'CHIPR0805'    | ''          | ''            | '20190521'
 '1.62K'      | '0.1%'    | '1/16W'  | '0402LF'  | 'CHIP'   | 'CS21622BB00'(!)        = ''              | ''                 | 'CS21622BB00'           |'R0402'| '(R0402-0201)'                 | '1.62K'   | '0.1%'  | '1/16W'  | 'DISCRETE' | 'RES CHIP 1.62K 1/16W +-0.1%(0402)'                | 'CHIPR0402'    | ''          | ''            | '20190527'
 '1.62K'      | '0.1%'    | '1/16W'  | '0402LF'  | 'EMPTY'  | 'CS21622BB00'(!)        = ''              | ''                 | 'CS21622BB00'           |'R0402'| '(R0402-0201)'                 | '1.62K'   | '0.1%'  | '1/16W'  | 'IO'       | 'RES CHIP 1.62K 1/16W +-0.1%(0402)'                | 'CHIPR0402'    | ''          | ''            | '20190527'
 '95.3K'      | '0.1%'    | '1/8W'   | '0805LF'  | 'CHIP'   | 'CS39534BA00'(!)        = ''              | ''                 | 'CS39534BA00'           |'R0805'| '(SMR0805AW)'                  | '95.3K'   | '0.1%'  | '1/8W'   | 'DISCRETE' | 'RES CHIP 95.3K 1/8W +-0.1%(0805)'                 | 'CHIPR0805'    | ''          | ''            | '20190529'
 '95.3K'      | '0.1%'    | '1/8W'   | '0805LF'  | 'EMPTY'  | 'CS39534BA00'(!)        = ''              | ''                 | 'CS39534BA00'           |'R0805'| '(SMR0805AW)'                  | '95.3K'   | '0.1%'  | '1/8W'   | 'IO'       | 'RES CHIP 95.3K 1/8W +-0.1%(0805)'                 | 'CHIPR0805'    | ''          | ''            | '20190529'
 '909'        | '1%'      | '1/16W'  | '0402LF'  | 'CHIP'   | 'CS19092FB03'(!)        = 'End of Design' | 'Comp-Approve'     | 'CS19092FB03'           |'R0402'| '(R0402-0201)'                 | '909'     | '1%'    | '1/16W'  | 'DISCRETE' | 'RES CHIP 909 1/16W +-1%(0402)EF'                  | 'CHIPR0402'    | ''          | ''            | '20190614'
 '909'        | '1%'      | '1/16W'  | '0402LF'  | 'EMPTY'  | 'CS19092FB03'(!)        = 'End of Design' | 'Comp-Approve'     | 'CS19092FB03'           |'R0402'| '(R0402-0201)'                 | '909'     | '1%'    | '1/16W'  | 'IO'       | 'RES CHIP 909 1/16W +-1%(0402)EF'                  | 'CHIPR0402'    | ''          | ''            | '20190614'
 '90.9K'      | '1%'      | '1/16W'  | '0402LF'  | 'CHIP'   | 'CS39092FB04'(!)        = 'End of Design' | 'Comp-Approve'     | 'CS39092FB04'           |'R0402'| '(R0402-0201)'                 | '90.9K'   | '1%'    | '1/16W'  | 'DISCRETE' | 'RES CHIP 90.9K 1/16W +-1%(0402)EF'                | 'CHIPR0402'    | ''          | ''            | '20190715'
 '90.9K'      | '1%'      | '1/16W'  | '0402LF'  | 'EMPTY'  | 'CS39092FB04'(!)        = 'End of Design' | 'Comp-Approve'     | 'CS39092FB04'           |'R0402'| '(R0402-0201)'                 | '90.9K'   | '1%'    | '1/16W'  | 'IO'       | 'RES CHIP 90.9K 1/16W +-1%(0402)EF'                | 'CHIPR0402'    | ''          | ''            | '20190715'
 '33.2K'      | '1%'      | '1/16W'  | '0402LF'  | 'CHIP'   | 'CS33322FB03'(!)        = 'End of Design' | 'Comp-Approve'     | 'CS33322FB03'           |'R0402'| '(R0402-0201)'                 | '33.2K'   | '1%'    | '1/16W'  | 'DISCRETE' | 'RES CHIP 33.2K 1/16W +-1%(0402)EF'                | 'CHIPR0402'    | ''          | ''            | '20190715'
 '33.2K'      | '1%'      | '1/16W'  | '0402LF'  | 'EMPTY'  | 'CS33322FB03'(!)        = 'End of Design' | 'Comp-Approve'     | 'CS33322FB03'           |'R0402'| '(R0402-0201)'                 | '33.2K'   | '1%'    | '1/16W'  | 'IO'       | 'RES CHIP 33.2K 1/16W +-1%(0402)EF'                | 'CHIPR0402'    | ''          | ''            | '20190715'
 '5.6K'       | '1%'      | '1/16W'  | '0402LF'  | 'CHIP'   | 'CS25602FB04'(!)        = ''              | ''                 | 'CS25602FB04'           |'R0402'| '(R0402-0201)'                 | '5.6K'    | '1%'    | '1/16W'  | 'DISCRETE' | 'RES CHIP 5.6K 1/16W +-1%(0402)EF'                 | 'CHIPR0402'    | ''          | ''            | '20190711'
 '5.6K'       | '1%'      | '1/16W'  | '0402LF'  | 'EMPTY'  | 'CS25602FB04'(!)        = ''              | ''                 | 'CS25602FB04'           |'R0402'| '(R0402-0201)'                 | '5.6K'    | '1%'    | '1/16W'  | 'IO'       | 'RES CHIP 5.6K 1/16W +-1%(0402)EF'                 | 'CHIPR0402'    | ''          | ''            | '20190711'
 '56K'        | '1%'      | '1/16W'  | '0402LF'  | 'CHIP'   | 'CS35602FB00'(!)        = ''              | ''                 | 'CS35602FB00'           |'R0402'| '(R0402-0201)'                 | '56K'     | '1%'    | '1/16W'  | 'DISCRETE' | 'RES CHIP 56K 1/16W +-1%(0402)EF'                  | 'CHIPR0402'    | ''          | ''            | '20190711'
 '56K'        | '1%'      | '1/16W'  | '0402LF'  | 'EMPTY'  | 'CS35602FB00'(!)        = ''              | ''                 | 'CS35602FB00'           |'R0402'| '(R0402-0201)'                 | '56K'     | '1%'    | '1/16W'  | 'IO'       | 'RES CHIP 56K 1/16W +-1%(0402)EF'                  | 'CHIPR0402'    | ''          | ''            | '20190711'
 '59K'        | '1%'      | '1/16W'  | '0402LF'  | 'CHIP'   | 'CS35902FB01'(!)        = 'End of Design' | 'Comp-Approve'     | 'CS35902FB01'           |'R0402'| '(R0402-0201)'                 | '59K'     | '1%'    | '1/16W'  | 'DISCRETE' | 'RES CHIP 59K 1/16W +-1%(0402)EF'                  | 'CHIPR0402'    | ''          | ''            | '20190711'
 '59K'        | '1%'      | '1/16W'  | '0402LF'  | 'EMPTY'  | 'CS35902FB01'(!)        = 'End of Design' | 'Comp-Approve'     | 'CS35902FB01'           |'R0402'| '(R0402-0201)'                 | '59K'     | '1%'    | '1/16W'  | 'IO'       | 'RES CHIP 59K 1/16W +-1%(0402)EF'                  | 'CHIPR0402'    | ''          | ''            | '20190711'
 '71.5K'      | '1%'      | '1/16W'  | '0402LF'  | 'CHIP'   | 'CS37152FB05'(!)        = ''              | ''                 | 'CS37152FB05'           |'R0402'| '(R0402-0201)'                 | '71.5K'   | '1%'    | '1/16W'  | 'DISCRETE' | 'RES CHIP 71.5K 1/16W +-1%(0402)EF'                | 'CHIPR0402'    | ''          | ''            | '20190717'
 '71.5K'      | '1%'      | '1/16W'  | '0402LF'  | 'EMPTY'  | 'CS37152FB05'(!)        = ''              | ''                 | 'CS37152FB05'           |'R0402'| '(R0402-0201)'                 | '71.5K'   | '1%'    | '1/16W'  | 'IO'       | 'RES CHIP 71.5K 1/16W +-1%(0402)EF'                | 'CHIPR0402'    | ''          | ''            | '20190717'
 '24.3K'      | '1%'      | '1/16W'  | '0402LF'  | 'CHIP'   | 'CS32432FB03'(!)        = ''              | ''                 | 'CS32432FB03'           |'R0402'| '(R0402-0201)'                 | '24.3K'   | '1%'    | '1/16W'  | 'DISCRETE' | 'RES CHIP 24.3K 1/16W +-1%(0402)EF'                | 'CHIPR0402'    | ''          | ''            | '20190717'
 '24.3K'      | '1%'      | '1/16W'  | '0402LF'  | 'EMPTY'  | 'CS32432FB03'(!)        = ''              | ''                 | 'CS32432FB03'           |'R0402'| '(R0402-0201)'                 | '24.3K'   | '1%'    | '1/16W'  | 'IO'       | 'RES CHIP 24.3K 1/16W +-1%(0402)EF'                | 'CHIPR0402'    | ''          | ''            | '20190717'
 '115K'       | '1%'      | '1/16W'  | '0402LF'  | 'CHIP'   | 'CS41152FB03'(!)        = 'End of Design' | 'Comp-Approve'     | 'CS41152FB03'           |'R0402'| '(R0402-0201)'                 | '115K'    | '1%'    | '1/16W'  | 'DISCRETE' | 'RES CHIP 115K 1/16W +-1%(0402)EF'                 | 'CHIPR0402'    | ''          | ''            | '20190718'
 '115K'       | '1%'      | '1/16W'  | '0402LF'  | 'EMPTY'  | 'CS41152FB03'(!)        = 'End of Design' | 'Comp-Approve'     | 'CS41152FB03'           |'R0402'| '(R0402-0201)'                 | '115K'    | '1%'    | '1/16W'  | 'IO'       | 'RES CHIP 115K 1/16W +-1%(0402)EF'                 | 'CHIPR0402'    | ''          | ''            | '20190718'
 '6.04K'      | '1%'      | '1/16W'  | '0402LF'  | 'CHIP'   | 'CS26042FB04'(!)        = 'End of Design' | 'Comp-Approve'     | 'CS26042FB04'           |'R0402'| '(R0402-0201)'                 | '6.04K'   | '1%'    | '1/16W'  | 'DISCRETE' | 'RES CHIP 6.04K 1/16W +-1%(0402)EF'                | 'CHIPR0402'    | ''          | ''            | '20190717'
 '6.04K'      | '1%'      | '1/16W'  | '0402LF'  | 'EMPTY'  | 'CS26042FB04'(!)        = 'End of Design' | 'Comp-Approve'     | 'CS26042FB04'           |'R0402'| '(R0402-0201)'                 | '6.04K'   | '1%'    | '1/16W'  | 'IO'       | 'RES CHIP 6.04K 1/16W +-1%(0402)EF'                | 'CHIPR0402'    | ''          | ''            | '20190717'
 '1.33K'      | '1%'      | '1/16W'  | '0402LF'  | 'CHIP'   | 'CS21332FB05'(!)        = ''              | ''                 | 'CS21332FB05'           |'R0402'| '(R0402-0201)'                 | '1.33K'   | '1%'    | '1/16W'  | 'DISCRETE' | 'RES CHIP 1.33K 1/16W +-1%(0402)EF'                | 'CHIPR0402'    | ''          | ''            | '20190717'
 '1.33K'      | '1%'      | '1/16W'  | '0402LF'  | 'EMPTY'  | 'CS21332FB05'(!)        = ''              | ''                 | 'CS21332FB05'           |'R0402'| '(R0402-0201)'                 | '1.33K'   | '1%'    | '1/16W'  | 'IO'       | 'RES CHIP 1.33K 1/16W +-1%(0402)EF'                | 'CHIPR0402'    | ''          | ''            | '20190717'
 '1'          | '5%'      | '1/16W'  | '0402LF'  | 'CHIP'   | 'CS-1002JB10'(!)        = 'End of Design' | 'Comp-Approve'     | 'CS-1002JB10'           |'R0402'| '(R0402-0201)'                 | '1'       | '5%'    | '1/16W'  | 'DISCRETE' | 'RES CHIP 1 1/16W +-5%(0402)EF'                    | 'CHIPR0402'    | ''          | ''            | '20190717'
 '1'          | '5%'      | '1/16W'  | '0402LF'  | 'EMPTY'  | 'CS-1002JB10'(!)        = 'End of Design' | 'Comp-Approve'     | 'CS-1002JB10'           |'R0402'| '(R0402-0201)'                 | '1'       | '5%'    | '1/16W'  | 'IO'       | 'RES CHIP 1 1/16W +-5%(0402)EF'                    | 'CHIPR0402'    | ''          | ''            | '20190717'
 '40.2K'      | '1%'      | '1/20W'  | '0201LF'  | 'CHIP'   | 'CS34021FE02'(!)        = ''              | ''                 | 'CS34021FE02'           |'R0201'| '(SMR0201AW)'                  | '40.2K'   | '1%'    | '1/20W'  | 'DISCRETE' | 'RES CHIP 40.2K 1/20W +-1%(0201)'                  | 'CHIPR0201'    | ''          | ''            | '20190718'
 '40.2K'      | '1%'      | '1/20W'  | '0201LF'  | 'EMPTY'  | 'CS34021FE02'(!)        = ''              | ''                 | 'CS34021FE02'           |'R0201'| '(SMR0201AW)'                  | '40.2K'   | '1%'    | '1/20W'  | 'IO'       | 'RES CHIP 40.2K 1/20W +-1%(0201)'                  | 'CHIPR0201'    | ''          | ''            | '20190718'
 '200'        | '5%'      | '1/10W'  | '0603LF'  | 'CHIP'   | 'CS12003J901'(!)        = ''              | ''                 | 'CS12003J901'           |'R0603_H24'| '(SMR0603AW)'                  | '200'     | '5%'    | '1/10W'  | 'DISCRETE' | 'RES CHIP 200 1/10W +-5%(0603)EF'                  | 'CHIPR0603'    | ''          | ''            | '20190717'
 '200'        | '5%'      | '1/10W'  | '0603LF'  | 'EMPTY'  | 'CS12003J901'(!)        = ''              | ''                 | 'CS12003J901'           |'R0603_H24'| '(SMR0603AW)'                  | '200'     | '5%'    | '1/10W'  | 'IO'       | 'RES CHIP 200 1/10W +-5%(0603)EF'                  | 'CHIPR0603'    | ''          | ''            | '20190717'
 '2.2'        | '5%'      | '1/16W'  | '0402LF'  | 'CHIP'   | 'CS-2202JB07'(!)        = 'End of Design' | 'Comp-Approve'     | 'CS-2202JB07'           |'R0402'| '(R0402-0201)'                 | '2.2'     | '5%'    | '1/16W'  | 'DISCRETE' | 'RES CHIP 2.2 1/16W +-5%  (0402) EF'               | 'CHIPR0402'    | ''          | ''            | '20190717'
 '2.2'        | '5%'      | '1/16W'  | '0402LF'  | 'EMPTY'  | 'CS-2202JB07'(!)        = 'End of Design' | 'Comp-Approve'     | 'CS-2202JB07'           |'R0402'| '(R0402-0201)'                 | '2.2'     | '5%'    | '1/16W'  | 'IO'       | 'RES CHIP 2.2 1/16W +-5%  (0402) EF'               | 'CHIPR0402'    | ''          | ''            | '20190717'
 '4.42K'      | '1%'      | '1/16W'  | '0402LF'  | 'CHIP'   | 'CS24422FB03'(!)        = 'End of Design' | 'Comp-Approve'     | 'CS24422FB03'           |'R0402'| '(R0402-0201)'                 | '4.42K'   | '1%'    | '1/16W'  | 'DISCRETE' | 'RES CHIP 4.42K 1/16W +-1%(0402)EF'                | 'CHIPR0402'    | ''          | ''            | '20190717'
 '4.42K'      | '1%'      | '1/16W'  | '0402LF'  | 'EMPTY'  | 'CS24422FB03'(!)        = 'End of Design' | 'Comp-Approve'     | 'CS24422FB03'           |'R0402'| '(R0402-0201)'                 | '4.42K'   | '1%'    | '1/16W'  | 'IO'       | 'RES CHIP 4.42K 1/16W +-1%(0402)EF'                | 'CHIPR0402'    | ''          | ''            | '20190717'
 '4.99K'      | '1%'      | '1/16W'  | '0402LF'  | 'CHIP'   | 'CS24992FB07'(!)        = 'End of Design' | 'Comp-Approve'     | 'CS24992FB07'           |'R0402'| '(R0402-0201)'                 | '4.99K'   | '1%'    | '1/16W'  | 'DISCRETE' | 'RES CHIP 4.99K 1/16W +-1%(0402)EF'                | 'CHIPR0402'    | ''          | ''            | '20190717'
 '4.99K'      | '1%'      | '1/16W'  | '0402LF'  | 'EMPTY'  | 'CS24992FB07'(!)        = 'End of Design' | 'Comp-Approve'     | 'CS24992FB07'           |'R0402'| '(R0402-0201)'                 | '4.99K'   | '1%'    | '1/16W'  | 'IO'       | 'RES CHIP 4.99K 1/16W +-1%(0402)EF'                | 'CHIPR0402'    | ''          | ''            | '20190717'
 '8.25K'      | '0.1%'    | '1/16W'  | '0402LF'  | 'CHIP'   | 'CS28252BB01'(!)        = ''              | ''                 | 'CS28252BB01'           |'R0402'| '(R0402-0201)'                 | '8.25K'   | '0.1%'  | '1/16W'  | 'DISCRETE' | 'RES CHIP 8.25K 1/16W +-0.1%(0402)EF'              | 'CHIPR0402'    | ''          | ''            | '20190717'
 '8.25K'      | '0.1%'    | '1/16W'  | '0402LF'  | 'EMPTY'  | 'CS28252BB01'(!)        = ''              | ''                 | 'CS28252BB01'           |'R0402'| '(R0402-0201)'                 | '8.25K'   | '0.1%'  | '1/16W'  | 'IO'       | 'RES CHIP 8.25K 1/16W +-0.1%(0402)EF'              | 'CHIPR0402'    | ''          | ''            | '20190717'
 '8.87K'      | '1%'      | '1/16W'  | '0402LF'  | 'CHIP'   | 'CS28872FB01'(!)        = 'End of Design' | 'Comp-Approve'     | 'CS28872FB01'           |'R0402'| '(R0402-0201)'                 | '8.87K'   | '1%'    | '1/16W'  | 'DISCRETE' | 'RES CHIP 8.87K 1/16W +-1%(0402)EF'                | 'CHIPR0402'    | ''          | ''            | '20190718'
 '8.87K'      | '1%'      | '1/16W'  | '0402LF'  | 'EMPTY'  | 'CS28872FB01'(!)        = 'End of Design' | 'Comp-Approve'     | 'CS28872FB01'           |'R0402'| '(R0402-0201)'                 | '8.87K'   | '1%'    | '1/16W'  | 'IO'       | 'RES CHIP 8.87K 1/16W +-1%(0402)EF'                | 'CHIPR0402'    | ''          | ''            | '20190718'
 '18.2K'      | '1%'      | '1/16W'  | '0402LF'  | 'CHIP'   | 'CS31822FB02'(!)        = 'End of Design' | 'Comp-Approve'     | 'CS31822FB02'           |'R0402'| '(R0402-0201)'                 | '18.2K'   | '1%'    | '1/16W'  | 'DISCRETE' | 'RES CHIP 18.2K 1/16W +-1%(0402)EF'                | 'CHIPR0402'    | ''          | ''            | '20190718'
 '18.2K'      | '1%'      | '1/16W'  | '0402LF'  | 'EMPTY'  | 'CS31822FB02'(!)        = 'End of Design' | 'Comp-Approve'     | 'CS31822FB02'           |'R0402'| '(R0402-0201)'                 | '18.2K'   | '1%'    | '1/16W'  | 'IO'       | 'RES CHIP 18.2K 1/16W +-1%(0402)EF'                | 'CHIPR0402'    | ''          | ''            | '20190718'
 '31.6K'      | '1%'      | '1/16W'  | '0402LF'  | 'CHIP'   | 'CS33162FB02'(!)        = 'End of Design' | 'Comp-Approve'     | 'CS33162FB02'           |'R0402'| '(R0402-0201)'                 | '31.6K'   | '1%'    | '1/16W'  | 'DISCRETE' | 'RES CHIP 31.6K 1/16W +-1%(0402)EF'                | 'CHIPR0402'    | ''          | ''            | '20190718'
 '31.6K'      | '1%'      | '1/16W'  | '0402LF'  | 'EMPTY'  | 'CS33162FB02'(!)        = 'End of Design' | 'Comp-Approve'     | 'CS33162FB02'           |'R0402'| '(R0402-0201)'                 | '31.6K'   | '1%'    | '1/16W'  | 'IO'       | 'RES CHIP 31.6K 1/16W +-1%(0402)EF'                | 'CHIPR0402'    | ''          | ''            | '20190718'
 '41.2K'      | '1%'      | '1/16W'  | '0402LF'  | 'CHIP'   | 'CS34122FB03'(!)        = 'End of Design' | 'Comp-Approve'     | 'CS34122FB03'           |'R0402'| '(R0402-0201)'                 | '41.2K'   | '1%'    | '1/16W'  | 'DISCRETE' | 'RES CHIP 41.2K 1/16W +-1%(0402)EF'                | 'CHIPR0402'    | ''          | ''            | '20190718'
 '41.2K'      | '1%'      | '1/16W'  | '0402LF'  | 'EMPTY'  | 'CS34122FB03'(!)        = 'End of Design' | 'Comp-Approve'     | 'CS34122FB03'           |'R0402'| '(R0402-0201)'                 | '41.2K'   | '1%'    | '1/16W'  | 'IO'       | 'RES CHIP 41.2K 1/16W +-1%(0402)EF'                | 'CHIPR0402'    | ''          | ''            | '20190718'
 '47K'        | '5%'      | '1/16W'  | '0402LF'  | 'CHIP'   | 'CS34702JB09'(!)        = ''              | ''                 | 'CS34702JB09'           |'R0402'| '(R0402-0201)'                 | '47K'     | '5%'    | '1/16W'  | 'DISCRETE' | 'RES CHIP 47K 1/16W +-5%(0402)EF'                  | 'CHIPR0402'    | ''          | ''            | '20190718'
 '47K'        | '5%'      | '1/16W'  | '0402LF'  | 'EMPTY'  | 'CS34702JB09'(!)        = ''              | ''                 | 'CS34702JB09'           |'R0402'| '(R0402-0201)'                 | '47K'     | '5%'    | '1/16W'  | 'IO'       | 'RES CHIP 47K 1/16W +-5%(0402)EF'                  | 'CHIPR0402'    | ''          | ''            | '20190718'
 '53.6K'      | '1%'      | '1/16W'  | '0402LF'  | 'CHIP'   | 'CS35362FB02'(!)        = 'End of Design' | 'Comp-Approve'     | 'CS35362FB02'           |'R0402'| '(R0402-0201)'                 | '53.6K'   | '1%'    | '1/16W'  | 'DISCRETE' | 'RES CHIP 53.6K 1/16W +-1%(0402)EF'                | 'CHIPR0402'    | ''          | ''            | '20190718'
 '53.6K'      | '1%'      | '1/16W'  | '0402LF'  | 'EMPTY'  | 'CS35362FB02'(!)        = 'End of Design' | 'Comp-Approve'     | 'CS35362FB02'           |'R0402'| '(R0402-0201)'                 | '53.6K'   | '1%'    | '1/16W'  | 'IO'       | 'RES CHIP 53.6K 1/16W +-1%(0402)EF'                | 'CHIPR0402'    | ''          | ''            | '20190718'
 '60.4K'      | '0.1%'    | '1/16W'  | '0402LF'  | 'CHIP'   | 'CS36042BB01'(!)        = ''              | ''                 | 'CS36042BB01'           |'R0402'| '(R0402-0201)'                 | '60.4K'   | '0.1%'  | '1/16W'  | 'DISCRETE' | 'RES CHIP 60.4K 1/16W +-0.1%(0402)EF'              | 'CHIPR0402'    | ''          | ''            | '20190718'
 '60.4K'      | '0.1%'    | '1/16W'  | '0402LF'  | 'EMPTY'  | 'CS36042BB01'(!)        = ''              | ''                 | 'CS36042BB01'           |'R0402'| '(R0402-0201)'                 | '60.4K'   | '0.1%'  | '1/16W'  | 'IO'       | 'RES CHIP 60.4K 1/16W +-0.1%(0402)EF'              | 'CHIPR0402'    | ''          | ''            | '20190718'
 '61.9K'      | '1%'      | '1/16W'  | '0402LF'  | 'CHIP'   | 'CS36192FB04'(!)        = 'End of Design' | 'Comp-Approve'     | 'CS36192FB04'           |'R0402'| '(R0402-0201)'                 | '61.9K'   | '1%'    | '1/16W'  | 'DISCRETE' | 'RES CHIP 61.9K 1/16W +-1%(0402)EF'                | 'CHIPR0402'    | ''          | ''            | '20190718'
 '61.9K'      | '1%'      | '1/16W'  | '0402LF'  | 'EMPTY'  | 'CS36192FB04'(!)        = 'End of Design' | 'Comp-Approve'     | 'CS36192FB04'           |'R0402'| '(R0402-0201)'                 | '61.9K'   | '1%'    | '1/16W'  | 'IO'       | 'RES CHIP 61.9K 1/16W +-1%(0402)EF'                | 'CHIPR0402'    | ''          | ''            | '20190718'
 '82K'        | '1%'      | '1/16W'  | '0402LF'  | 'CHIP'   | 'CS38202FB01'(!)        = 'End of Design' | 'Comp-Approve'     | 'CS38202FB01'           |'R0402'| '(R0402-0201)'                 | '82K'     | '1%'    | '1/16W'  | 'DISCRETE' | 'RES CHIP 82K  1/16W +-1% (0402)EF'                | 'CHIPR0402'    | ''          | ''            | '20190718'
 '82K'        | '1%'      | '1/16W'  | '0402LF'  | 'EMPTY'  | 'CS38202FB01'(!)        = 'End of Design' | 'Comp-Approve'     | 'CS38202FB01'           |'R0402'| '(R0402-0201)'                 | '82K'     | '1%'    | '1/16W'  | 'IO'       | 'RES CHIP 82K  1/16W +-1% (0402)EF'                | 'CHIPR0402'    | ''          | ''            | '20190718'
 '140K'       | '1%'      | '1/16W'  | '0402LF'  | 'CHIP'   | 'CS41402FB01'(!)        = 'End of Design' | 'Comp-Approve'     | 'CS41402FB01'           |'R0402'| '(R0402-0201)'                 | '140K'    | '1%'    | '1/16W'  | 'DISCRETE' | 'RES CHIP 140K 1/16W +-1%(0402)EF'                 | 'CHIPR0402'    | ''          | ''            | '20190718'
 '140K'       | '1%'      | '1/16W'  | '0402LF'  | 'EMPTY'  | 'CS41402FB01'(!)        = 'End of Design' | 'Comp-Approve'     | 'CS41402FB01'           |'R0402'| '(R0402-0201)'                 | '140K'    | '1%'    | '1/16W'  | 'IO'       | 'RES CHIP 140K 1/16W +-1%(0402)EF'                 | 'CHIPR0402'    | ''          | ''            | '20190718'
 '200K'       | '5%'      | '1/16W'  | '0402LF'  | 'CHIP'   | 'CS42002JB02'(!)        = 'End of Design' | 'Comp-Approve'     | 'CS42002JB02'           |'R0402'| '(R0402-0201)'                 | '200K'    | '5%'    | '1/16W'  | 'DISCRETE' | 'RES CHIP 200K 1/16W +-5%(0402)EF'                 | 'CHIPR0402'    | ''          | ''            | '20190718'
 '200K'       | '5%'      | '1/16W'  | '0402LF'  | 'EMPTY'  | 'CS42002JB02'(!)        = 'End of Design' | 'Comp-Approve'     | 'CS42002JB02'           |'R0402'| '(R0402-0201)'                 | '200K'    | '5%'    | '1/16W'  | 'IO'       | 'RES CHIP 200K 1/16W +-5%(0402)EF'                 | 'CHIPR0402'    | ''          | ''            | '20190718'
 '22.6K'      | '1%'      | '1/16W'  | '0402LF'  | 'CHIP'   | 'CS32262FB02'(!)        = 'End of Design' | 'Comp-Approve'     | 'CS32262FB02'           |'R0402'| '(R0402-0201)'                 | '22.6K'   | '1%'    | '1/16W'  | 'DISCRETE' | 'RES CHIP 22.6K 1/16W +-1%(0402)EF'                | 'CHIPR0402'    | ''          | ''            | '20190718'
 '22.6K'      | '1%'      | '1/16W'  | '0402LF'  | 'EMPTY'  | 'CS32262FB02'(!)        = 'End of Design' | 'Comp-Approve'     | 'CS32262FB02'           |'R0402'| '(R0402-0201)'                 | '22.6K'   | '1%'    | '1/16W'  | 'IO'       | 'RES CHIP 22.6K 1/16W +-1%(0402)EF'                | 'CHIPR0402'    | ''          | ''            | '20190718'
 '36.5K'      | '1%'      | '1/16W'  | '0402LF'  | 'CHIP'   | 'CS33652FB03'(!)        = 'End of Design' | 'Comp-Approve'     | 'CS33652FB03'           |'R0402'| '(R0402-0201)'                 | '36.5K'   | '1%'    | '1/16W'  | 'DISCRETE' | 'RES CHIP 36.5K 1/16W +-1%(0402)EF'                | 'CHIPR0402'    | ''          | ''            | '20190718'
 '36.5K'      | '1%'      | '1/16W'  | '0402LF'  | 'EMPTY'  | 'CS33652FB03'(!)        = 'End of Design' | 'Comp-Approve'     | 'CS33652FB03'           |'R0402'| '(R0402-0201)'                 | '36.5K'   | '1%'    | '1/16W'  | 'IO'       | 'RES CHIP 36.5K 1/16W +-1%(0402)EF'                | 'CHIPR0402'    | ''          | ''            | '20190718'
 '1'          | '1%'      | '1/2W'   | '1206LF'  | 'CHIP'   | 'CS-1007F201'(!)        = 'End of Design' | 'Comp-Approve'     | 'CS-1007F201'           |'R1206XI'| '(SMR1206AW)'                  | '1'       | '1%'    | '1/2W'   | 'DISCRETE' | 'RES CHIP 1 1/2W +-1%(1206)EF'                     | 'CHIPR1206'    | ''          | ''            | '20190722'
 '1'          | '1%'      | '1/2W'   | '1206LF'  | 'EMPTY'  | 'CS-1007F201'(!)        = 'End of Design' | 'Comp-Approve'     | 'CS-1007F201'           |'R1206XI'| '(SMR1206AW)'                  | '1'       | '1%'    | '1/2W'   | 'IO'       | 'RES CHIP 1 1/2W +-1%(1206)EF'                     | 'CHIPR1206'    | ''          | ''            | '20190722'
 '1'          | '1%'      | '1/4W'   | '1206LF'  | 'CHIP'   | 'CS-1006F203'(!)        = ''              | ''                 | 'CS-1006F203'           |'R1206XF'| '(SMR1206AW)'                  | '1'       | '1%'    | '1/4W'   | 'DISCRETE' | 'RES CHIP 1 1/4W +-1%(1206)EF'                     | 'CHIPR1206'    | ''          | ''            | '20190722'
 '1'          | '1%'      | '1/4W'   | '1206LF'  | 'EMPTY'  | 'CS-1006F203'(!)        = ''              | ''                 | 'CS-1006F203'           |'R1206XF'| '(SMR1206AW)'                  | '1'       | '1%'    | '1/4W'   | 'IO'       | 'RES CHIP 1 1/4W +-1%(1206)EF'                     | 'CHIPR1206'    | ''          | ''            | '20190722'
 '576'        | '1%'      | '1/16W'  | '0402LF'  | 'CHIP'   | 'CS15762FB03'(!)        = 'End of Design' | 'Comp-Approve'     | 'CS15762FB03'           |'R0402'| '(R0402-0201)'                 | '576'     | '1%'    | '1/16W'  | 'DISCRETE' | 'RES CHIP 576 1/16W +-1%(0402)EF'                  | 'CHIPR0402'    | ''          | ''            | '20190729'
 '576'        | '1%'      | '1/16W'  | '0402LF'  | 'EMPTY'  | 'CS15762FB03'(!)        = 'End of Design' | 'Comp-Approve'     | 'CS15762FB03'           |'R0402'| '(R0402-0201)'                 | '576'     | '1%'    | '1/16W'  | 'IO'       | 'RES CHIP 576 1/16W +-1%(0402)EF'                  | 'CHIPR0402'    | ''          | ''            | '20190729'
 '1.37K'      | '1%'      | '1/16W'  | '0402LF'  | 'CHIP'   | 'CS21372FB03'(!)        = 'End of Design' | 'Comp-Approve'     | 'CS21372FB03'           |'R0402'| '(R0402-0201)'                 | '1.37K'   | '1%'    | '1/16W'  | 'DISCRETE' | 'RES CHIP 1.37K 1/16W +-1%(0402)EF'                | 'CHIPR0402'    | ''          | ''            | '20190729'
 '1.37K'      | '1%'      | '1/16W'  | '0402LF'  | 'EMPTY'  | 'CS21372FB03'(!)        = 'End of Design' | 'Comp-Approve'     | 'CS21372FB03'           |'R0402'| '(R0402-0201)'                 | '1.37K'   | '1%'    | '1/16W'  | 'IO'       | 'RES CHIP 1.37K 1/16W +-1%(0402)EF'                | 'CHIPR0402'    | ''          | ''            | '20190729'
 '27'         | '5%'      | '1/16W'  | '0402LF'  | 'CHIP'   | 'CS02702JB02'(!)        = 'End of Design' | 'Comp-Approve'     | 'CS02702JB02'           |'R0402'| '(R0402-0201)'                 | '27'      | '5%'    | '1/16W'  | 'DISCRETE' | 'RES CHIP 27 1/16W +-5%(0402)EF'                   | 'CHIPR0402'    | ''          | ''            | '20190729'
 '27'         | '5%'      | '1/16W'  | '0402LF'  | 'EMPTY'  | 'CS02702JB02'(!)        = 'End of Design' | 'Comp-Approve'     | 'CS02702JB02'           |'R0402'| '(R0402-0201)'                 | '27'      | '5%'    | '1/16W'  | 'IO'       | 'RES CHIP 27 1/16W +-5%(0402)EF'                   | 'CHIPR0402'    | ''          | ''            | '20190729'
 '43.2'       | '1%'      | '1/16W'  | '0402LF'  | 'CHIP'   | 'CS04322FB01'(!)        = 'End of Design' | 'Comp-Approve'     | 'CS04322FB01'           |'R0402'| '(R0402-0201)'                 | '43.2'    | '1%'    | '1/16W'  | 'DISCRETE' | 'RES CHIP 43.2 1/16W +-1%(0402)EF'                 | 'CHIPR0402'    | ''          | ''            | '20190729'
 '43.2'       | '1%'      | '1/16W'  | '0402LF'  | 'EMPTY'  | 'CS04322FB01'(!)        = 'End of Design' | 'Comp-Approve'     | 'CS04322FB01'           |'R0402'| '(R0402-0201)'                 | '43.2'    | '1%'    | '1/16W'  | 'IO'       | 'RES CHIP 43.2 1/16W +-1%(0402)EF'                 | 'CHIPR0402'    | ''          | ''            | '20190729'
 '100'        | '5%'      | '1/16W'  | '0402LF'  | 'CHIP'   | 'CS11002JB06'(!)        = 'End of Design' | 'Comp-Approve'     | 'CS11002JB06'           |'R0402'| '(R0402-0201)'                 | '100'     | '5%'    | '1/16W'  | 'DISCRETE' | 'RES CHIP 100 1/16W +-5%(0402)EF'                  | 'CHIPR0402'    | ''          | ''            | '20190729'
 '100'        | '5%'      | '1/16W'  | '0402LF'  | 'EMPTY'  | 'CS11002JB06'(!)        = 'End of Design' | 'Comp-Approve'     | 'CS11002JB06'           |'R0402'| '(R0402-0201)'                 | '100'     | '5%'    | '1/16W'  | 'IO'       | 'RES CHIP 100 1/16W +-5%(0402)EF'                  | 'CHIPR0402'    | ''          | ''            | '20190729'
 '4.7K'       | '5%'      | '1/16W'  | '0402LF'  | 'CHIP'   | 'CS24702JB10'(!)        = 'End of Design' | 'Comp-Approve'     | 'CS24702JB10'           |'R0402'| '(R0402-0201)'                 | '4.7K'    | '5%'    | '1/16W'  | 'DISCRETE' | 'RES CHIP 4.7K 1/16W +-5%(0402)EF'                 | 'CHIPR0402'    | ''          | ''            | '20190729'
 '4.7K'       | '5%'      | '1/16W'  | '0402LF'  | 'EMPTY'  | 'CS24702JB10'(!)        = 'End of Design' | 'Comp-Approve'     | 'CS24702JB10'           |'R0402'| '(R0402-0201)'                 | '4.7K'    | '5%'    | '1/16W'  | 'IO'       | 'RES CHIP 4.7K 1/16W +-5%(0402)EF'                 | 'CHIPR0402'    | ''          | ''            | '20190729'
 '5.11K'      | '1%'      | '1/16W'  | '0402LF'  | 'CHIP'   | 'CS25112FB04'(!)        = 'End of Design' | 'Comp-Approve'     | 'CS25112FB04'           |'R0402'| '(R0402-0201)'                 | '5.11K'   | '1%'    | '1/16W'  | 'DISCRETE' | 'RES CHIP 5.11K 1/16W +-1%(0402)EF'                | 'CHIPR0402'    | ''          | ''            | '20190726'
 '5.11K'      | '1%'      | '1/16W'  | '0402LF'  | 'EMPTY'  | 'CS25112FB04'(!)        = 'End of Design' | 'Comp-Approve'     | 'CS25112FB04'           |'R0402'| '(R0402-0201)'                 | '5.11K'   | '1%'    | '1/16W'  | 'IO'       | 'RES CHIP 5.11K 1/16W +-1%(0402)EF'                | 'CHIPR0402'    | ''          | ''            | '20190726'
 '82.5K'      | '1%'      | '1/16W'  | '0402LF'  | 'CHIP'   | 'CS38252FB01'(!)        = ''              | ''                 | 'CS38252FB01'           |'R0402'| '(R0402-0201)'                 | '82.5K'   | '1%'    | '1/16W'  | 'DISCRETE' | 'RES CHIP 82.5K 1/16W +-1%(0402)EF'                | 'CHIPR0402'    | ''          | ''            | '20190730'
 '82.5K'      | '1%'      | '1/16W'  | '0402LF'  | 'EMPTY'  | 'CS38252FB01'(!)        = ''              | ''                 | 'CS38252FB01'           |'R0402'| '(R0402-0201)'                 | '82.5K'   | '1%'    | '1/16W'  | 'IO'       | 'RES CHIP 82.5K 1/16W +-1%(0402)EF'                | 'CHIPR0402'    | ''          | ''            | '20190730'
 '17.8K'      | '1%'      | '1/16W'  | '0402LF'  | 'CHIP'   | 'CS31782FB04'(!)        = 'End of Design' | 'Comp-Approve'     | 'CS31782FB04'           |'R0402'| '(R0402-0201)'                 | '17.8K'   | '1%'    | '1/16W'  | 'DISCRETE' | 'RES CHIP 17.8K 1/16W +- 1% (0402)EF'              | 'CHIPR0402'    | ''          | ''            | '20190730'
 '17.8K'      | '1%'      | '1/16W'  | '0402LF'  | 'EMPTY'  | 'CS31782FB04'(!)        = 'End of Design' | 'Comp-Approve'     | 'CS31782FB04'           |'R0402'| '(R0402-0201)'                 | '17.8K'   | '1%'    | '1/16W'  | 'IO'       | 'RES CHIP 17.8K 1/16W +- 1% (0402)EF'              | 'CHIPR0402'    | ''          | ''            | '20190730'
 '953'        | '1%'      | '1/10W'  | '0603LF'  | 'CHIP'   | 'CS19533F901'(!)        = 'End of Design' | 'Comp-Approve'     | 'CS19533F901'           |'R0603_H24'| '(SMR0603AW)'                  | '953'     | '1%'    | '1/10W'  | 'DISCRETE' | 'RES CHIP 953 1/10W +-1%(0603)EF'                  | 'CHIPR0603'    | ''          | ''            | '20190730'
 '953'        | '1%'      | '1/10W'  | '0603LF'  | 'EMPTY'  | 'CS19533F901'(!)        = 'End of Design' | 'Comp-Approve'     | 'CS19533F901'           |'R0603_H24'| '(SMR0603AW)'                  | '953'     | '1%'    | '1/10W'  | 'IO'       | 'RES CHIP 953 1/10W +-1%(0603)EF'                  | 'CHIPR0603'    | ''          | ''            | '20190730'
 '1.6K'       | '1%'      | '1/10W'  | '0603LF'  | 'CHIP'   | 'CS21603F900'(!)        = 'End of Design' | 'Comp-Approve'     | 'CS21603F900'           |'R0603_H24'| '(SMR0603AW)'                  | '1.6K'    | '1%'    | '1/10W'  | 'DISCRETE' | 'RES CHIP 1.6K 1/10W +-1% (0603)EF'                | 'CHIPR0603'    | ''          | ''            | '20190731'
 '1.6K'       | '1%'      | '1/10W'  | '0603LF'  | 'EMPTY'  | 'CS21603F900'(!)        = 'End of Design' | 'Comp-Approve'     | 'CS21603F900'           |'R0603_H24'| '(SMR0603AW)'                  | '1.6K'    | '1%'    | '1/10W'  | 'IO'       | 'RES CHIP 1.6K 1/10W +-1% (0603)EF'                | 'CHIPR0603'    | ''          | ''            | '20190731'
 '681K'       | '1%'      | '1/16W'  | '0402LF'  | 'CHIP'   | 'CS46812FB06'(!)        = ''              | ''                 | 'CS46812FB06'           |'R0402'| '(R0402-0201)'                 | '681K'    | '1%'    | '1/16W'  | 'DISCRETE' | 'RES CHIP 681K 1/16W +-1%(0402)EF'                 | 'CHIPR0402'    | ''          | ''            | '20190731'
 '681K'       | '1%'      | '1/16W'  | '0402LF'  | 'EMPTY'  | 'CS46812FB06'(!)        = ''              | ''                 | 'CS46812FB06'           |'R0402'| '(R0402-0201)'                 | '681K'    | '1%'    | '1/16W'  | 'IO'       | 'RES CHIP 681K 1/16W +-1%(0402)EF'                 | 'CHIPR0402'    | ''          | ''            | '20190731'
 '0.004'      | '1%'      | '1W'     | '1206LF'  | 'CHIP'   | 'CS+0048F201'(!)        = 'End of Design' | 'Comp-Release Qty' | 'CS+0048F201'           |'R1206XD_H36'| '(SMR1206AW)'                  | '0.004'   | '1%'    | '1W'     | 'DISCRETE' | 'RES CHIP 0.004 1W +-1%(1206)EF'                   | 'CHIPR1206'    | ''          | ''            | '20190731'
 '0.004'      | '1%'      | '1W'     | '1206LF'  | 'EMPTY'  | 'CS+0048F201'(!)        = 'End of Design' | 'Comp-Release Qty' | 'CS+0048F201'           |'R1206XD_H36'| '(SMR1206AW)'                  | '0.004'   | '1%'    | '1W'     | 'IO'       | 'RES CHIP 0.004 1W +-1%(1206)EF'                   | 'CHIPR1206'    | ''          | ''            | '20190731'
 '1.5K'       | '0.1%'    | '1/16W'  | '0402LF'  | 'CHIP'   | 'CS21502BB00'(!)        = ''              | ''                 | 'CS21502BB00'           |'R0402'| '(R0402-0201)'                 | '1.5K'    | '0.1%'  | '1/16W'  | 'DISCRETE' | 'RES CHIP 1.5K 1/16W +-0.1% (0402)'                | 'CHIPR0402'    | ''          | ''            | '20190801'
 '1.5K'       | '0.1%'    | '1/16W'  | '0402LF'  | 'EMPTY'  | 'CS21502BB00'(!)        = ''              | ''                 | 'CS21502BB00'           |'R0402'| '(R0402-0201)'                 | '1.5K'    | '0.1%'  | '1/16W'  | 'IO'       | 'RES CHIP 1.5K 1/16W +-0.1% (0402)'                | 'CHIPR0402'    | ''          | ''            | '20190801'
 '56K'        | '0.1%'    | '1/16W'  | '0402LF'  | 'CHIP'   | 'CS35602BB00'(!)        = ''              | ''                 | 'CS35602BB00'           |'R0402'| '(R0402-0201)'                 | '56K'     | '0.1%'  | '1/16W'  | 'DISCRETE' | 'RES CHIP 56K 1/16W +-0.1%(0402)'                  | 'CHIPR0402'    | ''          | ''            | '20190821'
 '56K'        | '0.1%'    | '1/16W'  | '0402LF'  | 'EMPTY'  | 'CS35602BB00'(!)        = ''              | ''                 | 'CS35602BB00'           |'R0402'| '(R0402-0201)'                 | '56K'     | '0.1%'  | '1/16W'  | 'IO'       | 'RES CHIP 56K 1/16W +-0.1%(0402)'                  | 'CHIPR0402'    | ''          | ''            | '20190821'
 '7.87K'      | '1%'      | '1/16W'  | '0402LF'  | 'CHIP'   | 'CS27872FB02'(!)        = 'End of Design' | 'Comp-Approve'     | 'CS27872FB02'           |'R0402'| '(R0402-0201)'                 | '7.87K'   | '1%'    | '1/16W'  | 'DISCRETE' | 'RES CHIP 7.87K 1/16W +-1%(0402)EF'                | 'CHIPR0402'    | ''          | ''            | '20190820'
 '7.87K'      | '1%'      | '1/16W'  | '0402LF'  | 'EMPTY'  | 'CS27872FB02'(!)        = 'End of Design' | 'Comp-Approve'     | 'CS27872FB02'           |'R0402'| '(R0402-0201)'                 | '7.87K'   | '1%'    | '1/16W'  | 'IO'       | 'RES CHIP 7.87K 1/16W +-1%(0402)EF'                | 'CHIPR0402'    | ''          | ''            | '20190820'
 '13.3K'      | '1%'      | '1/16W'  | '0402LF'  | 'CHIP'   | 'CS31332FB02'(!)        = 'End of Design' | 'Comp-Approve'     | 'CS31332FB02'           |'R0402'| '(R0402-0201)'                 | '13.3K'   | '1%'    | '1/16W'  | 'DISCRETE' | 'RES CHIP 13.3K 1/16W +-1%(0402)EF'                | 'CHIPR0402'    | ''          | ''            | '20190820'
 '13.3K'      | '1%'      | '1/16W'  | '0402LF'  | 'EMPTY'  | 'CS31332FB02'(!)        = 'End of Design' | 'Comp-Approve'     | 'CS31332FB02'           |'R0402'| '(R0402-0201)'                 | '13.3K'   | '1%'    | '1/16W'  | 'IO'       | 'RES CHIP 13.3K 1/16W +-1%(0402)EF'                | 'CHIPR0402'    | ''          | ''            | '20190820'
 '1.47K'      | '1%'      | '1/16W'  | '0402LF'  | 'CHIP'   | 'CS21472FB02'(!)        = 'End of Design' | 'Comp-Approve'     | 'CS21472FB02'           |'R0402'| '(R0402-0201)'                 | '1.47K'   | '1%'    | '1/16W'  | 'DISCRETE' | 'RES CHIP 1.47K 1/16W +-1%(0402)EF'                | 'CHIPR0402'    | ''          | ''            | '20190821'
 '1.47K'      | '1%'      | '1/16W'  | '0402LF'  | 'EMPTY'  | 'CS21472FB02'(!)        = 'End of Design' | 'Comp-Approve'     | 'CS21472FB02'           |'R0402'| '(R0402-0201)'                 | '1.47K'   | '1%'    | '1/16W'  | 'IO'       | 'RES CHIP 1.47K 1/16W +-1%(0402)EF'                | 'CHIPR0402'    | ''          | ''            | '20190821'
 '76.8K'      | '1%'      | '1/20W'  | '0201LF'  | 'CHIP'   | 'CS37681FE01'(!)        = ''              | ''                 | 'CS37681FE01'           |'R0201'| '(SMR0201AW)'                  | '76.8K'   | '1%'    | '1/20W'  | 'DISCRETE' | 'RES CHIP 76.8K 1/20W +-1%(0201)YGOSELASN'         | 'CHIPR0201'    | ''          | ''            | '20190821'
 '76.8K'      | '1%'      | '1/20W'  | '0201LF'  | 'EMPTY'  | 'CS37681FE01'(!)        = ''              | ''                 | 'CS37681FE01'           |'R0201'| '(SMR0201AW)'                  | '76.8K'   | '1%'    | '1/20W'  | 'IO'       | 'RES CHIP 76.8K 1/20W +-1%(0201)YGOSELASN'         | 'CHIPR0201'    | ''          | ''            | '20190821'
 '17.4K'      | '1%'      | '1/16W'  | '0402LF'  | 'CHIP'   | 'CS31742FB04'(!)        = 'End of Design' | 'Comp-Approve'     | 'CS31742FB04'           |'R0402'| '(R0402-0201)'                 | '17.4K'   | '1%'    | '1/16W'  | 'DISCRETE' | 'RES CHIP 17.4K 1/16W +-1%(0402)EF'                | 'CHIPR0402'    | ''          | ''            | '20190826'
 '17.4K'      | '1%'      | '1/16W'  | '0402LF'  | 'EMPTY'  | 'CS31742FB04'(!)        = 'End of Design' | 'Comp-Approve'     | 'CS31742FB04'           |'R0402'| '(R0402-0201)'                 | '17.4K'   | '1%'    | '1/16W'  | 'IO'       | 'RES CHIP 17.4K 1/16W +-1%(0402)EF'                | 'CHIPR0402'    | ''          | ''            | '20190826'
 '0.15'       | '1%'      | '1/2W'   | '1206LF'  | 'CHIP'   | 'CS+1507F200'(!)        = ''              | ''                 | 'CS+1507F200'           |'R1206XF'| '(SMR1206AW)'                  | '0.15'    | '1%'    | '1/2W'   | 'DISCRETE' | 'RES CHIP 0.15 1/2W +-1%(1206)'                    | 'CHIPR1206'    | ''          | ''            | '20190829'
 '0.15'       | '1%'      | '1/2W'   | '1206LF'  | 'EMPTY'  | 'CS+1507F200'(!)        = ''              | ''                 | 'CS+1507F200'           |'R1206XF'| '(SMR1206AW)'                  | '0.15'    | '1%'    | '1/2W'   | 'IO'       | 'RES CHIP 0.15 1/2W +-1%(1206)'                    | 'CHIPR1206'    | ''          | ''            | '20190829'
 '680'        | '1%'      | '1/16W'  | '0402LF'  | 'CHIP'   | 'CS16802FB03'(!)        = ''              | ''                 | 'CS16802FB03'           |'R0402'| '(R0402-0201)'                 | '680'     | '1%'    | '1/16W'  | 'DISCRETE' | 'RES CHIP 680 1/16W +-1%(0402)EF'                  | 'CHIPR0402'    | ''          | ''            | '20190829'
 '680'        | '1%'      | '1/16W'  | '0402LF'  | 'EMPTY'  | 'CS16802FB03'(!)        = ''              | ''                 | 'CS16802FB03'           |'R0402'| '(R0402-0201)'                 | '680'     | '1%'    | '1/16W'  | 'IO'       | 'RES CHIP 680 1/16W +-1%(0402)EF'                  | 'CHIPR0402'    | ''          | ''            | '20190829'
 '3.57K'      | '1%'      | '1/16W'  | '0402LF'  | 'CHIP'   | 'CS23572FB05'(!)        = 'End of Design' | 'Comp-Approve'     | 'CS23572FB05'           |'R0402'| '(R0402-0201)'                 | '3.57K'   | '1%'    | '1/16W'  | 'DISCRETE' | 'RES CHIP 3.57K 1/16W +-1%(0402)EF'                | 'CHIPR0402'    | ''          | ''            | '20190829'
 '3.57K'      | '1%'      | '1/16W'  | '0402LF'  | 'EMPTY'  | 'CS23572FB05'(!)        = 'End of Design' | 'Comp-Approve'     | 'CS23572FB05'           |'R0402'| '(R0402-0201)'                 | '3.57K'   | '1%'    | '1/16W'  | 'IO'       | 'RES CHIP 3.57K 1/16W +-1%(0402)EF'                | 'CHIPR0402'    | ''          | ''            | '20190829'
 '76.8K'      | '1%'      | '1/20W'  | '0201LF'  | 'CHIP'   | 'CS37681FE06'(!)        = ''              | ''                 | 'CS37681FE06'           |'R0201'| '(SMR0201AW)'                  | '76.8K'   | '1%'    | '1/20W'  | 'DISCRETE' | 'RES CHIP 76.8K 1/20W +-1%(0201)'                  | 'CHIPR0201'    | ''          | ''            | '20190829'
 '76.8K'      | '1%'      | '1/20W'  | '0201LF'  | 'EMPTY'  | 'CS37681FE06'(!)        = ''              | ''                 | 'CS37681FE06'           |'R0201'| '(SMR0201AW)'                  | '76.8K'   | '1%'    | '1/20W'  | 'IO'       | 'RES CHIP 76.8K 1/20W +-1%(0201)'                  | 'CHIPR0201'    | ''          | ''            | '20190829'
 '0.003'      | '1%'      | '1W'     | '1206LF'  | 'CHIP'   | 'CS+0038F203'(!)        = ''              | ''                 | 'CS+0038F203'           |'R1206XK'| '(SMR1206AW)'                  | '0.003'   | '1%'    | '1W'     | 'DISCRETE' | 'RES CHIP 0.003 1W +-1%(1206)'                     | 'CHIPR1206'    | ''          | ''            | '20190828'
 '0.003'      | '1%'      | '1W'     | '1206LF'  | 'EMPTY'  | 'CS+0038F203'(!)        = ''              | ''                 | 'CS+0038F203'           |'R1206XK'| '(SMR1206AW)'                  | '0.003'   | '1%'    | '1W'     | 'IO'       | 'RES CHIP 0.003 1W +-1%(1206)'                     | 'CHIPR1206'    | ''          | ''            | '20190828'
 '1.1M'       | '1%'      | '1/8W'   | '0805LF'  | 'CHIP'   | 'CS51104FA00'(!)        = ''              | ''                 | 'CS51104FA00'           |'R0805'| '(SMR0805AW)'                  | '1.1M'    | '1%'    | '1/8W'   | 'DISCRETE' | 'RES CHIP 1.1M 1/8W +-1%(0805)'                    | 'CHIPR0805'    | ''          | ''            | '20190826'
 '1.1M'       | '1%'      | '1/8W'   | '0805LF'  | 'EMPTY'  | 'CS51104FA00'(!)        = ''              | ''                 | 'CS51104FA00'           |'R0805'| '(SMR0805AW)'                  | '1.1M'    | '1%'    | '1/8W'   | 'IO'       | 'RES CHIP 1.1M 1/8W +-1%(0805)'                    | 'CHIPR0805'    | ''          | ''            | '20190826'
 '28.7K'      | '1%'      | '1/10W'  | '0603LF'  | 'CHIP'   | 'CS32873F918'(!)        = ''              | ''                 | 'CS32873F918'           |'R0603'| '(SMR0603AW)'                  | '28.7K'   | '1%'    | '1/10W'  | 'DISCRETE' | 'RESISTOR CHIP 28.7K 1/10W+-1%(0603)'              | 'CHIPR0603'    | ''          | ''            | '20190830'
 '28.7K'      | '1%'      | '1/10W'  | '0603LF'  | 'EMPTY'  | 'CS32873F918'(!)        = ''              | ''                 | 'CS32873F918'           |'R0603'| '(SMR0603AW)'                  | '28.7K'   | '1%'    | '1/10W'  | 'IO'       | 'RESISTOR CHIP 28.7K 1/10W+-1%(0603)'              | 'CHIPR0603'    | ''          | ''            | '20190830'
 '20'         | '5%'      | '1/16W'  | '0402LF'  | 'CHIP'   | 'CS02002JB02'(!)        = ''              | ''                 | 'CS02002JB02'           |'R0402'| '(R0402-0201)'                 | '20'      | '5%'    | '1/16W'  | 'DISCRETE' | 'RES CHIP 20 1/16W +-5%(0402)EF'                   | 'CHIPR0402'    | ''          | ''            | '20190904'
 '20'         | '5%'      | '1/16W'  | '0402LF'  | 'EMPTY'  | 'CS02002JB02'(!)        = ''              | ''                 | 'CS02002JB02'           |'R0402'| '(R0402-0201)'                 | '20'      | '5%'    | '1/16W'  | 'IO'       | 'RES CHIP 20 1/16W +-5%(0402)EF'                   | 'CHIPR0402'    | ''          | ''            | '20190904'
 '30.1'       | '1%'      | '1/10W'  | '0603LF'  | 'CHIP'   | 'CS03013F902'(!)        = 'End of Design' | 'Comp-Release Qty' | 'CS03013F902'           |'R0603_H24'| '(SMR0603AW)'                  | '30.1'    | '1%'    | '1/10W'  | 'DISCRETE' | 'RES CHIP 30.1 1/10W +-1%(0603)EF'                 | 'CHIPR0603'    | ''          | ''            | '20190904'
 '30.1'       | '1%'      | '1/10W'  | '0603LF'  | 'EMPTY'  | 'CS03013F902'(!)        = 'End of Design' | 'Comp-Release Qty' | 'CS03013F902'           |'R0603_H24'| '(SMR0603AW)'                  | '30.1'    | '1%'    | '1/10W'  | 'IO'       | 'RES CHIP 30.1 1/10W +-1%(0603)EF'                 | 'CHIPR0603'    | ''          | ''            | '20190904'
 '33'         | '5%'      | '1/16W'  | '0402LF'  | 'CHIP'   | 'CS03302JB10'(!)        = 'End of Design' | 'Comp-Approve'     | 'CS03302JB10'           |'R0402'| '(R0402-0201)'                 | '33'      | '5%'    | '1/16W'  | 'DISCRETE' | 'RES CHIP 33 1/16W +-5%(0402)EF'                   | 'CHIPR0402'    | ''          | ''            | '20190904'
 '33'         | '5%'      | '1/16W'  | '0402LF'  | 'EMPTY'  | 'CS03302JB10'(!)        = 'End of Design' | 'Comp-Approve'     | 'CS03302JB10'           |'R0402'| '(R0402-0201)'                 | '33'      | '5%'    | '1/16W'  | 'IO'       | 'RES CHIP 33 1/16W +-5%(0402)EF'                   | 'CHIPR0402'    | ''          | ''            | '20190904'
 '1'          | '1%'      | '1/10W'  | '0603LF'  | 'CHIP'   | 'CS-1003F900'(!)        = 'End of Design' | 'Comp-Approve'     | 'CS-1003F900'           |'R0603_H24'| '(SMR0603AW)'                  | '1'       | '1%'    | '1/10W'  | 'DISCRETE' | 'RES CHIP 1 1/10W +-1%(0603)EF'                    | 'CHIPR0603'    | ''          | ''            | '20190904'
 '1'          | '1%'      | '1/10W'  | '0603LF'  | 'EMPTY'  | 'CS-1003F900'(!)        = 'End of Design' | 'Comp-Approve'     | 'CS-1003F900'           |'R0603_H24'| '(SMR0603AW)'                  | '1'       | '1%'    | '1/10W'  | 'IO'       | 'RES CHIP 1 1/10W +-1%(0603)EF'                    | 'CHIPR0603'    | ''          | ''            | '20190904'
 '165'        | '1%'      | '1/16W'  | '0402LF'  | 'CHIP'   | 'CS11652FB03'(!)        = 'End of Design' | 'Comp-Approve'     | 'CS11652FB03'           |'R0402'| '(R0402-0201)'                 | '165'     | '1%'    | '1/16W'  | 'DISCRETE' | 'RES CHIP 165 1/16W +-1%(0402)EF'                  | 'CHIPR0402'    | ''          | ''            | '20190904'
 '165'        | '1%'      | '1/16W'  | '0402LF'  | 'EMPTY'  | 'CS11652FB03'(!)        = 'End of Design' | 'Comp-Approve'     | 'CS11652FB03'           |'R0402'| '(R0402-0201)'                 | '165'     | '1%'    | '1/16W'  | 'IO'       | 'RES CHIP 165 1/16W +-1%(0402)EF'                  | 'CHIPR0402'    | ''          | ''            | '20190904'
 '249'        | '1%'      | '1/16W'  | '0402LF'  | 'CHIP'   | 'CS12492FB02'(!)        = 'End of Design' | 'Comp-Approve'     | 'CS12492FB02'           |'R0402'| '(R0402-0201)'                 | '249'     | '1%'    | '1/16W'  | 'DISCRETE' | 'RES CHIP 249 1/16W +-1%(0402)EF'                  | 'CHIPR0402'    | ''          | ''            | '20190904'
 '249'        | '1%'      | '1/16W'  | '0402LF'  | 'EMPTY'  | 'CS12492FB02'(!)        = 'End of Design' | 'Comp-Approve'     | 'CS12492FB02'           |'R0402'| '(R0402-0201)'                 | '249'     | '1%'    | '1/16W'  | 'IO'       | 'RES CHIP 249 1/16W +-1%(0402)EF'                  | 'CHIPR0402'    | ''          | ''            | '20190904'
 '249'        | '0.1%'    | '1/10W'  | '0603LF'  | 'CHIP'   | 'CS12493B901'(!)        = ''              | ''                 | 'CS12493B901'           |'R0603_H24'| '(SMR0603AW)'                  | '249'     | '0.1%'  | '1/10W'  | 'DISCRETE' | 'RES CHIP 249 1/10W +-0.1%(0603)EF'                | 'CHIPR0603'    | ''          | ''            | '20190905'
 '249'        | '0.1%'    | '1/10W'  | '0603LF'  | 'EMPTY'  | 'CS12493B901'(!)        = ''              | ''                 | 'CS12493B901'           |'R0603_H24'| '(SMR0603AW)'                  | '249'     | '0.1%'  | '1/10W'  | 'IO'       | 'RES CHIP 249 1/10W +-0.1%(0603)EF'                | 'CHIPR0603'    | ''          | ''            | '20190905'
 '301'        | '1%'      | '1/16W'  | '0402LF'  | 'CHIP'   | 'CS13012FB02'(!)        = 'End of Design' | 'Comp-Approve'     | 'CS13012FB02'           |'R0402'| '(R0402-0201)'                 | '301'     | '1%'    | '1/16W'  | 'DISCRETE' | 'RES CHIP 301 1/16W +-1%(0402)EF'                  | 'CHIPR0402'    | ''          | ''            | '20190904'
 '301'        | '1%'      | '1/16W'  | '0402LF'  | 'EMPTY'  | 'CS13012FB02'(!)        = 'End of Design' | 'Comp-Approve'     | 'CS13012FB02'           |'R0402'| '(R0402-0201)'                 | '301'     | '1%'    | '1/16W'  | 'IO'       | 'RES CHIP 301 1/16W +-1%(0402)EF'                  | 'CHIPR0402'    | ''          | ''            | '20190904'
 '383'        | '1%'      | '1/16W'  | '0402LF'  | 'CHIP'   | 'CS13832FB03'(!)        = 'End of Design' | 'Comp-Approve'     | 'CS13832FB03'           |'R0402'| '(R0402-0201)'                 | '383'     | '1%'    | '1/16W'  | 'DISCRETE' | 'RES CHIP 383 1/16W +-1%(0402)EF'                  | 'CHIPR0402'    | ''          | ''            | '20190904'
 '383'        | '1%'      | '1/16W'  | '0402LF'  | 'EMPTY'  | 'CS13832FB03'(!)        = 'End of Design' | 'Comp-Approve'     | 'CS13832FB03'           |'R0402'| '(R0402-0201)'                 | '383'     | '1%'    | '1/16W'  | 'IO'       | 'RES CHIP 383 1/16W +-1%(0402)EF'                  | 'CHIPR0402'    | ''          | ''            | '20190904'
 '510'        | '5%'      | '1/16W'  | '0402LF'  | 'CHIP'   | 'CS15102JB04'(!)        = ''              | ''                 | 'CS15102JB04'           |'R0402'| '(R0402-0201)'                 | '510'     | '5%'    | '1/16W'  | 'DISCRETE' | 'RES CHIP 510 1/16W +-5%(0402)EF'                  | 'CHIPR0402'    | ''          | ''            | '20190904'
 '510'        | '5%'      | '1/16W'  | '0402LF'  | 'EMPTY'  | 'CS15102JB04'(!)        = ''              | ''                 | 'CS15102JB04'           |'R0402'| '(R0402-0201)'                 | '510'     | '5%'    | '1/16W'  | 'IO'       | 'RES CHIP 510 1/16W +-5%(0402)EF'                  | 'CHIPR0402'    | ''          | ''            | '20190904'
 '523'        | '1%'      | '1/16W'  | '0402LF'  | 'CHIP'   | 'CS15232FB03'(!)        = ''              | ''                 | 'CS15232FB03'           |'R0402'| '(R0402-0201)'                 | '523'     | '1%'    | '1/16W'  | 'DISCRETE' | 'RES CHIP 523 1/16W +-1%(0402)EF'                  | 'CHIPR0402'    | ''          | ''            | '20190904'
 '523'        | '1%'      | '1/16W'  | '0402LF'  | 'EMPTY'  | 'CS15232FB03'(!)        = ''              | ''                 | 'CS15232FB03'           |'R0402'| '(R0402-0201)'                 | '523'     | '1%'    | '1/16W'  | 'IO'       | 'RES CHIP 523 1/16W +-1%(0402)EF'                  | 'CHIPR0402'    | ''          | ''            | '20190904'
 '560'        | '1%'      | '1/16W'  | '0402LF'  | 'CHIP'   | 'CS15602FB03'(!)        = ''              | ''                 | 'CS15602FB03'           |'R0402'| '(R0402-0201)'                 | '560'     | '1%'    | '1/16W'  | 'DISCRETE' | 'RES CHIP 560 1/16W +-1%(0402)EF'                  | 'CHIPR0402'    | ''          | ''            | '20190904'
 '560'        | '1%'      | '1/16W'  | '0402LF'  | 'EMPTY'  | 'CS15602FB03'(!)        = ''              | ''                 | 'CS15602FB03'           |'R0402'| '(R0402-0201)'                 | '560'     | '1%'    | '1/16W'  | 'IO'       | 'RES CHIP 560 1/16W +-1%(0402)EF'                  | 'CHIPR0402'    | ''          | ''            | '20190904'
 '562'        | '1%'      | '1/16W'  | '0402LF'  | 'CHIP'   | 'CS15622FB01'(!)        = 'End of Design' | 'Comp-Approve'     | 'CS15622FB01'           |'R0402'| '(R0402-0201)'                 | '562'     | '1%'    | '1/16W'  | 'DISCRETE' | 'RES CHIP 562 1/16W +-1% (0402)EF'                 | 'CHIPR0402'    | ''          | ''            | '20190904'
 '562'        | '1%'      | '1/16W'  | '0402LF'  | 'EMPTY'  | 'CS15622FB01'(!)        = 'End of Design' | 'Comp-Approve'     | 'CS15622FB01'           |'R0402'| '(R0402-0201)'                 | '562'     | '1%'    | '1/16W'  | 'IO'       | 'RES CHIP 562 1/16W +-1% (0402)EF'                 | 'CHIPR0402'    | ''          | ''            | '20190904'
 '750'        | '1%'      | '1/20W'  | '0201LF'  | 'CHIP'   | 'CS17501FE11'(!)        = ''              | ''                 | 'CS17501FE11'           |'R0201'| '(SMR0201AW)'                  | '750'     | '1%'    | '1/20W'  | 'DISCRETE' | 'RES CHIP 750 1/20W +-1%(0201)EF'                  | 'CHIPR0201'    | ''          | ''            | '20190904'
 '750'        | '1%'      | '1/20W'  | '0201LF'  | 'EMPTY'  | 'CS17501FE11'(!)        = ''              | ''                 | 'CS17501FE11'           |'R0201'| '(SMR0201AW)'                  | '750'     | '1%'    | '1/20W'  | 'IO'       | 'RES CHIP 750 1/20W +-1%(0201)EF'                  | 'CHIPR0201'    | ''          | ''            | '20190904'
 '887'        | '1%'      | '1/16W'  | '0402LF'  | 'CHIP'   | 'CS18872FB02'(!)        = 'End of Design' | 'Comp-Approve'     | 'CS18872FB02'           |'R0402'| '(R0402-0201)'                 | '887'     | '1%'    | '1/16W'  | 'DISCRETE' | 'RES CHIP 887 1/16W +-1%(0402)EF'                  | 'CHIPR0402'    | ''          | ''            | '20190905'
 '887'        | '1%'      | '1/16W'  | '0402LF'  | 'EMPTY'  | 'CS18872FB02'(!)        = 'End of Design' | 'Comp-Approve'     | 'CS18872FB02'           |'R0402'| '(R0402-0201)'                 | '887'     | '1%'    | '1/16W'  | 'IO'       | 'RES CHIP 887 1/16W +-1%(0402)EF'                  | 'CHIPR0402'    | ''          | ''            | '20190905'
 '1.18K'      | '1%'      | '1/16W'  | '0402LF'  | 'CHIP'   | 'CS21182FB01'(!)        = 'End of Design' | 'Comp-Approve'     | 'CS21182FB01'           |'R0402'| '(R0402-0201)'                 | '1.18K'   | '1%'    | '1/16W'  | 'DISCRETE' | 'RES CHIP 1.18K 1/16W +-1%(0402)EF'                | 'CHIPR0402'    | ''          | ''            | '20190905'
 '1.18K'      | '1%'      | '1/16W'  | '0402LF'  | 'EMPTY'  | 'CS21182FB01'(!)        = 'End of Design' | 'Comp-Approve'     | 'CS21182FB01'           |'R0402'| '(R0402-0201)'                 | '1.18K'   | '1%'    | '1/16W'  | 'IO'       | 'RES CHIP 1.18K 1/16W +-1%(0402)EF'                | 'CHIPR0402'    | ''          | ''            | '20190905'
 '1.2K'       | '1%'      | '1/16W'  | '0402LF'  | 'CHIP'   | 'CS21202FB00'(!)        = 'End of Design' | 'Comp-Approve'     | 'CS21202FB00'           |'R0402'| '(R0402-0201)'                 | '1.2K'    | '1%'    | '1/16W'  | 'DISCRETE' | 'RES CHIP 1.2K 1/16W+-1%(0402)EF'                  | 'CHIPR0402'    | ''          | ''            | '20190905'
 '1.2K'       | '1%'      | '1/16W'  | '0402LF'  | 'EMPTY'  | 'CS21202FB00'(!)        = 'End of Design' | 'Comp-Approve'     | 'CS21202FB00'           |'R0402'| '(R0402-0201)'                 | '1.2K'    | '1%'    | '1/16W'  | 'IO'       | 'RES CHIP 1.2K 1/16W+-1%(0402)EF'                  | 'CHIPR0402'    | ''          | ''            | '20190905'
 '2.67K'      | '1%'      | '1/16W'  | '0402LF'  | 'CHIP'   | 'CS22672FB03'(!)        = 'End of Design' | 'Comp-Approve'     | 'CS22672FB03'           |'R0402'| '(R0402-0201)'                 | '2.67K'   | '1%'    | '1/16W'  | 'DISCRETE' | 'RES CHIP 2.67K 1/16W +-1%(0402)EF'                | 'CHIPR0402'    | ''          | ''            | '20190905'
 '2.67K'      | '1%'      | '1/16W'  | '0402LF'  | 'EMPTY'  | 'CS22672FB03'(!)        = 'End of Design' | 'Comp-Approve'     | 'CS22672FB03'           |'R0402'| '(R0402-0201)'                 | '2.67K'   | '1%'    | '1/16W'  | 'IO'       | 'RES CHIP 2.67K 1/16W +-1%(0402)EF'                | 'CHIPR0402'    | ''          | ''            | '20190905'
 '4.22K'      | '1%'      | '1/16W'  | '0402LF'  | 'CHIP'   | 'CS24222FB01'(!)        = 'End of Design' | 'Comp-Approve'     | 'CS24222FB01'           |'R0402'| '(R0402-0201)'                 | '4.22K'   | '1%'    | '1/16W'  | 'DISCRETE' | 'RES CHIP 4.22K 1/16W +-1%(0402)EF'                | 'CHIPR0402'    | ''          | ''            | '20190906'
 '4.22K'      | '1%'      | '1/16W'  | '0402LF'  | 'EMPTY'  | 'CS24222FB01'(!)        = 'End of Design' | 'Comp-Approve'     | 'CS24222FB01'           |'R0402'| '(R0402-0201)'                 | '4.22K'   | '1%'    | '1/16W'  | 'IO'       | 'RES CHIP 4.22K 1/16W +-1%(0402)EF'                | 'CHIPR0402'    | ''          | ''            | '20190906'
 '5.36K'      | '1%'      | '1/16W'  | '0402LF'  | 'CHIP'   | 'CS25362FB02'(!)        = 'End of Design' | 'Comp-Approve'     | 'CS25362FB02'           |'R0402'| '(R0402-0201)'                 | '5.36K'   | '1%'    | '1/16W'  | 'DISCRETE' | 'RES CHIP 5.36K 1/16W +-1%(0402)EF'                | 'CHIPR0402'    | ''          | ''            | '20190906'
 '5.36K'      | '1%'      | '1/16W'  | '0402LF'  | 'EMPTY'  | 'CS25362FB02'(!)        = 'End of Design' | 'Comp-Approve'     | 'CS25362FB02'           |'R0402'| '(R0402-0201)'                 | '5.36K'   | '1%'    | '1/16W'  | 'IO'       | 'RES CHIP 5.36K 1/16W +-1%(0402)EF'                | 'CHIPR0402'    | ''          | ''            | '20190906'
 '6.98K'      | '1%'      | '1/16W'  | '0402LF'  | 'CHIP'   | 'CS26982FB08'(!)        = ''              | ''                 | 'CS26982FB08'           |'R0402'| '(R0402-0201)'                 | '6.98K'   | '1%'    | '1/16W'  | 'DISCRETE' | 'RES CHIP 6.98K 1/16W +-1%(0402)EF'                | 'CHIPR0402'    | ''          | ''            | '20190906'
 '6.98K'      | '1%'      | '1/16W'  | '0402LF'  | 'EMPTY'  | 'CS26982FB08'(!)        = ''              | ''                 | 'CS26982FB08'           |'R0402'| '(R0402-0201)'                 | '6.98K'   | '1%'    | '1/16W'  | 'IO'       | 'RES CHIP 6.98K 1/16W +-1%(0402)EF'                | 'CHIPR0402'    | ''          | ''            | '20190906'
 '10.7K'      | '1%'      | '1/16W'  | '0402LF'  | 'CHIP'   | 'CS31072FB05'(!)        = 'End of Design' | 'Comp-Approve'     | 'CS31072FB05'           |'R0402'| '(R0402-0201)'                 | '10.7K'   | '1%'    | '1/16W'  | 'DISCRETE' | 'RES CHIP 10.7K 1/16W +-1%(0402)EF'                | 'CHIPR0402'    | ''          | ''            | '20190906'
 '10.7K'      | '1%'      | '1/16W'  | '0402LF'  | 'EMPTY'  | 'CS31072FB05'(!)        = 'End of Design' | 'Comp-Approve'     | 'CS31072FB05'           |'R0402'| '(R0402-0201)'                 | '10.7K'   | '1%'    | '1/16W'  | 'IO'       | 'RES CHIP 10.7K 1/16W +-1%(0402)EF'                | 'CHIPR0402'    | ''          | ''            | '20190906'
 '26.7K'      | '1%'      | '1/16W'  | '0402LF'  | 'CHIP'   | 'CS32672FB03'(!)        = 'End of Design' | 'Comp-Approve'     | 'CS32672FB03'           |'R0402'| '(R0402-0201)'                 | '26.7K'   | '1%'    | '1/16W'  | 'DISCRETE' | 'RES CHIP 26.7K 1/16W +-1%(0402)EF'                | 'CHIPR0402'    | ''          | ''            | '20190906'
 '26.7K'      | '1%'      | '1/16W'  | '0402LF'  | 'EMPTY'  | 'CS32672FB03'(!)        = 'End of Design' | 'Comp-Approve'     | 'CS32672FB03'           |'R0402'| '(R0402-0201)'                 | '26.7K'   | '1%'    | '1/16W'  | 'IO'       | 'RES CHIP 26.7K 1/16W +-1%(0402)EF'                | 'CHIPR0402'    | ''          | ''            | '20190906'
 '27K'        | '1%'      | '1/16W'  | '0402LF'  | 'CHIP'   | 'CS32702FB03'(!)        = 'End of Design' | 'Comp-Approve'     | 'CS32702FB03'           |'R0402'| '(R0402-0201)'                 | '27K'     | '1%'    | '1/16W'  | 'DISCRETE' | 'RES CHIP 27K 1/16W +-1%(0402)EF'                  | 'CHIPR0402'    | ''          | ''            | '20190906'
 '27K'        | '1%'      | '1/16W'  | '0402LF'  | 'EMPTY'  | 'CS32702FB03'(!)        = 'End of Design' | 'Comp-Approve'     | 'CS32702FB03'           |'R0402'| '(R0402-0201)'                 | '27K'     | '1%'    | '1/16W'  | 'IO'       | 'RES CHIP 27K 1/16W +-1%(0402)EF'                  | 'CHIPR0402'    | ''          | ''            | '20190906'
 '57.6K'      | '1%'      | '1/16W'  | '0402LF'  | 'CHIP'   | 'CS35762FB02'(!)        = ''              | ''                 | 'CS35762FB02'           |'R0402'| '(R0402-0201)'                 | '57.6K'   | '1%'    | '1/16W'  | 'DISCRETE' | 'RES CHIP 57.6K 1/16W +-1%(0402)EF'                | 'CHIPR0402'    | ''          | ''            | '20190906'
 '57.6K'      | '1%'      | '1/16W'  | '0402LF'  | 'EMPTY'  | 'CS35762FB02'(!)        = ''              | ''                 | 'CS35762FB02'           |'R0402'| '(R0402-0201)'                 | '57.6K'   | '1%'    | '1/16W'  | 'IO'       | 'RES CHIP 57.6K 1/16W +-1%(0402)EF'                | 'CHIPR0402'    | ''          | ''            | '20190906'
 '68K'        | '1%'      | '1/16W'  | '0402LF'  | 'CHIP'   | 'CS36802FB04'(!)        = 'End of Design' | 'Comp-Approve'     | 'CS36802FB04'           |'R0402'| '(R0402-0201)'                 | '68K'     | '1%'    | '1/16W'  | 'DISCRETE' | 'RES CHIP 68K 1/16W +-1%(0402)EF'                  | 'CHIPR0402'    | ''          | ''            | '20190906'
 '68K'        | '1%'      | '1/16W'  | '0402LF'  | 'EMPTY'  | 'CS36802FB04'(!)        = 'End of Design' | 'Comp-Approve'     | 'CS36802FB04'           |'R0402'| '(R0402-0201)'                 | '68K'     | '1%'    | '1/16W'  | 'IO'       | 'RES CHIP 68K 1/16W +-1%(0402)EF'                  | 'CHIPR0402'    | ''          | ''            | '20190906'
 '4.02'       | '1%'      | '1/16W'  | '0402LF'  | 'CHIP'   | 'CS-4022FB01'(!)        = 'End of Design' | 'Comp-Approve'     | 'CS-4022FB01'           |'R0402'| '(R0402-0201)'                 | '4.02'    | '1%'    | '1/16W'  | 'DISCRETE' | 'RES CHIP 4.02 1/16W +-1%(0402)EF'                 | 'CHIPR0402'    | ''          | ''            | '20190906'
 '4.02'       | '1%'      | '1/16W'  | '0402LF'  | 'EMPTY'  | 'CS-4022FB01'(!)        = 'End of Design' | 'Comp-Approve'     | 'CS-4022FB01'           |'R0402'| '(R0402-0201)'                 | '4.02'    | '1%'    | '1/16W'  | 'IO'       | 'RES CHIP 4.02 1/16W +-1%(0402)EF'                 | 'CHIPR0402'    | ''          | ''            | '20190906'
 '143K'       | '1%'      | '1/16W'  | '0402LF'  | 'CHIP'   | 'CS41432FB04'(!)        = ''              | ''                 | 'CS41432FB04'           |'R0402'| '(R0402-0201)'                 | '143K'    | '1%'    | '1/16W'  | 'DISCRETE' | 'RES CHIP 143K 1/16W +-1%(0402)EF'                 | 'CHIPR0402'    | ''          | ''            | '20190906'
 '143K'       | '1%'      | '1/16W'  | '0402LF'  | 'EMPTY'  | 'CS41432FB04'(!)        = ''              | ''                 | 'CS41432FB04'           |'R0402'| '(R0402-0201)'                 | '143K'    | '1%'    | '1/16W'  | 'IO'       | 'RES CHIP 143K 1/16W +-1%(0402)EF'                 | 'CHIPR0402'    | ''          | ''            | '20190906'
 '165K'       | '1%'      | '1/16W'  | '0402LF'  | 'CHIP'   | 'CS41652FB03'(!)        = 'End of Design' | 'Comp-Approve'     | 'CS41652FB03'           |'R0402'| '(R0402-0201)'                 | '165K'    | '1%'    | '1/16W'  | 'DISCRETE' | 'RES CHIP 165K 1/16W +-1%(0402)EF'                 | 'CHIPR0402'    | ''          | ''            | '20190906'
 '165K'       | '1%'      | '1/16W'  | '0402LF'  | 'EMPTY'  | 'CS41652FB03'(!)        = 'End of Design' | 'Comp-Approve'     | 'CS41652FB03'           |'R0402'| '(R0402-0201)'                 | '165K'    | '1%'    | '1/16W'  | 'IO'       | 'RES CHIP 165K 1/16W +-1%(0402)EF'                 | 'CHIPR0402'    | ''          | ''            | '20190906'
 '255K'       | '1%'      | '1/16W'  | '0402LF'  | 'CHIP'   | 'CS42552FB02'(!)        = 'End of Design' | 'Comp-Approve'     | 'CS42552FB02'           |'R0402'| '(R0402-0201)'                 | '255K'    | '1%'    | '1/16W'  | 'DISCRETE' | 'RES CHIP 255K 1/16W +-1%(0402)EF'                 | 'CHIPR0402'    | ''          | ''            | '20190906'
 '255K'       | '1%'      | '1/16W'  | '0402LF'  | 'EMPTY'  | 'CS42552FB02'(!)        = 'End of Design' | 'Comp-Approve'     | 'CS42552FB02'           |'R0402'| '(R0402-0201)'                 | '255K'    | '1%'    | '1/16W'  | 'IO'       | 'RES CHIP 255K 1/16W +-1%(0402)EF'                 | 'CHIPR0402'    | ''          | ''            | '20190906'
 '470K'       | '1%'      | '1/16W'  | '0402LF'  | 'CHIP'   | 'CS44702FB02'(!)        = 'End of Design' | 'Comp-Approve'     | 'CS44702FB02'           |'R0402'| '(R0402-0201)'                 | '470K'    | '1%'    | '1/16W'  | 'DISCRETE' | 'RES CHIP 470K 1/16W +-1%(0402)EF'                 | 'CHIPR0402'    | ''          | ''            | '20190906'
 '470K'       | '1%'      | '1/16W'  | '0402LF'  | 'EMPTY'  | 'CS44702FB02'(!)        = 'End of Design' | 'Comp-Approve'     | 'CS44702FB02'           |'R0402'| '(R0402-0201)'                 | '470K'    | '1%'    | '1/16W'  | 'IO'       | 'RES CHIP 470K 1/16W +-1%(0402)EF'                 | 'CHIPR0402'    | ''          | ''            | '20190906'
 '866K'       | '1%'      | '1/16W'  | '0402LF'  | 'CHIP'   | 'CS48662FB02'(!)        = ''              | ''                 | 'CS48662FB02'           |'R0402'| '(R0402-0201)'                 | '866K'    | '1%'    | '1/16W'  | 'DISCRETE' | 'RES CHIP 866K 1/16W +-1%(0402)EF'                 | 'CHIPR0402'    | ''          | ''            | '20190906'
 '866K'       | '1%'      | '1/16W'  | '0402LF'  | 'EMPTY'  | 'CS48662FB02'(!)        = ''              | ''                 | 'CS48662FB02'           |'R0402'| '(R0402-0201)'                 | '866K'    | '1%'    | '1/16W'  | 'IO'       | 'RES CHIP 866K 1/16W +-1%(0402)EF'                 | 'CHIPR0402'    | ''          | ''            | '20190906'
 '5.11'       | '1%'      | '1/16W'  | '0402LF'  | 'CHIP'   | 'CS-5112FB02'(!)        = 'End of Design' | 'Comp-Approve'     | 'CS-5112FB02'           |'R0402'| '(R0402-0201)'                 | '5.11'    | '1%'    | '1/16W'  | 'DISCRETE' | 'RES CHIP 5.11 1/16W +-1%(0402)EF'                 | 'CHIPR0402'    | ''          | ''            | '20190906'
 '5.11'       | '1%'      | '1/16W'  | '0402LF'  | 'EMPTY'  | 'CS-5112FB02'(!)        = 'End of Design' | 'Comp-Approve'     | 'CS-5112FB02'           |'R0402'| '(R0402-0201)'                 | '5.11'    | '1%'    | '1/16W'  | 'IO'       | 'RES CHIP 5.11 1/16W +-1%(0402)EF'                 | 'CHIPR0402'    | ''          | ''            | '20190906'
 '10M'        | '1%'      | '1/16W'  | '0402LF'  | 'CHIP'   | 'CS61002FB02'(!)        = ''              | ''                 | 'CS61002FB02'           |'R0402'| '(R0402-0201)'                 | '10M'     | '1%'    | '1/16W'  | 'DISCRETE' | 'RES CHIP 10M 1/16W +-1%(0402)EF'                  | 'CHIPR0402'    | ''          | ''            | '20190906'
 '10M'        | '1%'      | '1/16W'  | '0402LF'  | 'EMPTY'  | 'CS61002FB02'(!)        = ''              | ''                 | 'CS61002FB02'           |'R0402'| '(R0402-0201)'                 | '10M'     | '1%'    | '1/16W'  | 'IO'       | 'RES CHIP 10M 1/16W +-1%(0402)EF'                  | 'CHIPR0402'    | ''          | ''            | '20190906'
 '2.8M'       | '1%'      | '1/8W'   | '0805LF'  | 'CHIP'   | 'CS52804FA00'(!)        = ''              | ''                 | 'CS52804FA00'           |'R0805'| '(SMR0805AW)'                  | '2.8M'    | '1%'    | '1/8W'   | 'DISCRETE' | 'RES CHIP 2.8M 1/8W +-1%(0805)'                    | 'CHIPR0805'    | ''          | ''            | '20191001'
 '2.8M'       | '1%'      | '1/8W'   | '0805LF'  | 'EMPTY'  | 'CS52804FA00'(!)        = ''              | ''                 | 'CS52804FA00'           |'R0805'| '(SMR0805AW)'                  | '2.8M'    | '1%'    | '1/8W'   | 'IO'       | 'RES CHIP 2.8M 1/8W +-1%(0805)'                    | 'CHIPR0805'    | ''          | ''            | '20191001'
 '12K'        | '1%'      | '1/10W'  | '0603LF'  | 'CHIP'   | 'CS31203F911'(!)        = ''              | ''                 | 'CS31203F911'           |'R0603'| '(SMR0603AW)'                  | '12K'     | '1%'    | '1/10W'  | 'DISCRETE' | 'RESISTOR CHIP 12K 1/10W+-1%(0603)'                | 'CHIPR0603'    | ''          | ''            | '20190925'
 '12K'        | '1%'      | '1/10W'  | '0603LF'  | 'EMPTY'  | 'CS31203F911'(!)        = ''              | ''                 | 'CS31203F911'           |'R0603'| '(SMR0603AW)'                  | '12K'     | '1%'    | '1/10W'  | 'IO'       | 'RESISTOR CHIP 12K 1/10W+-1%(0603)'                | 'CHIPR0603'    | ''          | ''            | '20190925'
 '26.1K'      | '0.1%'    | '1/10W'  | '0603LF'  | 'CHIP'   | 'CS32613B900'(!)        = 'End of Design' | 'Comp-Approve'     | 'CS32613B900'           |'R0603'| '(SMR0603AW)'                  | '26.1K'   | '0.1%'  | '1/10W'  | 'DISCRETE' | 'RES CHIP 26.1K 1/10W +-0.1%(0603)'                | 'CHIPR0603'    | ''          | ''            | '20190927'
 '26.1K'      | '0.1%'    | '1/10W'  | '0603LF'  | 'EMPTY'  | 'CS32613B900'(!)        = 'End of Design' | 'Comp-Approve'     | 'CS32613B900'           |'R0603'| '(SMR0603AW)'                  | '26.1K'   | '0.1%'  | '1/10W'  | 'IO'       | 'RES CHIP 26.1K 1/10W +-0.1%(0603)'                | 'CHIPR0603'    | ''          | ''            | '20190927'
 '10.2K'      | '0.1%'    | '1/16W'  | '0402LF'  | 'CHIP'   | 'CS31022BB01'(!)        = ''              | ''                 | 'CS31022BB01'           |'R0402'| '(R0402-0201)'                 | '10.2K'   | '0.1%'  | '1/16W'  | 'DISCRETE' | 'RES CHIP 10.2K 1/16W +-0.1%(0402)'                | 'CHIPR0402'    | ''          | ''            | '20190927'
 '10.2K'      | '0.1%'    | '1/16W'  | '0402LF'  | 'EMPTY'  | 'CS31022BB01'(!)        = ''              | ''                 | 'CS31022BB01'           |'R0402'| '(R0402-0201)'                 | '10.2K'   | '0.1%'  | '1/16W'  | 'IO'       | 'RES CHIP 10.2K 1/16W +-0.1%(0402)'                | 'CHIPR0402'    | ''          | ''            | '20190927'
 '10K'        | '1%'      | '1/20W'  | '0201LF'  | 'CHIP'   | 'CS31001FE17'(!)        = ''              | ''                 | 'CS31001FE17'           |'R0201'| '(SMR0201AW)'                  | '10K'     | '1%'    | '1/20W'  | 'DISCRETE' | 'RES CHIP 10K 1/20W +-1%(0201)EF'                  | 'CHIPR0201'    | ''          | ''            | '20191004'
 '10K'        | '1%'      | '1/20W'  | '0201LF'  | 'EMPTY'  | 'CS31001FE17'(!)        = ''              | ''                 | 'CS31001FE17'           |'R0201'| '(SMR0201AW)'                  | '10K'     | '1%'    | '1/20W'  | 'IO'       | 'RES CHIP 10K 1/20W +-1%(0201)EF'                  | 'CHIPR0201'    | ''          | ''            | '20191004'
 '32.4'       | '1%'      | '1/16W'  | '0402LF'  | 'CHIP'   | 'CS03242FB00'(!)        = ''              | ''                 | 'CS03242FB00'           |'R0402'| '(R0402-0201)'                 | '32.4'    | '1%'    | '1/16W'  | 'DISCRETE' | 'RES CHIP 32.4 1/16W +-1%(0402)'                   | 'CHIPR0402'    | ''          | ''            | '20191004'
 '32.4'       | '1%'      | '1/16W'  | '0402LF'  | 'EMPTY'  | 'CS03242FB00'(!)        = ''              | ''                 | 'CS03242FB00'           |'R0402'| '(R0402-0201)'                 | '32.4'    | '1%'    | '1/16W'  | 'IO'       | 'RES CHIP 32.4 1/16W +-1%(0402)'                   | 'CHIPR0402'    | ''          | ''            | '20191004'
 '1.74M'      | '1%'      | '1/8W'   | '0805LF'  | 'CHIP'   | 'CS51744FA00'(!)        = ''              | ''                 | 'CS51744FA00'           |'R0805'| '(SMR0805AW)'                  | '1.74M'   | '1%'    | '1/8W'   | 'DISCRETE' | 'RES CHIP 1.74M 1/8W +-1%(0805)'                   | 'CHIPR0805'    | ''          | ''            | '20191008'
 '1.74M'      | '1%'      | '1/8W'   | '0805LF'  | 'EMPTY'  | 'CS51744FA00'(!)        = ''              | ''                 | 'CS51744FA00'           |'R0805'| '(SMR0805AW)'                  | '1.74M'   | '1%'    | '1/8W'   | 'IO'       | 'RES CHIP 1.74M 1/8W +-1%(0805)'                   | 'CHIPR0805'    | ''          | ''            | '20191008'
 '4.7K'       | '5%'      | '1/20W'  | '0201LF'  | 'CHIP'   | 'CS24701JE04'(!)        = 'End of Design' | 'Comp-Approve'     | 'CS24701JE04'           |'R0201'| '(SMR0201AW)'                  | '4.7K'    | '5%'    | '1/20W'  | 'DISCRETE' | 'RES CHIP 4.7K 1/20W +-5%(0201)EF'                 | 'CHIPR0201'    | ''          | ''            | '20191008'
 '4.7K'       | '5%'      | '1/20W'  | '0201LF'  | 'EMPTY'  | 'CS24701JE04'(!)        = 'End of Design' | 'Comp-Approve'     | 'CS24701JE04'           |'R0201'| '(SMR0201AW)'                  | '4.7K'    | '5%'    | '1/20W'  | 'IO'       | 'RES CHIP 4.7K 1/20W +-5%(0201)EF'                 | 'CHIPR0201'    | ''          | ''            | '20191008'
 '3.6K'       | '1%'      | '1/20W'  | '0201LF'  | 'CHIP'   | 'CS23601FE00'(!)        = ''              | ''                 | 'CS23601FE00'           |'R0201'| '(SMR0201AW)'                  | '3.6K'    | '1%'    | '1/20W'  | 'DISCRETE' | 'RES CHIP 3.6K 1/20W +-1% (0201)'                  | 'CHIPR0201'    | ''          | ''            | '20191008'
 '3.6K'       | '1%'      | '1/20W'  | '0201LF'  | 'EMPTY'  | 'CS23601FE00'(!)        = ''              | ''                 | 'CS23601FE00'           |'R0201'| '(SMR0201AW)'                  | '3.6K'    | '1%'    | '1/20W'  | 'IO'       | 'RES CHIP 3.6K 1/20W +-1% (0201)'                  | 'CHIPR0201'    | ''          | ''            | '20191008'
 '348'        | '1%'      | '1/10W'  | '0603LF'  | 'CHIP'   | 'CS13483F917'(!)        = ''              | ''                 | 'CS13483F917'           |'R0603_H24'| '(SMR0603AW)'                  | '348'     | '1%'    | '1/10W'  | 'DISCRETE' | 'RES CHIP 348 1/10W +-1%(0603)'                    | 'CHIPR0603'    | ''          | ''            | '20191008'
 '348'        | '1%'      | '1/10W'  | '0603LF'  | 'EMPTY'  | 'CS13483F917'(!)        = ''              | ''                 | 'CS13483F917'           |'R0603_H24'| '(SMR0603AW)'                  | '348'     | '1%'    | '1/10W'  | 'IO'       | 'RES CHIP 348 1/10W +-1%(0603)'                    | 'CHIPR0603'    | ''          | ''            | '20191008'
 '10.2'       | '0.1%'    | '1/16W'  | '0402LF'  | 'CHIP'   | 'CS01022BB00'(!)        = ''              | ''                 | 'CS01022BB00'           |'R0402'| '(R0402-0201)'                 | '10.2'    | '0.1%'  | '1/16W'  | 'DISCRETE' | 'RES CHIP 10.2 1/16W +-0.1%(0402)'                 | 'CHIPR0402'    | ''          | ''            | '20191021'
 '10.2'       | '0.1%'    | '1/16W'  | '0402LF'  | 'EMPTY'  | 'CS01022BB00'(!)        = ''              | ''                 | 'CS01022BB00'           |'R0402'| '(R0402-0201)'                 | '10.2'    | '0.1%'  | '1/16W'  | 'IO'       | 'RES CHIP 10.2 1/16W +-0.1%(0402)'                 | 'CHIPR0402'    | ''          | ''            | '20191021'
 '6.8K'       | '1%'      | '1/20W'  | '0201LF'  | 'CHIP'   | 'CS26801FE00'(!)        = ''              | ''                 | 'CS26801FE00'           |'R0201'| '(SMR0201AW)'                  | '6.8K'    | '1%'    | '1/20W'  | 'DISCRETE' | 'RES CHIP 6.8K(1/20W,+-1%,0201)'                   | 'CHIPR0201'    | ''          | ''            | '20191022'
 '6.8K'       | '1%'      | '1/20W'  | '0201LF'  | 'EMPTY'  | 'CS26801FE00'(!)        = ''              | ''                 | 'CS26801FE00'           |'R0201'| '(SMR0201AW)'                  | '6.8K'    | '1%'    | '1/20W'  | 'IO'       | 'RES CHIP 6.8K(1/20W,+-1%,0201)'                   | 'CHIPR0201'    | ''          | ''            | '20191022'
 '4.7'        | '1%'      | '1/16W'  | '0402LF'  | 'CHIP'   | 'CS-4702FB19'(!)        = 'End of Design' | 'Comp-Approve'     | 'CS-4702FB19'           |'R0402'| '(R0402-0201)'                 | '4.7'     | '1%'    | '1/16W'  | 'DISCRETE' | 'RES CHIP 4.7 1/16W +-1%(0402)'                    | 'CHIPR0402'    | ''          | ''            | '20191025'
 '4.7'        | '1%'      | '1/16W'  | '0402LF'  | 'EMPTY'  | 'CS-4702FB19'(!)        = 'End of Design' | 'Comp-Approve'     | 'CS-4702FB19'           |'R0402'| '(R0402-0201)'                 | '4.7'     | '1%'    | '1/16W'  | 'IO'       | 'RES CHIP 4.7 1/16W +-1%(0402)'                    | 'CHIPR0402'    | ''          | ''            | '20191025'
 '10.2'       | '1%'      | '1/16W'  | '0402LF'  | 'CHIP'   | 'CS01022FB00'(!)        = ''              | ''                 | 'CS01022FB00'           |'R0402'| '(R0402-0201)'                 | '10.2'    | '1%'    | '1/16W'  | 'DISCRETE' | 'RES CHIP 10.2 1/16W +-1%(0402)HF'                 | 'CHIPR0402'    | ''          | ''            | '20191029'
 '10.2'       | '1%'      | '1/16W'  | '0402LF'  | 'EMPTY'  | 'CS01022FB00'(!)        = ''              | ''                 | 'CS01022FB00'           |'R0402'| '(R0402-0201)'                 | '10.2'    | '1%'    | '1/16W'  | 'IO'       | 'RES CHIP 10.2 1/16W +-1%(0402)HF'                 | 'CHIPR0402'    | ''          | ''            | '20191029'
 '0.03'       | '1%'      | '1/2W'   | '1206LF'  | 'CHIP'   | 'CS+0307F200'(!)        = ''              | ''                 | 'CS+0307F200'           |'R1206'| '(SMR1206AW)'                  | '0.03'    | '1%'    | '1/2W'   | 'DISCRETE' | 'RES CHIP 0.03 1/2W +-1%(1206)'                    | 'CHIPR1206'    | ''          | ''            | '20191030'
 '0.03'       | '1%'      | '1/2W'   | '1206LF'  | 'EMPTY'  | 'CS+0307F200'(!)        = ''              | ''                 | 'CS+0307F200'           |'R1206'| '(SMR1206AW)'                  | '0.03'    | '1%'    | '1/2W'   | 'IO'       | 'RES CHIP 0.03 1/2W +-1%(1206)'                    | 'CHIPR1206'    | ''          | ''            | '20191030'
 '332K'       | '1%'      | '1/16W'  | '0402LF'  | 'CHIP'   | 'CS43322FB03'(!)        = 'End of Design' | 'Comp-Approve'     | 'CS43322FB03'           |'R0402'| '(R0402-0201)'                 | '332K'    | '1%'    | '1/16W'  | 'DISCRETE' | 'RES CHIP 332K 1/16W +-1%(0402)EF'                 | 'CHIPR0402'    | ''          | ''            | '20191101'
 '332K'       | '1%'      | '1/16W'  | '0402LF'  | 'EMPTY'  | 'CS43322FB03'(!)        = 'End of Design' | 'Comp-Approve'     | 'CS43322FB03'           |'R0402'| '(R0402-0201)'                 | '332K'    | '1%'    | '1/16W'  | 'IO'       | 'RES CHIP 332K 1/16W +-1%(0402)EF'                 | 'CHIPR0402'    | ''          | ''            | '20191101'
 '40.2K'      | '1%'      | '1/16W'  | '0402LF'  | 'CHIP'   | 'CS34022FB04'(!)        = 'End of Design' | 'Comp-Approve'     | 'CS34022FB04'           |'R0402'| '(R0402-0201)'                 | '40.2K'   | '1%'    | '1/16W'  | 'DISCRETE' | 'RES CHIP 40.2K 1/16W +-1%(0402)EF'                | 'CHIPR0402'    | ''          | ''            | '20191101'
 '40.2K'      | '1%'      | '1/16W'  | '0402LF'  | 'EMPTY'  | 'CS34022FB04'(!)        = 'End of Design' | 'Comp-Approve'     | 'CS34022FB04'           |'R0402'| '(R0402-0201)'                 | '40.2K'   | '1%'    | '1/16W'  | 'IO'       | 'RES CHIP 40.2K 1/16W +-1%(0402)EF'                | 'CHIPR0402'    | ''          | ''            | '20191101'
 '118K'       | '1%'      | '1/16W'  | '0402LF'  | 'CHIP'   | 'CS41182FB05'(!)        = ''              | ''                 | 'CS41182FB05'           |'R0402'| '(R0402-0201)'                 | '118K'    | '1%'    | '1/16W'  | 'DISCRETE' | 'RES CHIP 118K 1/16W +-1%(0402)EF'                 | 'CHIPR0402'    | ''          | ''            | '20191101'
 '118K'       | '1%'      | '1/16W'  | '0402LF'  | 'EMPTY'  | 'CS41182FB05'(!)        = ''              | ''                 | 'CS41182FB05'           |'R0402'| '(R0402-0201)'                 | '118K'    | '1%'    | '1/16W'  | 'IO'       | 'RES CHIP 118K 1/16W +-1%(0402)EF'                 | 'CHIPR0402'    | ''          | ''            | '20191101'
 '160K'       | '1%'      | '1/16W'  | '0402LF'  | 'CHIP'   | 'CS41602FB05'(!)        = ''              | ''                 | 'CS41602FB05'           |'R0402'| '(R0402-0201)'                 | '160K'    | '1%'    | '1/16W'  | 'DISCRETE' | 'RES CHIP 160K 1/16W+-1%(0402)EF'                  | 'CHIPR0402'    | ''          | ''            | '20191113'
 '160K'       | '1%'      | '1/16W'  | '0402LF'  | 'EMPTY'  | 'CS41602FB05'(!)        = ''              | ''                 | 'CS41602FB05'           |'R0402'| '(R0402-0201)'                 | '160K'    | '1%'    | '1/16W'  | 'IO'       | 'RES CHIP 160K 1/16W+-1%(0402)EF'                  | 'CHIPR0402'    | ''          | ''            | '20191113'
 '33.2K'      | '1%'      | '1/20W'  | '0201LF'  | 'CHIP'   | 'CS33321FE00'(!)        = ''              | ''                 | 'CS33321FE00'           |'R0201'| '(SMR0201AW)'                  | '33.2K'   | '1%'    | '1/20W'  | 'DISCRETE' | 'RES CHIP 33.2K 1/20W +-1%(0201)'                  | 'CHIPR0201'    | ''          | ''            | '20191122'
 '33.2K'      | '1%'      | '1/20W'  | '0201LF'  | 'EMPTY'  | 'CS33321FE00'(!)        = ''              | ''                 | 'CS33321FE00'           |'R0201'| '(SMR0201AW)'                  | '33.2K'   | '1%'    | '1/20W'  | 'IO'       | 'RES CHIP 33.2K 1/20W +-1%(0201)'                  | 'CHIPR0201'    | ''          | ''            | '20191122'
 '115K'       | '1%'      | '1/20W'  | '0201LF'  | 'CHIP'   | 'CS41151FE00'(!)        = ''              | ''                 | 'CS41151FE00'           |'R0201'| '(SMR0201AW)'                  | '115K'    | '1%'    | '1/20W'  | 'DISCRETE' | 'RES CHIP 115K 1/20W +-1% (0201)'                  | 'CHIPR0201'    | ''          | ''            | '20191122'
 '115K'       | '1%'      | '1/20W'  | '0201LF'  | 'EMPTY'  | 'CS41151FE00'(!)        = ''              | ''                 | 'CS41151FE00'           |'R0201'| '(SMR0201AW)'                  | '115K'    | '1%'    | '1/20W'  | 'IO'       | 'RES CHIP 115K 1/20W +-1% (0201)'                  | 'CHIPR0201'    | ''          | ''            | '20191122'
 '806'        | '1%'      | '1/10W'  | '0603LF'  | 'CHIP'   | 'CS18063F901'(!)        = ''              | ''                 | 'CS18063F901'           |'R0603_H24'| '(SMR0603AW)'                  | '806'     | '1%'    | '1/10W'  | 'DISCRETE' | 'RES CHIP 806 1/10W +-1%(0603)EF'                  | 'CHIPR0603'    | ''          | ''            | '20191203'
 '806'        | '1%'      | '1/10W'  | '0603LF'  | 'EMPTY'  | 'CS18063F901'(!)        = ''              | ''                 | 'CS18063F901'           |'R0603_H24'| '(SMR0603AW)'                  | '806'     | '1%'    | '1/10W'  | 'IO'       | 'RES CHIP 806 1/10W +-1%(0603)EF'                  | 'CHIPR0603'    | ''          | ''            | '20191203'
 '0.0006'     | '1%'      | '4W'     | '2725LF'  | 'CHIP'   | 'CS0000FFT03'(!)        = 'End of Design' | 'Comp-Approve'     | 'CS0000FFT03'           |'R2725'| '(SMR2725AW)'                  | '0.0006'  | '1%'    | '4W'     | 'DISCRETE' | 'RES CHIP 0.0006 4W +-1%(2725)H0.991'              | 'CHIPR2725'    | ''          | ''            | '20191204'
 '0.0006'     | '1%'      | '4W'     | '2725LF'  | 'EMPTY'  | 'CS0000FFT03'(!)        = 'End of Design' | 'Comp-Approve'     | 'CS0000FFT03'           |'R2725'| '(SMR2725AW)'                  | '0.0006'  | '1%'    | '4W'     | 'IO'       | 'RES CHIP 0.0006 4W +-1%(2725)H0.991'              | 'CHIPR2725'    | ''          | ''            | '20191204'
 '2.61K'      | '0.1%'    | '1/16W'  | '0402LF'  | 'CHIP'   | 'CS22612BB00'(!)        = ''              | ''                 | 'CS22612BB00'           |'R0402'| '(R0402-0201)'                 | '2.61K'   | '0.1%'  | '1/16W'  | 'DISCRETE' | 'RES CHIP 2.61K 1/16W +-0.1%(0402)'                | 'CHIPR0402'    | ''          | ''            | '20191204'
 '2.61K'      | '0.1%'    | '1/16W'  | '0402LF'  | 'EMPTY'  | 'CS22612BB00'(!)        = ''              | ''                 | 'CS22612BB00'           |'R0402'| '(R0402-0201)'                 | '2.61K'   | '0.1%'  | '1/16W'  | 'IO'       | 'RES CHIP 2.61K 1/16W +-0.1%(0402)'                | 'CHIPR0402'    | ''          | ''            | '20191204'
 '76.8K'      | '0.1%'    | '1/20W'  | '0201LF'  | 'CHIP'   | 'CS37681BE01'(!)        = ''              | ''                 | 'CS37681BE01'           |'R0201'| '(SMR0201AW)'                  | '76.8K'   | '0.1%'  | '1/20W'  | 'DISCRETE' | 'RES CHIP 76.8K 1/20W +-0.1%(0201)'                | 'CHIPR0201'    | ''          | ''            | '20191204'
 '76.8K'      | '0.1%'    | '1/20W'  | '0201LF'  | 'EMPTY'  | 'CS37681BE01'(!)        = ''              | ''                 | 'CS37681BE01'           |'R0201'| '(SMR0201AW)'                  | '76.8K'   | '0.1%'  | '1/20W'  | 'IO'       | 'RES CHIP 76.8K 1/20W +-0.1%(0201)'                | 'CHIPR0201'    | ''          | ''            | '20191204'
 '8.06K'      | '1%'      | '1/20W'  | '0201LF'  | 'CHIP'   | 'CS28061FE00'(!)        = ''              | ''                 | 'CS28061FE00'           |'R0201'| '(SMR0201AW)'                  | '8.06K'   | '1%'    | '1/20W'  | 'DISCRETE' | 'RES CHIP 8.06K 1/20W +-1%(0201)'                  | 'CHIPR0201'    | ''          | ''            | '20191204'
 '8.06K'      | '1%'      | '1/20W'  | '0201LF'  | 'EMPTY'  | 'CS28061FE00'(!)        = ''              | ''                 | 'CS28061FE00'           |'R0201'| '(SMR0201AW)'                  | '8.06K'   | '1%'    | '1/20W'  | 'IO'       | 'RES CHIP 8.06K 1/20W +-1%(0201)'                  | 'CHIPR0201'    | ''          | ''            | '20191204'
 '931K'       | '1%'      | '1/16W'  | '0402LF'  | 'CHIP'   | 'CS49312FB00'(!)        = ''              | ''                 | 'CS49312FB00'           |'R0402'| '(R0402-0201)'                 | '931K'    | '1%'    | '1/16W'  | 'DISCRETE' | 'RES CHIP 931K 1/16W +-1%(0402)'                   | 'CHIPR0402'    | ''          | ''            | '20191216'
 '931K'       | '1%'      | '1/16W'  | '0402LF'  | 'EMPTY'  | 'CS49312FB00'(!)        = ''              | ''                 | 'CS49312FB00'           |'R0402'| '(R0402-0201)'                 | '931K'    | '1%'    | '1/16W'  | 'IO'       | 'RES CHIP 931K 1/16W +-1%(0402)'                   | 'CHIPR0402'    | ''          | ''            | '20191216'
 '0'          | '5%'      | '1/8W'   | '0805LF'  | 'CHIP'   | 'CS00004JA05'(!)        = 'End of Design' | 'Comp-Approve'     | 'CS00004JA05'           |'R0805'| '(SMR0805AW)'                  | '0'       | '5%'    | '1/8W'   | 'DISCRETE' | 'RES CHIP 0 1/8W +-5% (0805)EF'                    | 'CHIPR0805'    | ''          | ''            | '20191218'
 '0'          | '5%'      | '1/8W'   | '0805LF'  | 'EMPTY'  | 'CS00004JA05'(!)        = 'End of Design' | 'Comp-Approve'     | 'CS00004JA05'           |'R0805'| '(SMR0805AW)'                  | '0'       | '5%'    | '1/8W'   | 'IO'       | 'RES CHIP 0 1/8W +-5% (0805)EF'                    | 'CHIPR0805'    | ''          | ''            | '20191218'
 '0.0004'     | '1%'      | '4W'     | '2725LF'  | 'CHIP'   | 'CS0000FFT08'(!)        = 'End of Design' | 'Comp-Release Qty' | 'CS0000FFT08'           |'R2725'| '(SMR2725AW)'                  | '0.0004'  | '1%'    | '4W'     | 'DISCRETE' | 'RES CHIP 0.0004 4W +-1%(2725)'                    | 'CHIPR2725'    | ''          | ''            | '20191227'
 '0.0004'     | '1%'      | '4W'     | '2725LF'  | 'EMPTY'  | 'CS0000FFT08'(!)        = 'End of Design' | 'Comp-Release Qty' | 'CS0000FFT08'           |'R2725'| '(SMR2725AW)'                  | '0.0004'  | '1%'    | '4W'     | 'IO'       | 'RES CHIP 0.0004 4W +-1%(2725)'                    | 'CHIPR2725'    | ''          | ''            | '20191227'
 '0'          | ''        | '1W'     | '2512LF'  | 'CHIP'   | 'CS00008TR01'(!)        = ''              | ''                 | 'CS00008TR01'           |'R2512XU'| '(SMR2512AW)'                  | '0'       | ''      | '1W'     | 'DISCRETE' | 'RES CHIP 0 1W(2512)EF'                            | 'CHIPR2512'    | ''          | ''            | '20191227'
 '0'          | ''        | '1W'     | '2512LF'  | 'EMPTY'  | 'CS00008TR01'(!)        = ''              | ''                 | 'CS00008TR01'           |'R2512XU'| '(SMR2512AW)'                  | '0'       | ''      | '1W'     | 'IO'       | 'RES CHIP 0 1W(2512)EF'                            | 'CHIPR2512'    | ''          | ''            | '20191227'
 '750'        | '1%'      | '1/16W'  | '0402LF'  | 'CHIP'   | 'CS17502FB03'(!)        = 'End of Design' | 'Comp-Approve'     | 'CS17502FB03'           |'R0402'| '(R0402-0201)'                 | '750'     | '1%'    | '1/16W'  | 'DISCRETE' | 'RES CHIP 750 1/16W +-1%(0402)EF'                  | 'CHIPR0402'    | ''          | ''            | '20191227'
 '750'        | '1%'      | '1/16W'  | '0402LF'  | 'EMPTY'  | 'CS17502FB03'(!)        = 'End of Design' | 'Comp-Approve'     | 'CS17502FB03'           |'R0402'| '(R0402-0201)'                 | '750'     | '1%'    | '1/16W'  | 'IO'       | 'RES CHIP 750 1/16W +-1%(0402)EF'                  | 'CHIPR0402'    | ''          | ''            | '20191227'
 '2.32K'      | '1%'      | '1/16W'  | '0402LF'  | 'CHIP'   | 'CS22322FB03'(!)        = 'End of Design' | 'Comp-Approve'     | 'CS22322FB03'           |'R0402'| '(R0402-0201)'                 | '2.32K'   | '1%'    | '1/16W'  | 'DISCRETE' | 'RES CHIP 2.32K 1/16W +-1%(0402)EF'                | 'CHIPR0402'    | ''          | ''            | '20191227'
 '2.32K'      | '1%'      | '1/16W'  | '0402LF'  | 'EMPTY'  | 'CS22322FB03'(!)        = 'End of Design' | 'Comp-Approve'     | 'CS22322FB03'           |'R0402'| '(R0402-0201)'                 | '2.32K'   | '1%'    | '1/16W'  | 'IO'       | 'RES CHIP 2.32K 1/16W +-1%(0402)EF'                | 'CHIPR0402'    | ''          | ''            | '20191227'
 '7.32K'      | '1%'      | '1/16W'  | '0402LF'  | 'CHIP'   | 'CS27322FB02'(!)        = 'End of Design' | 'Comp-Approve'     | 'CS27322FB02'           |'R0402'| '(R0402-0201)'                 | '7.32K'   | '1%'    | '1/16W'  | 'DISCRETE' | 'RES CHIP 7.32K 1/16W +-1%(0402)EF'                | 'CHIPR0402'    | ''          | ''            | '20191227'
 '7.32K'      | '1%'      | '1/16W'  | '0402LF'  | 'EMPTY'  | 'CS27322FB02'(!)        = 'End of Design' | 'Comp-Approve'     | 'CS27322FB02'           |'R0402'| '(R0402-0201)'                 | '7.32K'   | '1%'    | '1/16W'  | 'IO'       | 'RES CHIP 7.32K 1/16W +-1%(0402)EF'                | 'CHIPR0402'    | ''          | ''            | '20191227'
 '7.68K'      | '1%'      | '1/16W'  | '0402LF'  | 'CHIP'   | 'CS27682FB04'(!)        = 'End of Design' | 'Comp-Approve'     | 'CS27682FB04'           |'R0402'| '(R0402-0201)'                 | '7.68K'   | '1%'    | '1/16W'  | 'DISCRETE' | 'RES CHIP 7.68K 1/16W +-1%(0402)EF'                | 'CHIPR0402'    | ''          | ''            | '20191227'
 '7.68K'      | '1%'      | '1/16W'  | '0402LF'  | 'EMPTY'  | 'CS27682FB04'(!)        = 'End of Design' | 'Comp-Approve'     | 'CS27682FB04'           |'R0402'| '(R0402-0201)'                 | '7.68K'   | '1%'    | '1/16W'  | 'IO'       | 'RES CHIP 7.68K 1/16W +-1%(0402)EF'                | 'CHIPR0402'    | ''          | ''            | '20191227'
 '15K'        | '1%'      | '1/16W'  | '0402LF'  | 'CHIP'   | 'CS31502FB05'(!)        = 'End of Design' | 'Comp-Approve'     | 'CS31502FB05'           |'R0402'| '(R0402-0201)'                 | '15K'     | '1%'    | '1/16W'  | 'DISCRETE' | 'RES CHIP 15K 1/16W +-1%(0402)EF'                  | 'CHIPR0402'    | ''          | ''            | '20191227'
 '15K'        | '1%'      | '1/16W'  | '0402LF'  | 'EMPTY'  | 'CS31502FB05'(!)        = 'End of Design' | 'Comp-Approve'     | 'CS31502FB05'           |'R0402'| '(R0402-0201)'                 | '15K'     | '1%'    | '1/16W'  | 'IO'       | 'RES CHIP 15K 1/16W +-1%(0402)EF'                  | 'CHIPR0402'    | ''          | ''            | '20191227'
 '634K'       | '1%'      | '1/16W'  | '0402LF'  | 'CHIP'   | 'CS46342FB04'(!)        = 'End of Design' | 'Comp-Approve'     | 'CS46342FB04'           |'R0402'| '(R0402-0201)'                 | '634K'    | '1%'    | '1/16W'  | 'DISCRETE' | 'RES CHIP 634K 1/16W +-1%(0402)'                   | 'CHIPR0402'    | ''          | ''            | '20200108'
 '634K'       | '1%'      | '1/16W'  | '0402LF'  | 'EMPTY'  | 'CS46342FB04'(!)        = 'End of Design' | 'Comp-Approve'     | 'CS46342FB04'           |'R0402'| '(R0402-0201)'                 | '634K'    | '1%'    | '1/16W'  | 'IO'       | 'RES CHIP 634K 1/16W +-1%(0402)'                   | 'CHIPR0402'    | ''          | ''            | '20200108'
 '825K'       | '1%'      | '1/16W'  | '0402LF'  | 'CHIP'   | 'CS48252FB01'(!)        = ''              | ''                 | 'CS48252FB01'           |'R0402'| '(R0402-0201)'                 | '825K'    | '1%'    | '1/16W'  | 'DISCRETE' | 'RES CHIP 825K 1/16W +-1%(0402)'                   | 'CHIPR0402'    | ''          | ''            | '20200108'
 '825K'       | '1%'      | '1/16W'  | '0402LF'  | 'EMPTY'  | 'CS48252FB01'(!)        = ''              | ''                 | 'CS48252FB01'           |'R0402'| '(R0402-0201)'                 | '825K'    | '1%'    | '1/16W'  | 'IO'       | 'RES CHIP 825K 1/16W +-1%(0402)'                   | 'CHIPR0402'    | ''          | ''            | '20200108'
 '715K'       | '1%'      | '1/16W'  | '0402LF'  | 'CHIP'   | 'CS47152FB00'(!)        = ''              | ''                 | 'CS47152FB00'           |'R0402'| '(R0402-0201)'                 | '715K'    | '1%'    | '1/16W'  | 'DISCRETE' | 'RES CHIP 715K 1/16W +-1% (0402)'                  | 'CHIPR0402'    | ''          | ''            | '20200114'
 '715K'       | '1%'      | '1/16W'  | '0402LF'  | 'EMPTY'  | 'CS47152FB00'(!)        = ''              | ''                 | 'CS47152FB00'           |'R0402'| '(R0402-0201)'                 | '715K'    | '1%'    | '1/16W'  | 'IO'       | 'RES CHIP 715K 1/16W +-1% (0402)'                  | 'CHIPR0402'    | ''          | ''            | '20200114'
 '2.7K'       | '5%'      | '1/8W'   | '0805LF'  | 'CHIP'   | 'CS22704JA36'(!)        = ''              | ''                 | 'CS22704JA36'           |'R0805'| '(SMR0805AW)'                  | '2.7K'    | '5%'    | '1/8W'   | 'DISCRETE' | 'RESISTOR CHIP 2.7K  1/8W  +-5%(0805)'             | 'CHIPR0805'    | ''          | ''            | '20200113'
 '2.7K'       | '5%'      | '1/8W'   | '0805LF'  | 'EMPTY'  | 'CS22704JA36'(!)        = ''              | ''                 | 'CS22704JA36'           |'R0805'| '(SMR0805AW)'                  | '2.7K'    | '5%'    | '1/8W'   | 'IO'       | 'RESISTOR CHIP 2.7K  1/8W  +-5%(0805)'             | 'CHIPR0805'    | ''          | ''            | '20200113'
 '19.6K'      | '1%'      | '1/16W'  | '0402LF'  | 'CHIP'   | 'CS31962FB07'(!)        = ''              | ''                 | 'CS31962FB07'           |'R0402'| '(R0402-0201)'                 | '19.6K'   | '1%'    | '1/16W'  | 'DISCRETE' | 'RES CHIP 19.6K 1/16W +-1%(0402)EF'                | 'CHIPR0402'    | ''          | ''            | '20200114'
 '19.6K'      | '1%'      | '1/16W'  | '0402LF'  | 'EMPTY'  | 'CS31962FB07'(!)        = ''              | ''                 | 'CS31962FB07'           |'R0402'| '(R0402-0201)'                 | '19.6K'   | '1%'    | '1/16W'  | 'IO'       | 'RES CHIP 19.6K 1/16W +-1%(0402)EF'                | 'CHIPR0402'    | ''          | ''            | '20200114'
 '255'        | '1%'      | '1/10W'  | '0603LF'  | 'CHIP'   | 'CS12553F914'(!)        = ''              | ''                 | 'CS12553F914'           |'R0603'| '(SMR0603AW)'                  | '255'     | '1%'    | '1/10W'  | 'DISCRETE' | 'RESISTOR CHIP 255,1/10W,+-1%(0603)'               | 'CHIPR0603'    | ''          | ''            | '20200122'
 '255'        | '1%'      | '1/10W'  | '0603LF'  | 'EMPTY'  | 'CS12553F914'(!)        = ''              | ''                 | 'CS12553F914'           |'R0603'| '(SMR0603AW)'                  | '255'     | '1%'    | '1/10W'  | 'IO'       | 'RESISTOR CHIP 255,1/10W,+-1%(0603)'               | 'CHIPR0603'    | ''          | ''            | '20200122'
 '33'         | '5%'      | '1/8W'   | '0805LF'  | 'CHIP'   | 'CS03304JA14'(!)        = ''              | ''                 | 'CS03304JA14'           |'R0805'| '(SMR0805AW)'                  | '33'      | '5%'    | '1/8W'   | 'DISCRETE' | 'RES CHIP 33 1/8W +-5% (0805)'                     | 'CHIPR0805'    | ''          | ''            | '20200203'
 '33'         | '5%'      | '1/8W'   | '0805LF'  | 'EMPTY'  | 'CS03304JA14'(!)        = ''              | ''                 | 'CS03304JA14'           |'R0805'| '(SMR0805AW)'                  | '33'      | '5%'    | '1/8W'   | 'IO'       | 'RES CHIP 33 1/8W +-5% (0805)'                     | 'CHIPR0805'    | ''          | ''            | '20200203'
 '120K'       | '1%'      | '1/16W'  | '0402LF'  | 'CHIP'   | 'CS41202FB05'(!)        = ''              | ''                 | 'CS41202FB05'           |'R0402'| '(R0402-0201)'                 | '120K'    | '1%'    | '1/16W'  | 'DISCRETE' | 'RES CHIP 120K 1/16W +-1%(0402)EF'                 | 'CHIPR0402'    | ''          | ''            | '20200225'
 '120K'       | '1%'      | '1/16W'  | '0402LF'  | 'EMPTY'  | 'CS41202FB05'(!)        = ''              | ''                 | 'CS41202FB05'           |'R0402'| '(R0402-0201)'                 | '120K'    | '1%'    | '1/16W'  | 'IO'       | 'RES CHIP 120K 1/16W +-1%(0402)EF'                 | 'CHIPR0402'    | ''          | ''            | '20200225'
 '0.0003'     | '1%'      | '8W'     | '2512LF'  | 'CHIP'   | 'CS0000LFR00'(!)        = ''              | ''                 | 'CS0000LFR00'           |'R2512XV'| '(SMR2512AW)'                  | '0.0003'  | '1%'    | '8W'     | 'DISCRETE' | 'RES CHIP 0.0003 8W +-1% (2512)KOA'                | 'CHIPR2512'    | ''          | ''            | '20200227'
 '0.0003'     | '1%'      | '8W'     | '2512LF'  | 'EMPTY'  | 'CS0000LFR00'(!)        = ''              | ''                 | 'CS0000LFR00'           |'R2512XV'| '(SMR2512AW)'                  | '0.0003'  | '1%'    | '8W'     | 'IO'       | 'RES CHIP 0.0003 8W +-1% (2512)KOA'                | 'CHIPR2512'    | ''          | ''            | '20200227'
 '56.2K'      | '1%'      | '1/16W'  | '0402LF'  | 'CHIP'   | 'CS35622FB07'(!)        = 'End of Design' | 'Comp-Approve'     | 'CS35622FB07'           |'R0402'| '(R0402-0201)'                 | '56.2K'   | '1%'    | '1/16W'  | 'DISCRETE' | 'RES CHIP 56.2K 1/16W +-1%(0402)EF'                | 'CHIPR0402'    | ''          | ''            | '20200227'
 '56.2K'      | '1%'      | '1/16W'  | '0402LF'  | 'EMPTY'  | 'CS35622FB07'(!)        = 'End of Design' | 'Comp-Approve'     | 'CS35622FB07'           |'R0402'| '(R0402-0201)'                 | '56.2K'   | '1%'    | '1/16W'  | 'IO'       | 'RES CHIP 56.2K 1/16W +-1%(0402)EF'                | 'CHIPR0402'    | ''          | ''            | '20200227'
 '46.4K'      | '1%'      | '1/16W'  | '0402LF'  | 'CHIP'   | 'CS34642FB02'(!)        = ''              | ''                 | 'CS34642FB02'           |'R0402'| '(R0402-0201)'                 | '46.4K'   | '1%'    | '1/16W'  | 'DISCRETE' | 'RES CHIP 46.4K 1/16W +-1%(0402)EF'                | 'CHIPR0402'    | ''          | ''            | '20200227'
 '46.4K'      | '1%'      | '1/16W'  | '0402LF'  | 'EMPTY'  | 'CS34642FB02'(!)        = ''              | ''                 | 'CS34642FB02'           |'R0402'| '(R0402-0201)'                 | '46.4K'   | '1%'    | '1/16W'  | 'IO'       | 'RES CHIP 46.4K 1/16W +-1%(0402)EF'                | 'CHIPR0402'    | ''          | ''            | '20200227'
 '21.5K'      | '1%'      | '1/16W'  | '0402LF'  | 'CHIP'   | 'CS32152FB04'(!)        = ''              | ''                 | 'CS32152FB04'           |'R0402'| '(R0402-0201)'                 | '21.5K'   | '1%'    | '1/16W'  | 'DISCRETE' | 'RES CHIP 21.5K 1/16W +-1%(0402)EF'                | 'CHIPR0402'    | ''          | ''            | '20200302'
 '21.5K'      | '1%'      | '1/16W'  | '0402LF'  | 'EMPTY'  | 'CS32152FB04'(!)        = ''              | ''                 | 'CS32152FB04'           |'R0402'| '(R0402-0201)'                 | '21.5K'   | '1%'    | '1/16W'  | 'IO'       | 'RES CHIP 21.5K 1/16W +-1%(0402)EF'                | 'CHIPR0402'    | ''          | ''            | '20200302'
 '270K'       | '1%'      | '1/16W'  | '0402LF'  | 'CHIP'   | 'CS42702FB01'(!)        = ''              | ''                 | 'CS42702FB01'           |'R0402'| '(R0402-0201)'                 | '270K'    | '1%'    | '1/16W'  | 'DISCRETE' | 'RES CHIP 270K 1/16W +-1%(0402)EF'                 | 'CHIPR0402'    | ''          | ''            | '20200304'
 '270K'       | '1%'      | '1/16W'  | '0402LF'  | 'EMPTY'  | 'CS42702FB01'(!)        = ''              | ''                 | 'CS42702FB01'           |'R0402'| '(R0402-0201)'                 | '270K'    | '1%'    | '1/16W'  | 'IO'       | 'RES CHIP 270K 1/16W +-1%(0402)EF'                 | 'CHIPR0402'    | ''          | ''            | '20200304'
 '0.22'       | '1%'      | '1/2W'   | '1206LF'  | 'CHIP'   | 'CS+2207F202'(!)        = ''              | ''                 | 'CS+2207F202'           |'R1206XJ'| '(SMR1206AW)'                  | '0.22'    | '1%'    | '1/2W'   | 'DISCRETE' | 'RES CHIP 0.22 1/2W +-1%(1206)'                    | 'CHIPR1206'    | ''          | ''            | '20200304'
 '0.22'       | '1%'      | '1/2W'   | '1206LF'  | 'EMPTY'  | 'CS+2207F202'(!)        = ''              | ''                 | 'CS+2207F202'           |'R1206XJ'| '(SMR1206AW)'                  | '0.22'    | '1%'    | '1/2W'   | 'IO'       | 'RES CHIP 0.22 1/2W +-1%(1206)'                    | 'CHIPR1206'    | ''          | ''            | '20200304'
 '4.75'       | '1%'      | '1/16W'  | '0402LF'  | 'CHIP'   | 'CS-4752FB01'(!)        = 'End of Design' | 'Comp-Approve'     | 'CS-4752FB01'           |'R0402'| '(R0402-0201)'                 | '4.75'    | '1%'    | '1/16W'  | 'DISCRETE' | 'RES CHIP 4.75 1/16W +-1%(0402)EF'                 | 'CHIPR0402'    | ''          | ''            | '20200312'
 '4.75'       | '1%'      | '1/16W'  | '0402LF'  | 'EMPTY'  | 'CS-4752FB01'(!)        = 'End of Design' | 'Comp-Approve'     | 'CS-4752FB01'           |'R0402'| '(R0402-0201)'                 | '4.75'    | '1%'    | '1/16W'  | 'IO'       | 'RES CHIP 4.75 1/16W +-1%(0402)EF'                 | 'CHIPR0402'    | ''          | ''            | '20200312'
 '1.3M'       | '1%'      | '1/16W'  | '0402LF'  | 'CHIP'   | 'CS51302FB00'(!)        = ''              | ''                 | 'CS51302FB00'           |'R0402'| '(R0402-0201)'                 | '1.3M'    | '1%'    | '1/16W'  | 'DISCRETE' | 'RES CHIP 1.3M 1/16W +-1%(0402)'                   | 'CHIPR0402'    | ''          | ''            | '20200313'
 '1.3M'       | '1%'      | '1/16W'  | '0402LF'  | 'EMPTY'  | 'CS51302FB00'(!)        = ''              | ''                 | 'CS51302FB00'           |'R0402'| '(R0402-0201)'                 | '1.3M'    | '1%'    | '1/16W'  | 'IO'       | 'RES CHIP 1.3M 1/16W +-1%(0402)'                   | 'CHIPR0402'    | ''          | ''            | '20200313'
 '1.43M'      | '1%'      | '1/16W'  | '0402LF'  | 'CHIP'   | 'CS51432FB10'(!)        = ''              | ''                 | 'CS51432FB10'           |'R0402'| '(R0402-0201)'                 | '1.43M'   | '1%'    | '1/16W'  | 'DISCRETE' | 'RES CHIP 1.43M 1/16W+-1%(0402)'                   | 'CHIPR0402'    | ''          | ''            | '20200313'
 '1.43M'      | '1%'      | '1/16W'  | '0402LF'  | 'EMPTY'  | 'CS51432FB10'(!)        = ''              | ''                 | 'CS51432FB10'           |'R0402'| '(R0402-0201)'                 | '1.43M'   | '1%'    | '1/16W'  | 'IO'       | 'RES CHIP 1.43M 1/16W+-1%(0402)'                   | 'CHIPR0402'    | ''          | ''            | '20200313'
 '976'        | '0.1%'    | '1/16W'  | '0402LF'  | 'CHIP'   | 'CS19762BB00'(!)        = ''              | ''                 | 'CS19762BB00'           |'R0402'| '(R0402-0201)'                 | '976'     | '0.1%'  | '1/16W'  | 'DISCRETE' | 'RES CHIP 976 1/16W  +-0.1%(0402)'                 | 'CHIPR0402'    | ''          | ''            | '20170829'
 '976'        | '0.1%'    | '1/16W'  | '0402LF'  | 'EMPTY'  | 'CS19762BB00'(!)        = ''              | ''                 | 'CS19762BB00'           |'R0402'| '(R0402-0201)'                 | '976'     | '0.1%'  | '1/16W'  | 'IO'       | 'RES CHIP 976 1/16W  +-0.1%(0402)'                 | 'CHIPR0402'    | ''          | ''            | '20170829'
 '3.3'        | '1%'      | '1/16W'  | '0402LF'  | 'CHIP'   | 'CS-3302FB00'(!)        = 'End of Design' | 'Comp-Approve'     | 'CS-3302FB00'           |'R0402'| '(R0402-0201)'                 | '3.3'     | '1%'    | '1/16W'  | 'DISCRETE' | 'RES CHIP 3.3 1/16W +-1% (0402)'                   | 'CHIPR0402'    | ''          | ''            | '20200319'
 '3.3'        | '1%'      | '1/16W'  | '0402LF'  | 'EMPTY'  | 'CS-3302FB00'(!)        = 'End of Design' | 'Comp-Approve'     | 'CS-3302FB00'           |'R0402'| '(R0402-0201)'                 | '3.3'     | '1%'    | '1/16W'  | 'IO'       | 'RES CHIP 3.3 1/16W +-1% (0402)'                   | 'CHIPR0402'    | ''          | ''            | '20200319'
 '100'        | '1%'      | '1/4W'   | '1206LF'  | 'CHIP'   | 'CS11006F216'(!)        = ''              | ''                 | 'CS11006F216'           |'R1206XM'| '(SMR1206AW)'                  | '100'     | '1%'    | '1/4W'   | 'DISCRETE' | 'RES CHIP 100 1/4W +-1%(1206)'                     | 'CHIPR1206'    | ''          | ''            | '20200323'
 '100'        | '1%'      | '1/4W'   | '1206LF'  | 'EMPTY'  | 'CS11006F216'(!)        = ''              | ''                 | 'CS11006F216'           |'R1206XM'| '(SMR1206AW)'                  | '100'     | '1%'    | '1/4W'   | 'IO'       | 'RES CHIP 100 1/4W +-1%(1206)'                     | 'CHIPR1206'    | ''          | ''            | '20200323'
 '5.76K'      | '1%'      | '1/16W'  | '0402LF'  | 'CHIP'   | 'CS25762FB04'(!)        = 'End of Design' | 'Comp-Approve'     | 'CS25762FB04'           |'R0402'| '(R0402-0201)'                 | '5.76K'   | '1%'    | '1/16W'  | 'DISCRETE' | 'RES CHIP 5.76K 1/16W +-1%(0402)EF'                | 'CHIPR0402'    | ''          | ''            | '20200320'
 '5.76K'      | '1%'      | '1/16W'  | '0402LF'  | 'EMPTY'  | 'CS25762FB04'(!)        = 'End of Design' | 'Comp-Approve'     | 'CS25762FB04'           |'R0402'| '(R0402-0201)'                 | '5.76K'   | '1%'    | '1/16W'  | 'IO'       | 'RES CHIP 5.76K 1/16W +-1%(0402)EF'                | 'CHIPR0402'    | ''          | ''            | '20200320'
 '4.7K'       | '1%'      | '1/20W'  | '0201LF'  | 'CHIP'   | 'CS24701FE00'(!)        = ''              | ''                 | 'CS24701FE00'           |'R0201'| '(SMR0201AW)'                  | '4.7K'    | '1%'    | '1/20W'  | 'DISCRETE' | 'RES CHIP 4.7K 1/20W +-1%(0201)'                   | 'CHIPR0201'    | ''          | ''            | '20200326'
 '4.7K'       | '1%'      | '1/20W'  | '0201LF'  | 'EMPTY'  | 'CS24701FE00'(!)        = ''              | ''                 | 'CS24701FE00'           |'R0201'| '(SMR0201AW)'                  | '4.7K'    | '1%'    | '1/20W'  | 'IO'       | 'RES CHIP 4.7K 1/20W +-1%(0201)'                   | 'CHIPR0201'    | ''          | ''            | '20200326'
 '30K'        | '1%'      | '1/20W'  | '0201LF'  | 'CHIP'   | 'CS33001FE00'(!)        = 'End of Design' | 'Comp-Approve'     | 'CS33001FE00'           |'R0201'| '(SMR0201AW)'                  | '30K'     | '1%'    | '1/20W'  | 'DISCRETE' | 'RES CHIP 30K 1/20W +-1% (0201)'                   | 'CHIPR0201'    | ''          | ''            | '20200326'
 '30K'        | '1%'      | '1/20W'  | '0201LF'  | 'EMPTY'  | 'CS33001FE00'(!)        = 'End of Design' | 'Comp-Approve'     | 'CS33001FE00'           |'R0201'| '(SMR0201AW)'                  | '30K'     | '1%'    | '1/20W'  | 'IO'       | 'RES CHIP 30K 1/20W +-1% (0201)'                   | 'CHIPR0201'    | ''          | ''            | '20200326'
 '162'        | '1%'      | '1/16W'  | '0402LF'  | 'CHIP'   | 'CS11622FB09'(!)        = ''              | ''                 | 'CS11622FB09'           |'R0402'| '(R0402-0201)'                 | '162'     | '1%'    | '1/16W'  | 'DISCRETE' | 'RES CHIP 162 1/16W +-1% (0402)YGO'                | 'CHIPR0402'    | ''          | ''            | '20200324'
 '162'        | '1%'      | '1/16W'  | '0402LF'  | 'EMPTY'  | 'CS11622FB09'(!)        = ''              | ''                 | 'CS11622FB09'           |'R0402'| '(R0402-0201)'                 | '162'     | '1%'    | '1/16W'  | 'IO'       | 'RES CHIP 162 1/16W +-1% (0402)YGO'                | 'CHIPR0402'    | ''          | ''            | '20200324'
 '681'        | '1%'      | '1/16W'  | '0402LF'  | 'CHIP'   | 'CS16812FB07'(!)        = ''              | ''                 | 'CS16812FB07'           |'R0402'| '(R0402-0201)'                 | '681'     | '1%'    | '1/16W'  | 'DISCRETE' | 'RES CHIP 681 1/16W +-1% (0402)YGO'                | 'CHIPR0402'    | ''          | ''            | '20200325'
 '681'        | '1%'      | '1/16W'  | '0402LF'  | 'EMPTY'  | 'CS16812FB07'(!)        = ''              | ''                 | 'CS16812FB07'           |'R0402'| '(R0402-0201)'                 | '681'     | '1%'    | '1/16W'  | 'IO'       | 'RES CHIP 681 1/16W +-1% (0402)YGO'                | 'CHIPR0402'    | ''          | ''            | '20200325'
 '2.8K'       | '1%'      | '1/16W'  | '0402LF'  | 'CHIP'   | 'CS22802FB07'(!)        = ''              | ''                 | 'CS22802FB07'           |'R0402'| '(R0402-0201)'                 | '2.8K'    | '1%'    | '1/16W'  | 'DISCRETE' | 'RES CHIP 2.8K 1/16W +-1%(0402)YGO'                | 'CHIPR0402'    | ''          | ''            | '20200325'
 '2.8K'       | '1%'      | '1/16W'  | '0402LF'  | 'EMPTY'  | 'CS22802FB07'(!)        = ''              | ''                 | 'CS22802FB07'           |'R0402'| '(R0402-0201)'                 | '2.8K'    | '1%'    | '1/16W'  | 'IO'       | 'RES CHIP 2.8K 1/16W +-1%(0402)YGO'                | 'CHIPR0402'    | ''          | ''            | '20200325'
 '3.3'        | '1%'      | '1/2W'   | '1206LF'  | 'CHIP'   | 'CS-3307F200'(!)        = ''              | ''                 | 'CS-3307F200'           |'R1206XN'| '(SMR1206AW)'                  | '3.3'     | '1%'    | '1/2W'   | 'DISCRETE' | 'RES CHIP 3.3 1/2W+-1%(1206)SR'                    | 'CHIPR1206'    | ''          | ''            | '20200330'
 '3.3'        | '1%'      | '1/2W'   | '1206LF'  | 'EMPTY'  | 'CS-3307F200'(!)        = ''              | ''                 | 'CS-3307F200'           |'R1206XN'| '(SMR1206AW)'                  | '3.3'     | '1%'    | '1/2W'   | 'IO'       | 'RES CHIP 3.3 1/2W+-1%(1206)SR'                    | 'CHIPR1206'    | ''          | ''            | '20200330'
 '475K'       | '1%'      | '1/10W'  | '0603LF'  | 'CHIP'   | 'CS44753F912'(!)        = ''              | ''                 | 'CS44753F912'           |'R0603'| '(SMR0603AW)'                  | '475K'    | '1%'    | '1/10W'  | 'DISCRETE' | 'RES CHIP 475K 1/10W +-1%(0603)'                   | 'CHIPR0603'    | ''          | ''            | '20200401'
 '475K'       | '1%'      | '1/10W'  | '0603LF'  | 'EMPTY'  | 'CS44753F912'(!)        = ''              | ''                 | 'CS44753F912'           |'R0603'| '(SMR0603AW)'                  | '475K'    | '1%'    | '1/10W'  | 'IO'       | 'RES CHIP 475K 1/10W +-1%(0603)'                   | 'CHIPR0603'    | ''          | ''            | '20200401'
 '124'        | '1%'      | '1/16W'  | '0402LF'  | 'CHIP'   | 'CS11242FB10'(!)        = 'End of Design' | 'Comp-Approve'     | 'CS11242FB10'           |'R0402'| '(R0402-0201)'                 | '124'     | '1%'    | '1/16W'  | 'DISCRETE' | 'RES CHIP 124 1/16W +-1%(0402)'                    | 'CHIPR0402'    | ''          | ''            | '20200409'
 '124'        | '1%'      | '1/16W'  | '0402LF'  | 'EMPTY'  | 'CS11242FB10'(!)        = 'End of Design' | 'Comp-Approve'     | 'CS11242FB10'           |'R0402'| '(R0402-0201)'                 | '124'     | '1%'    | '1/16W'  | 'IO'       | 'RES CHIP 124 1/16W +-1%(0402)'                    | 'CHIPR0402'    | ''          | ''            | '20200409'
 '3.3'        | '1%'      | '1/4W'   | '0603LF'  | 'CHIP'   | 'CS-3306F900'(!)        = ''              | ''                 | 'CS-3306F900'           |'R0603'| '(SMR0603AW)'                  | '3.3'     | '1%'    | '1/4W'   | 'DISCRETE' | 'RES CHIP 3.3 1/4W+-1%(0603)SR'                    | 'CHIPR0603'    | ''          | ''            | '20200414'
 '3.3'        | '1%'      | '1/4W'   | '0603LF'  | 'EMPTY'  | 'CS-3306F900'(!)        = ''              | ''                 | 'CS-3306F900'           |'R0603'| '(SMR0603AW)'                  | '3.3'     | '1%'    | '1/4W'   | 'IO'       | 'RES CHIP 3.3 1/4W+-1%(0603)SR'                    | 'CHIPR0603'    | ''          | ''            | '20200414'
 '330'        | '5%'      | '1/2W'   | '1206LF'  | 'CHIP'   | 'CS13307J200'(!)        = ''              | ''                 | 'CS13307J200'           |'R1206XN'| '(SMR1206AW)'                  | '330'     | '5%'    | '1/2W'   | 'DISCRETE' | 'RES CHIP 330 1/2W+-5%(1206)SR'                    | 'CHIPR1206'    | ''          | ''            | '20200424'
 '330'        | '5%'      | '1/2W'   | '1206LF'  | 'EMPTY'  | 'CS13307J200'(!)        = ''              | ''                 | 'CS13307J200'           |'R1206XN'| '(SMR1206AW)'                  | '330'     | '5%'    | '1/2W'   | 'IO'       | 'RES CHIP 330 1/2W+-5%(1206)SR'                    | 'CHIPR1206'    | ''          | ''            | '20200424'
 '3.3'        | '5%'      | '1/5W'   | '0603LF'  | 'CHIP'   | 'CS-330GJ900'(!)        = ''              | ''                 | 'CS-330GJ900'           |'R0603'| '(SMR0603AW)'                  | '3.3'     | '5%'    | '1/5W'   | 'DISCRETE' | 'RES CHIP 3.3 1/5W+-5%(0603)SR'                    | 'CHIPR0603'    | ''          | ''            | '20200429'
 '3.3'        | '5%'      | '1/5W'   | '0603LF'  | 'EMPTY'  | 'CS-330GJ900'(!)        = ''              | ''                 | 'CS-330GJ900'           |'R0603'| '(SMR0603AW)'                  | '3.3'     | '5%'    | '1/5W'   | 'IO'       | 'RES CHIP 3.3 1/5W+-5%(0603)SR'                    | 'CHIPR0603'    | ''          | ''            | '20200429'
 '1.5'        | '5%'      | '1/4W'   | '0603LF'  | 'CHIP'   | 'CS-1506J900'(!)        = ''              | ''                 | 'CS-1506J900'           |'R0603'| '(SMR0603AW)'                  | '1.5'     | '5%'    | '1/4W'   | 'DISCRETE' | 'RES CHIP 1.5 1/4W+-5%(0603)SR'                    | 'CHIPR0603'    | ''          | ''            | '20200505'
 '1.5'        | '5%'      | '1/4W'   | '0603LF'  | 'EMPTY'  | 'CS-1506J900'(!)        = ''              | ''                 | 'CS-1506J900'           |'R0603'| '(SMR0603AW)'                  | '1.5'     | '5%'    | '1/4W'   | 'IO'       | 'RES CHIP 1.5 1/4W+-5%(0603)SR'                    | 'CHIPR0603'    | ''          | ''            | '20200505'
 '3.65K'      | '1%'      | '1/16W'  | '0402LF'  | 'CHIP'   | 'CS23652FB03'(!)        = ''              | ''                 | 'CS23652FB03'           |'R0402'| '(R0402-0201)'                 | '3.65K'   | '1%'    | '1/16W'  | 'DISCRETE' | 'RES CHIP 3.65K 1/16W +-1%(0402)EF'                | 'CHIPR0402'    | ''          | ''            | '20200508'
 '3.65K'      | '1%'      | '1/16W'  | '0402LF'  | 'EMPTY'  | 'CS23652FB03'(!)        = ''              | ''                 | 'CS23652FB03'           |'R0402'| '(R0402-0201)'                 | '3.65K'   | '1%'    | '1/16W'  | 'IO'       | 'RES CHIP 3.65K 1/16W +-1%(0402)EF'                | 'CHIPR0402'    | ''          | ''            | '20200508'
 '0.01'       | '1%'      | '1W'     | '1206LF'  | 'CHIP'   | 'CS+0108F207'(!)        = ''              | ''                 | 'CS+0108F207'           |'R1206XO'| '(SMR1206AW)'                  | '0.01'    | '1%'    | '1W'     | 'DISCRETE' | 'RES CHIP 0.01 1W +-1%(1206)EF'                    | 'CHIPR1206'    | ''          | ''            | '20191224'
 '0.01'       | '1%'      | '1W'     | '1206LF'  | 'EMPTY'  | 'CS+0108F207'(!)        = ''              | ''                 | 'CS+0108F207'           |'R1206XO'| '(SMR1206AW)'                  | '0.01'    | '1%'    | '1W'     | 'IO'       | 'RES CHIP 0.01 1W +-1%(1206)EF'                    | 'CHIPR1206'    | ''          | ''            | '20191224'
 '1.58M'      | '1%'      | '1/8W'   | '0805LF'  | 'CHIP'   | 'CS51584FA00'(!)        = ''              | ''                 | 'CS51584FA00'           |'R0805'| '(SMR0805AW)'                  | '1.58M'   | '1%'    | '1/8W'   | 'DISCRETE' | 'RES CHIP 1.58M 1/8W +-1%(0805)'                   | 'CHIPR0805'    | ''          | ''            | '20200514'
 '1.58M'      | '1%'      | '1/8W'   | '0805LF'  | 'EMPTY'  | 'CS51584FA00'(!)        = ''              | ''                 | 'CS51584FA00'           |'R0805'| '(SMR0805AW)'                  | '1.58M'   | '1%'    | '1/8W'   | 'IO'       | 'RES CHIP 1.58M 1/8W +-1%(0805)'                   | 'CHIPR0805'    | ''          | ''            | '20200514'
 '1.5K'       | '1%'      | '1/4W'   | '1206LF'  | 'CHIP'   | 'CS21506F200'(!)        = ''              | ''                 | 'CS21506F200'           |'R1206XM'| '(SMR1206AW)'                  | '1.5K'    | '1%'    | '1/4W'   | 'DISCRETE' | 'RES CHIP 1.5K 1/4W +-1%(1206)'                    | 'CHIPR1206'    | ''          | ''            | '20200518'
 '1.5K'       | '1%'      | '1/4W'   | '1206LF'  | 'EMPTY'  | 'CS21506F200'(!)        = ''              | ''                 | 'CS21506F200'           |'R1206XM'| '(SMR1206AW)'                  | '1.5K'    | '1%'    | '1/4W'   | 'IO'       | 'RES CHIP 1.5K 1/4W +-1%(1206)'                    | 'CHIPR1206'    | ''          | ''            | '20200518'
 '0.001'      | '1%'      | '3W'     | '2512LF'  | 'CHIP'   | 'CS+001DFR07'(!)        = ''              | ''                 | 'CS+001DFR07'           |'R2512XW'| '(SMR2512AW)'                  | '0.001'   | '1%'    | '3W'     | 'DISCRETE' | 'RES CHIP 0.001 3W +-1%(2512)YGO AEC'              | 'CHIPR2512'    | ''          | ''            | '20200527'
 '0.001'      | '1%'      | '3W'     | '2512LF'  | 'EMPTY'  | 'CS+001DFR07'(!)        = ''              | ''                 | 'CS+001DFR07'           |'R2512XW'| '(SMR2512AW)'                  | '0.001'   | '1%'    | '3W'     | 'IO'       | 'RES CHIP 0.001 3W +-1%(2512)YGO AEC'              | 'CHIPR2512'    | ''          | ''            | '20200527'
 '45.3K'      | '1%'      | '1/16W'  | '0402LF'  | 'CHIP'   | 'CS34532FB08'(!)        = ''              | ''                 | 'CS34532FB08'           |'R0402'| '(R0402-0201)'                 | '45.3K'   | '1%'    | '1/16W'  | 'DISCRETE' | 'RES CHIP 45.3K 1/16W +-1%(0402)EF'                | 'CHIPR0402'    | ''          | ''            | '20200602'
 '45.3K'      | '1%'      | '1/16W'  | '0402LF'  | 'EMPTY'  | 'CS34532FB08'(!)        = ''              | ''                 | 'CS34532FB08'           |'R0402'| '(R0402-0201)'                 | '45.3K'   | '1%'    | '1/16W'  | 'IO'       | 'RES CHIP 45.3K 1/16W +-1%(0402)EF'                | 'CHIPR0402'    | ''          | ''            | '20200602'
 '107K'       | '1%'      | '1/16W'  | '0402LF'  | 'CHIP'   | 'CS41072FB05'(!)        = ''              | ''                 | 'CS41072FB05'           |'R0402'| '(R0402-0201)'                 | '107K'    | '1%'    | '1/16W'  | 'DISCRETE' | 'RES CHIP 107K 1/16W +-1%(0402)EF'                 | 'CHIPR0402'    | ''          | ''            | '20200602'
 '107K'       | '1%'      | '1/16W'  | '0402LF'  | 'EMPTY'  | 'CS41072FB05'(!)        = ''              | ''                 | 'CS41072FB05'           |'R0402'| '(R0402-0201)'                 | '107K'    | '1%'    | '1/16W'  | 'IO'       | 'RES CHIP 107K 1/16W +-1%(0402)EF'                 | 'CHIPR0402'    | ''          | ''            | '20200602'
 '91K'        | '1%'      | '1/16W'  | '0402LF'  | 'CHIP'   | 'CS39102FB06'(!)        = ''              | ''                 | 'CS39102FB06'           |'R0402'| '(R0402-0201)'                 | '91K'     | '1%'    | '1/16W'  | 'DISCRETE' | 'RES CHIP 91K 1/16W +-1%(0402)EF'                  | 'CHIPR0402'    | ''          | ''            | '20200602'
 '91K'        | '1%'      | '1/16W'  | '0402LF'  | 'EMPTY'  | 'CS39102FB06'(!)        = ''              | ''                 | 'CS39102FB06'           |'R0402'| '(R0402-0201)'                 | '91K'     | '1%'    | '1/16W'  | 'IO'       | 'RES CHIP 91K 1/16W +-1%(0402)EF'                  | 'CHIPR0402'    | ''          | ''            | '20200602'
 '20.5K'      | '1%'      | '1/16W'  | '0402LF'  | 'CHIP'   | 'CS32052FB02'(!)        = 'End of Design' | 'Comp-Approve'     | 'CS32052FB02'           |'R0402'| '(R0402-0201)'                 | '20.5K'   | '1%'    | '1/16W'  | 'DISCRETE' | 'RES CHIP 20.5K 1/16W +-1%(0402)EF'                | 'CHIPR0402'    | ''          | ''            | '20200602'
 '20.5K'      | '1%'      | '1/16W'  | '0402LF'  | 'EMPTY'  | 'CS32052FB02'(!)        = 'End of Design' | 'Comp-Approve'     | 'CS32052FB02'           |'R0402'| '(R0402-0201)'                 | '20.5K'   | '1%'    | '1/16W'  | 'IO'       | 'RES CHIP 20.5K 1/16W +-1%(0402)EF'                | 'CHIPR0402'    | ''          | ''            | '20200602'
 '0.0003'     | '1%'      | '4W'     | '2725LF'  | 'CHIP'   | 'CS0000FFT10'(!)        = 'End of Design' | 'Comp-Approve'     | 'CS0000FFT10'           |'R2725XA'| '(SMR2725AW)'                  | '0.0003'  | '1%'    | '4W'     | 'DISCRETE' | 'RES CHIP 0.0003 4W +-1%(2725)ERO'                 | 'CHIPR2725'    | ''          | ''            | '20200609'
 '0.0003'     | '1%'      | '4W'     | '2725LF'  | 'EMPTY'  | 'CS0000FFT10'(!)        = 'End of Design' | 'Comp-Approve'     | 'CS0000FFT10'           |'R2725XA'| '(SMR2725AW)'                  | '0.0003'  | '1%'    | '4W'     | 'IO'       | 'RES CHIP 0.0003 4W +-1%(2725)ERO'                 | 'CHIPR2725'    | ''          | ''            | '20200609'
 '0.0003'     | '1%'      | '4W'     | '2725LF'  | 'CHIP'   | 'CS0000FFT09'(!)        = ''              | ''                 | 'CS0000FFT09'           |'R2725'| '(SMR2725AW)'                  | '0.0003'  | '1%'    | '4W'     | 'DISCRETE' | 'RES CHIP 0.0003 4W +-1%(2725)RLC'                 | 'CHIPR2725'    | ''          | ''            | '20200609'
 '0.0003'     | '1%'      | '4W'     | '2725LF'  | 'EMPTY'  | 'CS0000FFT09'(!)        = ''              | ''                 | 'CS0000FFT09'           |'R2725'| '(SMR2725AW)'                  | '0.0003'  | '1%'    | '4W'     | 'IO'       | 'RES CHIP 0.0003 4W +-1%(2725)RLC'                 | 'CHIPR2725'    | ''          | ''            | '20200609'
 '4.64K'      | '1%'      | '1/16W'  | '0402LF'  | 'CHIP'   | 'CS24642FB01'(!)        = 'End of Design' | 'Comp-Approve'     | 'CS24642FB01'           |'R0402'| '(R0402-0201)'                 | '4.64K'   | '1%'    | '1/16W'  | 'DISCRETE' | 'RES CHIP 4.64K 1/16W +-1%(0402)EF'                | 'CHIPR0402'    | ''          | ''            | '20200609'
 '4.64K'      | '1%'      | '1/16W'  | '0402LF'  | 'EMPTY'  | 'CS24642FB01'(!)        = 'End of Design' | 'Comp-Approve'     | 'CS24642FB01'           |'R0402'| '(R0402-0201)'                 | '4.64K'   | '1%'    | '1/16W'  | 'IO'       | 'RES CHIP 4.64K 1/16W +-1%(0402)EF'                | 'CHIPR0402'    | ''          | ''            | '20200609'
 '7.15K'      | '1%'      | '1/16W'  | '0402LF'  | 'CHIP'   | 'CS27152FB03'(!)        = 'End of Design' | 'Comp-Approve'     | 'CS27152FB03'           |'R0402'| '(R0402-0201)'                 | '7.15K'   | '1%'    | '1/16W'  | 'DISCRETE' | 'RES CHIP 7.15K 1/16W +-1%(0402)EF'                | 'CHIPR0402'    | ''          | ''            | '20200609'
 '7.15K'      | '1%'      | '1/16W'  | '0402LF'  | 'EMPTY'  | 'CS27152FB03'(!)        = 'End of Design' | 'Comp-Approve'     | 'CS27152FB03'           |'R0402'| '(R0402-0201)'                 | '7.15K'   | '1%'    | '1/16W'  | 'IO'       | 'RES CHIP 7.15K 1/16W +-1%(0402)EF'                | 'CHIPR0402'    | ''          | ''            | '20200609'
 '100'        | '5%'      | '1/10W'  | '0603LF'  | 'CHIP'   | 'CS11003J903'(!)        = ''              | ''                 | 'CS11003J903'           |'R0603_H24'| '(SMR0603AW)'                  | '100'     | '5%'    | '1/10W'  | 'DISCRETE' | 'RES CHIP 100 1/10W +-5%(0603)EF'                  | 'CHIPR0603'    | ''          | ''            | '20200609'
 '100'        | '5%'      | '1/10W'  | '0603LF'  | 'EMPTY'  | 'CS11003J903'(!)        = ''              | ''                 | 'CS11003J903'           |'R0603_H24'| '(SMR0603AW)'                  | '100'     | '5%'    | '1/10W'  | 'IO'       | 'RES CHIP 100 1/10W +-5%(0603)EF'                  | 'CHIPR0603'    | ''          | ''            | '20200609'
 '6.49K'      | '1%'      | '1/16W'  | '0402LF'  | 'CHIP'   | 'CS26492FB06'(!)        = 'End of Design' | 'Comp-Approve'     | 'CS26492FB06'           |'R0402'| '(R0402-0201)'                 | '6.49K'   | '1%'    | '1/16W'  | 'DISCRETE' | 'RES CHIP 6.49K 1/16W +-1%(0402)EF'                | 'CHIPR0402'    | ''          | ''            | '20200611'
 '6.49K'      | '1%'      | '1/16W'  | '0402LF'  | 'EMPTY'  | 'CS26492FB06'(!)        = 'End of Design' | 'Comp-Approve'     | 'CS26492FB06'           |'R0402'| '(R0402-0201)'                 | '6.49K'   | '1%'    | '1/16W'  | 'IO'       | 'RES CHIP 6.49K 1/16W +-1%(0402)EF'                | 'CHIPR0402'    | ''          | ''            | '20200611'
 '16.9K'      | '1%'      | '1/16W'  | '0402LF'  | 'CHIP'   | 'CS31692FB03'(!)        = 'End of Design' | 'Comp-Approve'     | 'CS31692FB03'           |'R0402'| '(R0402-0201)'                 | '16.9K'   | '1%'    | '1/16W'  | 'DISCRETE' | 'RES CHIP 16.9K 1/16W +-1%(0402)EF'                | 'CHIPR0402'    | ''          | ''            | '20200615'
 '16.9K'      | '1%'      | '1/16W'  | '0402LF'  | 'EMPTY'  | 'CS31692FB03'(!)        = 'End of Design' | 'Comp-Approve'     | 'CS31692FB03'           |'R0402'| '(R0402-0201)'                 | '16.9K'   | '1%'    | '1/16W'  | 'IO'       | 'RES CHIP 16.9K 1/16W +-1%(0402)EF'                | 'CHIPR0402'    | ''          | ''            | '20200615'
 '5.1'        | '1%'      | '1/16W'  | '0402LF'  | 'CHIP'   | 'CS-5102FB00'(!)        = 'End of Design' | 'Comp-Approve'     | 'CS-5102FB00'           |'R0402'| '(R0402-0201)'                 | '5.1'     | '1%'    | '1/16W'  | 'DISCRETE' | 'RES CHIP 5.1 1/16W +-1%(0402)'                    | 'CHIPR0402'    | ''          | ''            | '20200707'
 '5.1'        | '1%'      | '1/16W'  | '0402LF'  | 'EMPTY'  | 'CS-5102FB00'(!)        = 'End of Design' | 'Comp-Approve'     | 'CS-5102FB00'           |'R0402'| '(R0402-0201)'                 | '5.1'     | '1%'    | '1/16W'  | 'IO'       | 'RES CHIP 5.1 1/16W +-1%(0402)'                    | 'CHIPR0402'    | ''          | ''            | '20200707'
 '1'          | '1%'      | '1/4W'   | '0603LF'  | 'CHIP'   | 'CS-1006F900'(!)        = ''              | ''                 | 'CS-1006F900'           |'R0603'| '(SMR0603AW)'                  | '1'       | '1%'    | '1/4W'   | 'DISCRETE' | 'RES CHIP 1 1/4W+-1%(0603)SR'                      | 'CHIPR0603'    | ''          | ''            | '20200707'
 '1'          | '1%'      | '1/4W'   | '0603LF'  | 'EMPTY'  | 'CS-1006F900'(!)        = ''              | ''                 | 'CS-1006F900'           |'R0603'| '(SMR0603AW)'                  | '1'       | '1%'    | '1/4W'   | 'IO'       | 'RES CHIP 1 1/4W+-1%(0603)SR'                      | 'CHIPR0603'    | ''          | ''            | '20200707'
 '820'        | '1%'      | '1/16W'  | '0402LF'  | 'CHIP'   | 'CS18202FB00'(!)        = 'End of Design' | 'Comp-Approve'     | 'CS18202FB00'           |'R0402'| '(R0402-0201)'                 | '820'     | '1%'    | '1/16W'  | 'DISCRETE' | 'RES CHIP 820 1/16W +-1%(0402)'                    | 'CHIPR0402'    | ''          | ''            | '20200715'
 '820'        | '1%'      | '1/16W'  | '0402LF'  | 'EMPTY'  | 'CS18202FB00'(!)        = 'End of Design' | 'Comp-Approve'     | 'CS18202FB00'           |'R0402'| '(R0402-0201)'                 | '820'     | '1%'    | '1/16W'  | 'IO'       | 'RES CHIP 820 1/16W +-1%(0402)'                    | 'CHIPR0402'    | ''          | ''            | '20200715'
 '1'          | '5%'      | '1/2W'   | '1206LF'  | 'CHIP'   | 'CS-1007J200'(!)        = ''              | ''                 | 'CS-1007J200'           |'R1206XN'| '(SMR1206AW)'                  | '1'       | '5%'    | '1/2W'   | 'DISCRETE' | 'RES CHIP 1 1/2W+-5%(1206)SR'                      | 'CHIPR1206'    | ''          | ''            | '20200715'
 '1'          | '5%'      | '1/2W'   | '1206LF'  | 'EMPTY'  | 'CS-1007J200'(!)        = ''              | ''                 | 'CS-1007J200'           |'R1206XN'| '(SMR1206AW)'                  | '1'       | '5%'    | '1/2W'   | 'IO'       | 'RES CHIP 1 1/2W+-5%(1206)SR'                      | 'CHIPR1206'    | ''          | ''            | '20200715'
 '34.8K'      | '1%'      | '1/16W'  | '0402LF'  | 'CHIP'   | 'CS33482FB04'(!)        = ''              | ''                 | 'CS33482FB04'           |'R0402'| '(R0402-0201)'                 | '34.8K'   | '1%'    | '1/16W'  | 'DISCRETE' | 'RES CHIP 34.8K 1/16W +-1%(0402)EF'                | 'CHIPR0402'    | ''          | ''            | '20200728'
 '34.8K'      | '1%'      | '1/16W'  | '0402LF'  | 'EMPTY'  | 'CS33482FB04'(!)        = ''              | ''                 | 'CS33482FB04'           |'R0402'| '(R0402-0201)'                 | '34.8K'   | '1%'    | '1/16W'  | 'IO'       | 'RES CHIP 34.8K 1/16W +-1%(0402)EF'                | 'CHIPR0402'    | ''          | ''            | '20200728'
 '0.68'       | '1%'      | '1/10W'  | '0603LF'  | 'CHIP'   | 'CS+6803F900'(!)        = ''              | ''                 | 'CS+6803F900'           |'R0603_H24'| '(SMR0603AW)'                  | '0.68'    | '1%'    | '1/10W'  | 'DISCRETE' | 'RES CHIP 0.68 1/10W+-1%(0603)EF'                  | 'CHIPR0603'    | ''          | ''            | '20200803'
 '0.68'       | '1%'      | '1/10W'  | '0603LF'  | 'EMPTY'  | 'CS+6803F900'(!)        = ''              | ''                 | 'CS+6803F900'           |'R0603_H24'| '(SMR0603AW)'                  | '0.68'    | '1%'    | '1/10W'  | 'IO'       | 'RES CHIP 0.68 1/10W+-1%(0603)EF'                  | 'CHIPR0603'    | ''          | ''            | '20200803'
 '24K'        | '1%'      | '1/10W'  | '0603LF'  | 'CHIP'   | 'CS32403F911'(!)        = 'End of Design' | 'Comp-Approve'     | 'CS32403F911'           |'R0603'| '(SMR0603AW)'                  | '24K'     | '1%'    | '1/10W'  | 'DISCRETE' | 'RES CHIP 24K 1/10W +-1%(0603)'                    | 'CHIPR0603'    | ''          | ''            | '20200810'
 '24K'        | '1%'      | '1/10W'  | '0603LF'  | 'EMPTY'  | 'CS32403F911'(!)        = 'End of Design' | 'Comp-Approve'     | 'CS32403F911'           |'R0603'| '(SMR0603AW)'                  | '24K'     | '1%'    | '1/10W'  | 'IO'       | 'RES CHIP 24K 1/10W +-1%(0603)'                    | 'CHIPR0603'    | ''          | ''            | '20200810'
 '1.1K'       | '1%'      | '1/16W'  | '0402LF'  | 'CHIP'   | 'CS21102FB04'(!)        = 'End of Design' | 'Comp-Approve'     | 'CS21102FB04'           |'R0402'| '(R0402-0201)'                 | '1.1K'    | '1%'    | '1/16W'  | 'DISCRETE' | 'RES CHIP 1.1K 1/16W +-1% (0402)EF'                | 'CHIPR0402'    | ''          | ''            | '20200810'
 '1.1K'       | '1%'      | '1/16W'  | '0402LF'  | 'EMPTY'  | 'CS21102FB04'(!)        = 'End of Design' | 'Comp-Approve'     | 'CS21102FB04'           |'R0402'| '(R0402-0201)'                 | '1.1K'    | '1%'    | '1/16W'  | 'IO'       | 'RES CHIP 1.1K 1/16W +-1% (0402)EF'                | 'CHIPR0402'    | ''          | ''            | '20200810'
 '49.9'       | '1%'      | '1/4W'   | '1206LF'  | 'CHIP'   | 'CS04996F200'(!)        = ''              | ''                 | 'CS04996F200'           |'R1206XJ'| '(SMR1206AW)'                  | '49.9'    | '1%'    | '1/4W'   | 'DISCRETE' | 'RES CHIP 49.9 1/4W+-1%(1206)'                     | 'CHIPR1206'    | ''          | ''            | '20200811'
 '49.9'       | '1%'      | '1/4W'   | '1206LF'  | 'EMPTY'  | 'CS04996F200'(!)        = ''              | ''                 | 'CS04996F200'           |'R1206XJ'| '(SMR1206AW)'                  | '49.9'    | '1%'    | '1/4W'   | 'IO'       | 'RES CHIP 49.9 1/4W+-1%(1206)'                     | 'CHIPR1206'    | ''          | ''            | '20200811'
 '330'        | '1%'      | '1/8W'   | '0805LF'  | 'CHIP'   | 'CS13304FA00'(!)        = ''              | ''                 | 'CS13304FA00'           |'R0805_H26'| '(SMR0805AW)'                  | '330'     | '1%'    | '1/8W'   | 'DISCRETE' | 'RES CHIP 330 1/8W +-1%(0805)'                     | 'CHIPR0805'    | ''          | ''            | '20200811'
 '330'        | '1%'      | '1/8W'   | '0805LF'  | 'EMPTY'  | 'CS13304FA00'(!)        = ''              | ''                 | 'CS13304FA00'           |'R0805_H26'| '(SMR0805AW)'                  | '330'     | '1%'    | '1/8W'   | 'IO'       | 'RES CHIP 330 1/8W +-1%(0805)'                     | 'CHIPR0805'    | ''          | ''            | '20200811'
 '68K'        | '1%'      | '1/10W'  | '0603LF'  | 'CHIP'   | 'CS36803F917'(!)        = 'End of Design' | 'Comp-Approve'     | 'CS36803F917'           |'R0603'| '(SMR0603AW)'                  | '68K'     | '1%'    | '1/10W'  | 'DISCRETE' | 'RES CHIP 68K 1/10W +-1%(0603)'                    | 'CHIPR0603'    | ''          | ''            | '20200811'
 '68K'        | '1%'      | '1/10W'  | '0603LF'  | 'EMPTY'  | 'CS36803F917'(!)        = 'End of Design' | 'Comp-Approve'     | 'CS36803F917'           |'R0603'| '(SMR0603AW)'                  | '68K'     | '1%'    | '1/10W'  | 'IO'       | 'RES CHIP 68K 1/10W +-1%(0603)'                    | 'CHIPR0603'    | ''          | ''            | '20200811'
 '240K'       | '1%'      | '1/10W'  | '0603LF'  | 'CHIP'   | 'CS42403F913'(!)        = 'End of Design' | 'Comp-Approve'     | 'CS42403F913'           |'R0603'| '(SMR0603AW)'                  | '240K'    | '1%'    | '1/10W'  | 'DISCRETE' | 'RESISTOR CHIP 240K 1/10W,+-1%(0603)'              | 'CHIPR0603'    | ''          | ''            | '20200811'
 '240K'       | '1%'      | '1/10W'  | '0603LF'  | 'EMPTY'  | 'CS42403F913'(!)        = 'End of Design' | 'Comp-Approve'     | 'CS42403F913'           |'R0603'| '(SMR0603AW)'                  | '240K'    | '1%'    | '1/10W'  | 'IO'       | 'RESISTOR CHIP 240K 1/10W,+-1%(0603)'              | 'CHIPR0603'    | ''          | ''            | '20200811'
 '604'        | '1%'      | '1/4W'   | '1206LF'  | 'CHIP'   | 'CS16046F200'(!)        = ''              | ''                 | 'CS16046F200'           |'R1206XF'| '(SMR1206AW)'                  | '604'     | '1%'    | '1/4W'   | 'DISCRETE' | 'RES CHIP 604 1/4W +-1%(1206)'                     | 'CHIPR1206'    | ''          | ''            | '20200812'
 '604'        | '1%'      | '1/4W'   | '1206LF'  | 'EMPTY'  | 'CS16046F200'(!)        = ''              | ''                 | 'CS16046F200'           |'R1206XF'| '(SMR1206AW)'                  | '604'     | '1%'    | '1/4W'   | 'IO'       | 'RES CHIP 604 1/4W +-1%(1206)'                     | 'CHIPR1206'    | ''          | ''            | '20200812'
 '0.0005'     | '1%'      | '3W'     | '2512LF'  | 'CHIP'   | 'CS0000DFR02'(!)        = 'End of Design' | 'Comp-Approve'     | 'CS0000DFR02'           |'R2512XG'| '(SMR2512AW)'                  | '0.0005'  | '1%'    | '3W'     | 'DISCRETE' | 'RES CHIP 0.0005 3W +-1%(2512)EF'                  | 'CHIPR2512'    | ''          | ''            | '20200826'
 '0.0005'     | '1%'      | '3W'     | '2512LF'  | 'EMPTY'  | 'CS0000DFR02'(!)        = 'End of Design' | 'Comp-Approve'     | 'CS0000DFR02'           |'R2512XG'| '(SMR2512AW)'                  | '0.0005'  | '1%'    | '3W'     | 'IO'       | 'RES CHIP 0.0005 3W +-1%(2512)EF'                  | 'CHIPR2512'    | ''          | ''            | '20200826'
 '0.1'        | '1%'      | '1/8W'   | '0805LF'  | 'CHIP'   | 'CS+1004FA01'(!)        = ''              | ''                 | 'CS+1004FA01'           |'R0805'| '(SMR0805AW)'                  | '0.1'     | '1%'    | '1/8W'   | 'DISCRETE' | 'RES CHIP 0.1 1/8W +-1%(0805)'                     | 'CHIPR0805'    | ''          | ''            | '20200909'
 '0.1'        | '1%'      | '1/8W'   | '0805LF'  | 'EMPTY'  | 'CS+1004FA01'(!)        = ''              | ''                 | 'CS+1004FA01'           |'R0805'| '(SMR0805AW)'                  | '0.1'     | '1%'    | '1/8W'   | 'IO'       | 'RES CHIP 0.1 1/8W +-1%(0805)'                     | 'CHIPR0805'    | ''          | ''            | '20200909'
 '100'        | '5%'      | '1/2W'   | '1206LF'  | 'CHIP'   | 'CS11007J200'(!)        = ''              | ''                 | 'CS11007J200'           |'R1206XN'| '(SMR1206AW)'                  | '100'     | '5%'    | '1/2W'   | 'DISCRETE' | 'RES CHIP 100 1/2W+-5%(1206)SR'                    | 'CHIPR1206'    | ''          | ''            | '20200909'
 '100'        | '5%'      | '1/2W'   | '1206LF'  | 'EMPTY'  | 'CS11007J200'(!)        = ''              | ''                 | 'CS11007J200'           |'R1206XN'| '(SMR1206AW)'                  | '100'     | '5%'    | '1/2W'   | 'IO'       | 'RES CHIP 100 1/2W+-5%(1206)SR'                    | 'CHIPR1206'    | ''          | ''            | '20200909'
 '10'         | '0.1%'    | '1/16W'  | '0402LF'  | 'CHIP'   | 'CS01002BB00'(!)        = ''              | ''                 | 'CS01002BB00'           |'R0402'| '(R0402-0201)'                 | '10'      | '0.1%'  | '1/16W'  | 'DISCRETE' | 'RES CHIP 10 1/16W +-0.1%(0402)'                   | 'CHIPR0402'    | ''          | ''            | '20200915'
 '10'         | '0.1%'    | '1/16W'  | '0402LF'  | 'EMPTY'  | 'CS01002BB00'(!)        = ''              | ''                 | 'CS01002BB00'           |'R0402'| '(R0402-0201)'                 | '10'      | '0.1%'  | '1/16W'  | 'IO'       | 'RES CHIP 10 1/16W +-0.1%(0402)'                   | 'CHIPR0402'    | ''          | ''            | '20200915'
 '56K'        | '0.5%'    | '1/16W'  | '0402LF'  | 'CHIP'   | 'CS35602DB00'(!)        = ''              | ''                 | 'CS35602DB00'           |'R0402'| '(R0402-0201)'                 | '56K'     | '0.5%'  | '1/16W'  | 'DISCRETE' | 'RES CHIP 56K 1/16W +-0.5%(0402)'                  | 'CHIPR0402'    | ''          | ''            | '20200915'
 '56K'        | '0.5%'    | '1/16W'  | '0402LF'  | 'EMPTY'  | 'CS35602DB00'(!)        = ''              | ''                 | 'CS35602DB00'           |'R0402'| '(R0402-0201)'                 | '56K'     | '0.5%'  | '1/16W'  | 'IO'       | 'RES CHIP 56K 1/16W +-0.5%(0402)'                  | 'CHIPR0402'    | ''          | ''            | '20200915'
 '2.4K'       | '5%'      | '1/16W'  | '0402LF'  | 'CHIP'   | 'CS22402JB15'(!)        = 'End of Design' | 'Comp-Approve'     | 'CS22402JB15'           |'R0402'| '(R0402-0201)'                 | '2.4K'    | '5%'    | '1/16W'  | 'DISCRETE' | 'RES CHIP 2.4K 1/16W+-5%(0402)'                    | 'CHIPR0402'    | ''          | ''            | '20200917'
 '2.4K'       | '5%'      | '1/16W'  | '0402LF'  | 'EMPTY'  | 'CS22402JB15'(!)        = 'End of Design' | 'Comp-Approve'     | 'CS22402JB15'           |'R0402'| '(R0402-0201)'                 | '2.4K'    | '5%'    | '1/16W'  | 'IO'       | 'RES CHIP 2.4K 1/16W+-5%(0402)'                    | 'CHIPR0402'    | ''          | ''            | '20200917'
 '0.0005'     | '1%'      | '3W'     | '2512LF'  | 'CHIP'   | 'CS0000DFR17'(!)        = ''              | ''                 | 'CS0000DFR17'           |'R2512XX'| '(SMR2512AW)'                  | '0.0005'  | '1%'    | '3W'     | 'DISCRETE' | 'RES CHIP 0.0005 3W +-1%(2512)ERO'                 | 'CHIPR2512'    | ''          | ''            | '20200917'
 '0.0005'     | '1%'      | '3W'     | '2512LF'  | 'EMPTY'  | 'CS0000DFR17'(!)        = ''              | ''                 | 'CS0000DFR17'           |'R2512XX'| '(SMR2512AW)'                  | '0.0005'  | '1%'    | '3W'     | 'IO'       | 'RES CHIP 0.0005 3W +-1%(2512)ERO'                 | 'CHIPR2512'    | ''          | ''            | '20200917'
 '100'        | '5%'      | '1/4W'   | '0805LF'  | 'CHIP'   | 'CS11006JA00'(!)        = ''              | ''                 | 'CS11006JA00'           |'R0805_H26'| '(SMR0805AW)'                  | '100'     | '5%'    | '1/4W'   | 'DISCRETE' | 'RES CHIP 100 1/4W+-5%(0805)SR'                    | 'CHIPR0805'    | ''          | ''            | '20200921'
 '100'        | '5%'      | '1/4W'   | '0805LF'  | 'EMPTY'  | 'CS11006JA00'(!)        = ''              | ''                 | 'CS11006JA00'           |'R0805_H26'| '(SMR0805AW)'                  | '100'     | '5%'    | '1/4W'   | 'IO'       | 'RES CHIP 100 1/4W+-5%(0805)SR'                    | 'CHIPR0805'    | ''          | ''            | '20200921'
 '14.3K'      | '0.1%'    | '1/16W'  | '0402LF'  | 'CHIP'   | 'CS31432BB00'(!)        = ''              | ''                 | 'CS31432BB00'           |'R0402'| '(R0402-0201)'                 | '14.3K'   | '0.1%'  | '1/16W'  | 'DISCRETE' | 'RES CHIP 14.3K 1/16W +-0.1%(0402)'                | 'CHIPR0402'    | ''          | ''            | '20200930'
 '14.3K'      | '0.1%'    | '1/16W'  | '0402LF'  | 'EMPTY'  | 'CS31432BB00'(!)        = ''              | ''                 | 'CS31432BB00'           |'R0402'| '(R0402-0201)'                 | '14.3K'   | '0.1%'  | '1/16W'  | 'IO'       | 'RES CHIP 14.3K 1/16W +-0.1%(0402)'                | 'CHIPR0402'    | ''          | ''            | '20200930'
 '35.7K'      | '0.1%'    | '1/16W'  | '0402LF'  | 'CHIP'   | 'CS33572BB00'(!)        = ''              | ''                 | 'CS33572BB00'           |'R0402'| '(R0402-0201)'                 | '35.7K'   | '0.1%'  | '1/16W'  | 'DISCRETE' | 'RES CHIP 35.7K 1/16W  +-0.1%(0402)'               | 'CHIPR0402'    | ''          | ''            | '20201005'
 '35.7K'      | '0.1%'    | '1/16W'  | '0402LF'  | 'EMPTY'  | 'CS33572BB00'(!)        = ''              | ''                 | 'CS33572BB00'           |'R0402'| '(R0402-0201)'                 | '35.7K'   | '0.1%'  | '1/16W'  | 'IO'       | 'RES CHIP 35.7K 1/16W  +-0.1%(0402)'               | 'CHIPR0402'    | ''          | ''            | '20201005'
 '332K'       | '1%'      | '1/4W'   | '1206LF'  | 'CHIP'   | 'CS43326F200'(!)        = ''              | ''                 | 'CS43326F200'           |'R1206XI'| '(SMR1206AW)'                  | '332K'    | '1%'    | '1/4W'   | 'DISCRETE' | 'RES CHIP 332K 1/4W +-1%(1206)'                    | 'CHIPR1206'    | ''          | ''            | '20201006'
 '332K'       | '1%'      | '1/4W'   | '1206LF'  | 'EMPTY'  | 'CS43326F200'(!)        = ''              | ''                 | 'CS43326F200'           |'R1206XI'| '(SMR1206AW)'                  | '332K'    | '1%'    | '1/4W'   | 'IO'       | 'RES CHIP 332K 1/4W +-1%(1206)'                    | 'CHIPR1206'    | ''          | ''            | '20201006'
 '30.1K'      | '0.1%'    | '1/16W'  | '0402LF'  | 'CHIP'   | 'CS33012BB00'(!)        = 'End of Design' | 'Comp-Approve'     | 'CS33012BB00'           |'R0402'| '(R0402-0201)'                 | '30.1K'   | '0.1%'  | '1/16W'  | 'DISCRETE' | 'RES CHIP 30.1K 1/16W +-0.1% (0402)'               | 'CHIPR0402'    | ''          | ''            | '20201008'
 '30.1K'      | '0.1%'    | '1/16W'  | '0402LF'  | 'EMPTY'  | 'CS33012BB00'(!)        = 'End of Design' | 'Comp-Approve'     | 'CS33012BB00'           |'R0402'| '(R0402-0201)'                 | '30.1K'   | '0.1%'  | '1/16W'  | 'IO'       | 'RES CHIP 30.1K 1/16W +-0.1% (0402)'               | 'CHIPR0402'    | ''          | ''            | '20201008'
 '3.32K'      | '0.1%'    | '1/16W'  | '0402LF'  | 'CHIP'   | 'CS23322BB08'(!)        = 'End of Design' | 'Comp-Approve'     | 'CS23322BB08'           |'R0402'| '(R0402-0201)'                 | '3.32K'   | '0.1%'  | '1/16W'  | 'DISCRETE' | 'RES CHIP 3.32K 1/16W +-0.1% (0402)'               | 'CHIPR0402'    | ''          | ''            | '20201008'
 '3.32K'      | '0.1%'    | '1/16W'  | '0402LF'  | 'EMPTY'  | 'CS23322BB08'(!)        = 'End of Design' | 'Comp-Approve'     | 'CS23322BB08'           |'R0402'| '(R0402-0201)'                 | '3.32K'   | '0.1%'  | '1/16W'  | 'IO'       | 'RES CHIP 3.32K 1/16W +-0.1% (0402)'               | 'CHIPR0402'    | ''          | ''            | '20201008'
 '34.8K'      | '0.1%'    | '1/16W'  | '0402LF'  | 'CHIP'   | 'CS33482BB01'(!)        = ''              | ''                 | 'CS33482BB01'           |'R0402'| '(R0402-0201)'                 | '34.8K'   | '0.1%'  | '1/16W'  | 'DISCRETE' | 'RES CHIP 34.8K 1/16W +-0.1%(0402)'                | 'CHIPR0402'    | ''          | ''            | '20201110'
 '34.8K'      | '0.1%'    | '1/16W'  | '0402LF'  | 'EMPTY'  | 'CS33482BB01'(!)        = ''              | ''                 | 'CS33482BB01'           |'R0402'| '(R0402-0201)'                 | '34.8K'   | '0.1%'  | '1/16W'  | 'IO'       | 'RES CHIP 34.8K 1/16W +-0.1%(0402)'                | 'CHIPR0402'    | ''          | ''            | '20201110'
 '3.57K'      | '0.1%'    | '1/16W'  | '0402LF'  | 'CHIP'   | 'CS23572BB05'(!)        = ''              | ''                 | 'CS23572BB05'           |'R0402'| '(R0402-0201)'                 | '3.57K'   | '0.1%'  | '1/16W'  | 'DISCRETE' | 'RES CHIP 3.57K 1/16W +-0.1%(0402)'                | 'CHIPR0402'    | ''          | ''            | '20201110'
 '3.57K'      | '0.1%'    | '1/16W'  | '0402LF'  | 'EMPTY'  | 'CS23572BB05'(!)        = ''              | ''                 | 'CS23572BB05'           |'R0402'| '(R0402-0201)'                 | '3.57K'   | '0.1%'  | '1/16W'  | 'IO'       | 'RES CHIP 3.57K 1/16W +-0.1%(0402)'                | 'CHIPR0402'    | ''          | ''            | '20201110'
 '182'        | '1%'      | '1/16W'  | '0402LF'  | 'CHIP'   | 'CS11822FB02'(!)        = ''              | ''                 | 'CS11822FB02'           |'R0402'| '(R0402-0201)'                 | '182'     | '1%'    | '1/16W'  | 'DISCRETE' | 'RES CHIP 182 1/16W +-1%(0402)EF'                  | 'CHIPR0402'    | ''          | ''            | '20201112'
 '182'        | '1%'      | '1/16W'  | '0402LF'  | 'EMPTY'  | 'CS11822FB02'(!)        = ''              | ''                 | 'CS11822FB02'           |'R0402'| '(R0402-0201)'                 | '182'     | '1%'    | '1/16W'  | 'IO'       | 'RES CHIP 182 1/16W +-1%(0402)EF'                  | 'CHIPR0402'    | ''          | ''            | '20201112'
 '8.06K'      | '1%'      | '1/16W'  | '0402LF'  | 'CHIP'   | 'CS28062FB03'(!)        = 'End of Design' | 'Comp-Approve'     | 'CS28062FB03'           |'R0402'| '(R0402-0201)'                 | '8.06K'   | '1%'    | '1/16W'  | 'DISCRETE' | 'RES CHIP 8.06K 1/16W +-1%(0402)EF'                | 'CHIPR0402'    | ''          | ''            | '20201118'
 '8.06K'      | '1%'      | '1/16W'  | '0402LF'  | 'EMPTY'  | 'CS28062FB03'(!)        = 'End of Design' | 'Comp-Approve'     | 'CS28062FB03'           |'R0402'| '(R0402-0201)'                 | '8.06K'   | '1%'    | '1/16W'  | 'IO'       | 'RES CHIP 8.06K 1/16W +-1%(0402)EF'                | 'CHIPR0402'    | ''          | ''            | '20201118'
 '162'        | '1%'      | '1/16W'  | '0402LF'  | 'CHIP'   | 'CS11622FB15'(!)        = 'End of Design' | 'Comp-Approve'     | 'CS11622FB15'           |'R0402'| '(R0402-0201)'                 | '162'     | '1%'    | '1/16W'  | 'DISCRETE' | 'RES CHIP 162 1/16W +-1%(0402)'                    | 'CHIPR0402'    | ''          | ''            | '20201120'
 '162'        | '1%'      | '1/16W'  | '0402LF'  | 'EMPTY'  | 'CS11622FB15'(!)        = 'End of Design' | 'Comp-Approve'     | 'CS11622FB15'           |'R0402'| '(R0402-0201)'                 | '162'     | '1%'    | '1/16W'  | 'IO'       | 'RES CHIP 162 1/16W +-1%(0402)'                    | 'CHIPR0402'    | ''          | ''            | '20201120'
 '8.2'        | '1%'      | '1/16W'  | '0402LF'  | 'CHIP'   | 'CS-8202FB00'(!)        = ''              | ''                 | 'CS-8202FB00'           |'R0402'| '(R0402-0201)'                 | '8.2'     | '1%'    | '1/16W'  | 'DISCRETE' | 'RES CHIP 8.2 1/16W +-1%(0402)'                    | 'CHIPR0402'    | ''          | ''            | '20201123'
 '8.2'        | '1%'      | '1/16W'  | '0402LF'  | 'EMPTY'  | 'CS-8202FB00'(!)        = ''              | ''                 | 'CS-8202FB00'           |'R0402'| '(R0402-0201)'                 | '8.2'     | '1%'    | '1/16W'  | 'IO'       | 'RES CHIP 8.2 1/16W +-1%(0402)'                    | 'CHIPR0402'    | ''          | ''            | '20201123'
 '0.2'        | '1%'      | '1/10W'  | '0603LF'  | 'CHIP'   | 'CS+2003F900'(!)        = ''              | ''                 | 'CS+2003F900'           |'R0603_H24'| '(SMR0603AW)'                  | '0.2'     | '1%'    | '1/10W'  | 'DISCRETE' | 'RES CHIP 0.2 1/10W +-1%(0603)EF'                  | 'CHIPR0603'    | ''          | ''            | '20201201'
 '0.2'        | '1%'      | '1/10W'  | '0603LF'  | 'EMPTY'  | 'CS+2003F900'(!)        = ''              | ''                 | 'CS+2003F900'           |'R0603_H24'| '(SMR0603AW)'                  | '0.2'     | '1%'    | '1/10W'  | 'IO'       | 'RES CHIP 0.2 1/10W +-1%(0603)EF'                  | 'CHIPR0603'    | ''          | ''            | '20201201'
 '9.1K'       | '1%'      | '1/16W'  | '0402LF'  | 'CHIP'   | 'CS29102FB00'(!)        = ''              | ''                 | 'CS29102FB00'           |'R0402'| '(R0402-0201)'                 | '9.1K'    | '1%'    | '1/16W'  | 'DISCRETE' | 'RES CHIP 9.1K 1/16W +-1%(0402)EF'                 | 'CHIPR0402'    | ''          | ''            | '20201207'
 '9.1K'       | '1%'      | '1/16W'  | '0402LF'  | 'EMPTY'  | 'CS29102FB00'(!)        = ''              | ''                 | 'CS29102FB00'           |'R0402'| '(R0402-0201)'                 | '9.1K'    | '1%'    | '1/16W'  | 'IO'       | 'RES CHIP 9.1K 1/16W +-1%(0402)EF'                 | 'CHIPR0402'    | ''          | ''            | '20201207'
 '3.3K'       | '5%'      | '1/16W'  | '0402LF'  | 'CHIP'   | 'CS23302JB04'(!)        = 'End of Design' | 'Comp-Approve'     | 'CS23302JB04'           |'R0402'| '(R0402-0201)'                 | '3.3K'    | '5%'    | '1/16W'  | 'DISCRETE' | 'RES CHIP 3.3K 1/16W +-5%(0402)EF'                 | 'CHIPR0402'    | ''          | ''            | '20201208'
 '3.3K'       | '5%'      | '1/16W'  | '0402LF'  | 'EMPTY'  | 'CS23302JB04'(!)        = 'End of Design' | 'Comp-Approve'     | 'CS23302JB04'           |'R0402'| '(R0402-0201)'                 | '3.3K'    | '5%'    | '1/16W'  | 'IO'       | 'RES CHIP 3.3K 1/16W +-5%(0402)EF'                 | 'CHIPR0402'    | ''          | ''            | '20201208'
 '0.15'       | '1%'      | '1W'     | '1206LF'  | 'CHIP'   | 'CS+1508F201'(!)        = ''              | ''                 | 'CS+1508F201'           |'R1206XP'| '(SMR1206AW)'                  | '0.15'    | '1%'    | '1W'     | 'DISCRETE' | 'RES CHIP 0.15 1W +-1%(1206)'                      | 'CHIPR1206'    | ''          | ''            | '20201209'
 '0.15'       | '1%'      | '1W'     | '1206LF'  | 'EMPTY'  | 'CS+1508F201'(!)        = ''              | ''                 | 'CS+1508F201'           |'R1206XP'| '(SMR1206AW)'                  | '0.15'    | '1%'    | '1W'     | 'IO'       | 'RES CHIP 0.15 1W +-1%(1206)'                      | 'CHIPR1206'    | ''          | ''            | '20201209'
 '6.34K'      | '0.1%'    | '1/16W'  | '0402LF'  | 'CHIP'   | 'CS26342BB00'(!)        = ''              | ''                 | 'CS26342BB00'           |'R0402'| '(R0402-0201)'                 | '6.34K'   | '0.1%'  | '1/16W'  | 'DISCRETE' | 'RES CHIP 6.34K 1/16W +-0.1%(0402)'                | 'CHIPR0402'    | ''          | ''            | '20201224'
 '6.34K'      | '0.1%'    | '1/16W'  | '0402LF'  | 'EMPTY'  | 'CS26342BB00'(!)        = ''              | ''                 | 'CS26342BB00'           |'R0402'| '(R0402-0201)'                 | '6.34K'   | '0.1%'  | '1/16W'  | 'IO'       | 'RES CHIP 6.34K 1/16W +-0.1%(0402)'                | 'CHIPR0402'    | ''          | ''            | '20201224'
 '9.09K'      | '0.1%'    | '1/16W'  | '0402LF'  | 'CHIP'   | 'CS29092BB01'(!)        = ''              | ''                 | 'CS29092BB01'           |'R0402'| '(R0402-0201)'                 | '9.09K'   | '0.1%'  | '1/16W'  | 'DISCRETE' | 'RES CHIP 9.09K 1/16W +-0.1%(0402)'                | 'CHIPR0402'    | ''          | ''            | '20201224'
 '9.09K'      | '0.1%'    | '1/16W'  | '0402LF'  | 'EMPTY'  | 'CS29092BB01'(!)        = ''              | ''                 | 'CS29092BB01'           |'R0402'| '(R0402-0201)'                 | '9.09K'   | '0.1%'  | '1/16W'  | 'IO'       | 'RES CHIP 9.09K 1/16W +-0.1%(0402)'                | 'CHIPR0402'    | ''          | ''            | '20201224'
 '2.21K'      | '0.1%'    | '1/16W'  | '0402LF'  | 'CHIP'   | 'CS22212BB01'(!)        = 'End of Design' | 'Comp-Approve'     | 'CS22212BB01'           |'R0402'| '(R0402-0201)'                 | '2.21K'   | '0.1%'  | '1/16W'  | 'DISCRETE' | 'RES CHIP 2.21K 1/16W +-0.1%(0402)'                | 'CHIPR0402'    | ''          | ''            | '20201225'
 '2.21K'      | '0.1%'    | '1/16W'  | '0402LF'  | 'EMPTY'  | 'CS22212BB01'(!)        = 'End of Design' | 'Comp-Approve'     | 'CS22212BB01'           |'R0402'| '(R0402-0201)'                 | '2.21K'   | '0.1%'  | '1/16W'  | 'IO'       | 'RES CHIP 2.21K 1/16W +-0.1%(0402)'                | 'CHIPR0402'    | ''          | ''            | '20201225'
 '4.32K'      | '0.1%'    | '1/16W'  | '0402LF'  | 'CHIP'   | 'CS24322BB01'(!)        = ''              | ''                 | 'CS24322BB01'           |'R0402'| '(R0402-0201)'                 | '4.32K'   | '0.1%'  | '1/16W'  | 'DISCRETE' | 'RES CHIP 4.32K 1/16W +-0.1%(0402)'                | 'CHIPR0402'    | ''          | ''            | '20201225'
 '4.32K'      | '0.1%'    | '1/16W'  | '0402LF'  | 'EMPTY'  | 'CS24322BB01'(!)        = ''              | ''                 | 'CS24322BB01'           |'R0402'| '(R0402-0201)'                 | '4.32K'   | '0.1%'  | '1/16W'  | 'IO'       | 'RES CHIP 4.32K 1/16W +-0.1%(0402)'                | 'CHIPR0402'    | ''          | ''            | '20201225'
 '16.5K'      | '0.1%'    | '1/16W'  | '0402LF'  | 'CHIP'   | 'CS31652BB00'(!)        = ''              | ''                 | 'CS31652BB00'           |'R0402'| '(R0402-0201)'                 | '16.5K'   | '0.1%'  | '1/16W'  | 'DISCRETE' | 'RES CHIP 16.5K 1/16W +-0.1%(0402)'                | 'CHIPR0402'    | ''          | ''            | '20201225'
 '16.5K'      | '0.1%'    | '1/16W'  | '0402LF'  | 'EMPTY'  | 'CS31652BB00'(!)        = ''              | ''                 | 'CS31652BB00'           |'R0402'| '(R0402-0201)'                 | '16.5K'   | '0.1%'  | '1/16W'  | 'IO'       | 'RES CHIP 16.5K 1/16W +-0.1%(0402)'                | 'CHIPR0402'    | ''          | ''            | '20201225'
 '4.12K'      | '0.1%'    | '1/16W'  | '0402LF'  | 'CHIP'   | 'CS24122BB01'(!)        = ''              | ''                 | 'CS24122BB01'           |'R0402'| '(R0402-0201)'                 | '4.12K'   | '0.1%'  | '1/16W'  | 'DISCRETE' | 'RES CHIP 4.12K 1/16W  +-0.1%(0402)'               | 'CHIPR0402'    | ''          | ''            | '20201225'
 '4.12K'      | '0.1%'    | '1/16W'  | '0402LF'  | 'EMPTY'  | 'CS24122BB01'(!)        = ''              | ''                 | 'CS24122BB01'           |'R0402'| '(R0402-0201)'                 | '4.12K'   | '0.1%'  | '1/16W'  | 'IO'       | 'RES CHIP 4.12K 1/16W  +-0.1%(0402)'               | 'CHIPR0402'    | ''          | ''            | '20201225'
 '2.2'        | '1%'      | '1/2W'   | '1206LF'  | 'CHIP'   | 'CS-2207F200'(!)        = ''              | ''                 | 'CS-2207F200'           |'R1206XF'| '(SMR1206AW)'                  | '2.2'     | '1%'    | '1/2W'   | 'DISCRETE' | 'RES CHIP 2.2 1/2W +-1%(1206)'                     | 'CHIPR1206'    | ''          | ''            | '20210105'
 '2.2'        | '1%'      | '1/2W'   | '1206LF'  | 'EMPTY'  | 'CS-2207F200'(!)        = ''              | ''                 | 'CS-2207F200'           |'R1206XF'| '(SMR1206AW)'                  | '2.2'     | '1%'    | '1/2W'   | 'IO'       | 'RES CHIP 2.2 1/2W +-1%(1206)'                     | 'CHIPR1206'    | ''          | ''            | '20210105'
 '200'        | '1%'      | '1/8W'   | '0402LF'  | 'CHIP'   | 'CS12004FB00'(!)        = ''              | ''                 | 'CS12004FB00'           |'R0402'| '(R0402-0201)'                 | '200'     | '1%'    | '1/8W'   | 'DISCRETE' | 'RES CHIP 200 1/8W +-1%(0402)SR'                   | 'CHIPR0402'    | ''          | ''            | '20210112'
 '200'        | '1%'      | '1/8W'   | '0402LF'  | 'EMPTY'  | 'CS12004FB00'(!)        = ''              | ''                 | 'CS12004FB00'           |'R0402'| '(R0402-0201)'                 | '200'     | '1%'    | '1/8W'   | 'IO'       | 'RES CHIP 200 1/8W +-1%(0402)SR'                   | 'CHIPR0402'    | ''          | ''            | '20210112'
 '47K'        | '0.1%'    | '1/16W'  | '0402LF'  | 'CHIP'   | 'CS34702BB03'(!)        = ''              | ''                 | 'CS34702BB03'           |'R0402'| '(R0402-0201)'                 | '47K'     | '0.1%'  | '1/16W'  | 'DISCRETE' | 'RES CHIP 47K 1/16W +-0.1%(0402)YGO'               | 'CHIPR0402'    | ''          | ''            | '20210120'
 '47K'        | '0.1%'    | '1/16W'  | '0402LF'  | 'EMPTY'  | 'CS34702BB03'(!)        = ''              | ''                 | 'CS34702BB03'           |'R0402'| '(R0402-0201)'                 | '47K'     | '0.1%'  | '1/16W'  | 'IO'       | 'RES CHIP 47K 1/16W +-0.1%(0402)YGO'               | 'CHIPR0402'    | ''          | ''            | '20210120'
 '15K'        | '0.1%'    | '1/16W'  | '0402LF'  | 'CHIP'   | 'CS31502BB01'(!)        = ''              | ''                 | 'CS31502BB01'           |'R0402'| '(R0402-0201)'                 | '15K'     | '0.1%'  | '1/16W'  | 'DISCRETE' | 'RES CHIP 15K 1/16W +-0.1%(0402)'                  | 'CHIPR0402'    | ''          | ''            | '20210120'
 '15K'        | '0.1%'    | '1/16W'  | '0402LF'  | 'EMPTY'  | 'CS31502BB01'(!)        = ''              | ''                 | 'CS31502BB01'           |'R0402'| '(R0402-0201)'                 | '15K'     | '0.1%'  | '1/16W'  | 'IO'       | 'RES CHIP 15K 1/16W +-0.1%(0402)'                  | 'CHIPR0402'    | ''          | ''            | '20210120'
 '26.1K'      | '0.1%'    | '1/16W'  | '0402LF'  | 'CHIP'   | 'CS32612BB01'(!)        = ''              | ''                 | 'CS32612BB01'           |'R0402'| '(R0402-0201)'                 | '26.1K'   | '0.1%'  | '1/16W'  | 'DISCRETE' | 'RES CHIP 26.1K 1/16W +-0.1%(0402)'                | 'CHIPR0402'    | ''          | ''            | '20210121'
 '26.1K'      | '0.1%'    | '1/16W'  | '0402LF'  | 'EMPTY'  | 'CS32612BB01'(!)        = ''              | ''                 | 'CS32612BB01'           |'R0402'| '(R0402-0201)'                 | '26.1K'   | '0.1%'  | '1/16W'  | 'IO'       | 'RES CHIP 26.1K 1/16W +-0.1%(0402)'                | 'CHIPR0402'    | ''          | ''            | '20210121'
 '86.6K'      | '0.1%'    | '1/16W'  | '0402LF'  | 'CHIP'   | 'CS38662BB00'(!)        = ''              | ''                 | 'CS38662BB00'           |'R0402'| '(R0402-0201)'                 | '86.6K'   | '0.1%'  | '1/16W'  | 'DISCRETE' | 'RES CHIP 86.6K 1/16W +-0.1%(0402)'                | 'CHIPR0402'    | ''          | ''            | '20210121'
 '86.6K'      | '0.1%'    | '1/16W'  | '0402LF'  | 'EMPTY'  | 'CS38662BB00'(!)        = ''              | ''                 | 'CS38662BB00'           |'R0402'| '(R0402-0201)'                 | '86.6K'   | '0.1%'  | '1/16W'  | 'IO'       | 'RES CHIP 86.6K 1/16W +-0.1%(0402)'                | 'CHIPR0402'    | ''          | ''            | '20210121'
 '7.32K'      | '0.1%'    | '1/16W'  | '0402LF'  | 'CHIP'   | 'CS27322BB08'(!)        = ''              | ''                 | 'CS27322BB08'           |'R0402'| '(R0402-0201)'                 | '7.32K'   | '0.1%'  | '1/16W'  | 'DISCRETE' | 'RES CHIP 7.32K 1/16W +-0.1% (0402)'               | 'CHIPR0402'    | ''          | ''            | '20210121'
 '7.32K'      | '0.1%'    | '1/16W'  | '0402LF'  | 'EMPTY'  | 'CS27322BB08'(!)        = ''              | ''                 | 'CS27322BB08'           |'R0402'| '(R0402-0201)'                 | '7.32K'   | '0.1%'  | '1/16W'  | 'IO'       | 'RES CHIP 7.32K 1/16W +-0.1% (0402)'               | 'CHIPR0402'    | ''          | ''            | '20210121'
 '31.6K'      | '0.1%'    | '1/16W'  | '0402LF'  | 'CHIP'   | 'CS33162BB03'(!)        = ''              | ''                 | 'CS33162BB03'           |'R0402'| '(R0402-0201)'                 | '31.6K'   | '0.1%'  | '1/16W'  | 'DISCRETE' | 'RES CHIP 31.6K 1/16W +-0.1%(0402)'                | 'CHIPR0402'    | ''          | ''            | '20210122'
 '31.6K'      | '0.1%'    | '1/16W'  | '0402LF'  | 'EMPTY'  | 'CS33162BB03'(!)        = ''              | ''                 | 'CS33162BB03'           |'R0402'| '(R0402-0201)'                 | '31.6K'   | '0.1%'  | '1/16W'  | 'IO'       | 'RES CHIP 31.6K 1/16W +-0.1%(0402)'                | 'CHIPR0402'    | ''          | ''            | '20210122'
 '36K'        | '0.1%'    | '1/16W'  | '0402LF'  | 'CHIP'   | 'CS33602BB00'(!)        = 'End of Design' | 'Comp-Approve'     | 'CS33602BB00'           |'R0402'| '(R0402-0201)'                 | '36K'     | '0.1%'  | '1/16W'  | 'DISCRETE' | 'RES CHIP 36K 1/16W +-0.1%(0402)'                  | 'CHIPR0402'    | ''          | ''            | '20210122'
 '36K'        | '0.1%'    | '1/16W'  | '0402LF'  | 'EMPTY'  | 'CS33602BB00'(!)        = 'End of Design' | 'Comp-Approve'     | 'CS33602BB00'           |'R0402'| '(R0402-0201)'                 | '36K'     | '0.1%'  | '1/16W'  | 'IO'       | 'RES CHIP 36K 1/16W +-0.1%(0402)'                  | 'CHIPR0402'    | ''          | ''            | '20210122'
 '1.15K'      | '0.1%'    | '1/16W'  | '0402LF'  | 'CHIP'   | 'CS21152BB00'(!)        = ''              | ''                 | 'CS21152BB00'           |'R0402'| '(R0402-0201)'                 | '1.15K'   | '0.1%'  | '1/16W'  | 'DISCRETE' | 'RES CHIP 1.15K 1/16W +-0.1%(0402)'                | 'CHIPR0402'    | ''          | ''            | '20210302'
 '1.15K'      | '0.1%'    | '1/16W'  | '0402LF'  | 'EMPTY'  | 'CS21152BB00'(!)        = ''              | ''                 | 'CS21152BB00'           |'R0402'| '(R0402-0201)'                 | '1.15K'   | '0.1%'  | '1/16W'  | 'IO'       | 'RES CHIP 1.15K 1/16W +-0.1%(0402)'                | 'CHIPR0402'    | ''          | ''            | '20210302'
 '1.02K'      | '0.1%'    | '1/16W'  | '0402LF'  | 'CHIP'   | 'CS21022BB00'(!)        = ''              | ''                 | 'CS21022BB00'           |'R0402'| '(R0402-0201)'                 | '1.02K'   | '0.1%'  | '1/16W'  | 'DISCRETE' | 'RES CHIP 1.02K 1/16W +-0.1%(0402)'                | 'CHIPR0402'    | ''          | ''            | '20210303'
 '1.02K'      | '0.1%'    | '1/16W'  | '0402LF'  | 'EMPTY'  | 'CS21022BB00'(!)        = ''              | ''                 | 'CS21022BB00'           |'R0402'| '(R0402-0201)'                 | '1.02K'   | '0.1%'  | '1/16W'  | 'IO'       | 'RES CHIP 1.02K 1/16W +-0.1%(0402)'                | 'CHIPR0402'    | ''          | ''            | '20210303'
 '16.2K'      | '0.1%'    | '1/16W'  | '0402LF'  | 'CHIP'   | 'CS31622BB00'(!)        = ''              | ''                 | 'CS31622BB00'           |'R0402'| '(R0402-0201)'                 | '16.2K'   | '0.1%'  | '1/16W'  | 'DISCRETE' | 'RES CHIP 16.2K 1/16W 0.1% (0402)'                 | 'CHIPR0402'    | ''          | ''            | '20210309'
 '16.2K'      | '0.1%'    | '1/16W'  | '0402LF'  | 'EMPTY'  | 'CS31622BB00'(!)        = ''              | ''                 | 'CS31622BB00'           |'R0402'| '(R0402-0201)'                 | '16.2K'   | '0.1%'  | '1/16W'  | 'IO'       | 'RES CHIP 16.2K 1/16W 0.1% (0402)'                 | 'CHIPR0402'    | ''          | ''            | '20210309'
 '5.76K'      | '0.1%'    | '1/16W'  | '0402LF'  | 'CHIP'   | 'CS25762BB00'(!)        = 'End of Design' | 'Comp-Approve'     | 'CS25762BB00'           |'R0402'| '(R0402-0201)'                 | '5.76K'   | '0.1%'  | '1/16W'  | 'DISCRETE' | 'RES CHIP 5.76K 1/16W +-0.1%(0402)'                | 'CHIPR0402'    | ''          | ''            | '20210310'
 '5.76K'      | '0.1%'    | '1/16W'  | '0402LF'  | 'EMPTY'  | 'CS25762BB00'(!)        = 'End of Design' | 'Comp-Approve'     | 'CS25762BB00'           |'R0402'| '(R0402-0201)'                 | '5.76K'   | '0.1%'  | '1/16W'  | 'IO'       | 'RES CHIP 5.76K 1/16W +-0.1%(0402)'                | 'CHIPR0402'    | ''          | ''            | '20210310'
 '1'          | '1%'      | '1/4W'   | '0603LF'  | 'CHIP'   | 'CS-1006F903'(!)        = ''              | ''                 | 'CS-1006F903'           |'R0603'| '(SMR0603AW)'                  | '1'       | '1%'    | '1/4W'   | 'DISCRETE' | 'RES CHIP 1 1/4W+-1%(0603)SR RLC'                  | 'CHIPR0603'    | ''          | ''            | '20210318'
 '1'          | '1%'      | '1/4W'   | '0603LF'  | 'EMPTY'  | 'CS-1006F903'(!)        = ''              | ''                 | 'CS-1006F903'           |'R0603'| '(SMR0603AW)'                  | '1'       | '1%'    | '1/4W'   | 'IO'       | 'RES CHIP 1 1/4W+-1%(0603)SR RLC'                  | 'CHIPR0603'    | ''          | ''            | '20210318'
 '3.3'        | '1%'      | '1/4W'   | '0603LF'  | 'CHIP'   | 'CS-3306F903'(!)        = ''              | ''                 | 'CS-3306F903'           |'R0603'| '(SMR0603AW)'                  | '3.3'     | '1%'    | '1/4W'   | 'DISCRETE' | 'RES CHIP 3.3 1/4W+-1%(0603)SR RLC'                | 'CHIPR0603'    | ''          | ''            | '20210318'
 '3.3'        | '1%'      | '1/4W'   | '0603LF'  | 'EMPTY'  | 'CS-3306F903'(!)        = ''              | ''                 | 'CS-3306F903'           |'R0603'| '(SMR0603AW)'                  | '3.3'     | '1%'    | '1/4W'   | 'IO'       | 'RES CHIP 3.3 1/4W+-1%(0603)SR RLC'                | 'CHIPR0603'    | ''          | ''            | '20210318'
 '75K'        | '1%'      | '1/10W'  | '0603LF'  | 'CHIP'   | 'CS37503F904'(!)        = ''              | ''                 | 'CS37503F904'           |'R0603_H24'| '(SMR0603AW)'                  | '75K'     | '1%'    | '1/10W'  | 'DISCRETE' | 'RES CHIP 75K 1/10W +-1%(0603)WTC'                 | 'CHIPR0603'    | ''          | ''            | '20210330'
 '75K'        | '1%'      | '1/10W'  | '0603LF'  | 'EMPTY'  | 'CS37503F904'(!)        = ''              | ''                 | 'CS37503F904'           |'R0603_H24'| '(SMR0603AW)'                  | '75K'     | '1%'    | '1/10W'  | 'IO'       | 'RES CHIP 75K 1/10W +-1%(0603)WTC'                 | 'CHIPR0603'    | ''          | ''            | '20210330'
 '174K'       | '1%'      | '1/10W'  | '0603LF'  | 'CHIP'   | 'CS41743F910'(!)        = ''              | ''                 | 'CS41743F910'           |'R0603_H24'| '(SMR0603AW)'                  | '174K'    | '1%'    | '1/10W'  | 'DISCRETE' | 'RESISTOR CHIP 174K 1/10W+-1%(0603)'               | 'CHIPR0603'    | ''          | ''            | '20210330'
 '174K'       | '1%'      | '1/10W'  | '0603LF'  | 'EMPTY'  | 'CS41743F910'(!)        = ''              | ''                 | 'CS41743F910'           |'R0603_H24'| '(SMR0603AW)'                  | '174K'    | '1%'    | '1/10W'  | 'IO'       | 'RESISTOR CHIP 174K 1/10W+-1%(0603)'               | 'CHIPR0603'    | ''          | ''            | '20210330'
 '174K'       | '0.5%'    | '1/10W'  | '0603LF'  | 'CHIP'   | 'CS41743D909'(!)        = ''              | ''                 | 'CS41743D909'           |'R0603_H24'| '(SMR0603AW)'                  | '174K'    | '0.5%'  | '1/10W'  | 'DISCRETE' | 'RES CHIP 174K 1/10W +-0.5%(0603)EP'               | 'CHIPR0603'    | ''          | ''            | '20210330'
 '174K'       | '0.5%'    | '1/10W'  | '0603LF'  | 'EMPTY'  | 'CS41743D909'(!)        = ''              | ''                 | 'CS41743D909'           |'R0603_H24'| '(SMR0603AW)'                  | '174K'    | '0.5%'  | '1/10W'  | 'IO'       | 'RES CHIP 174K 1/10W +-0.5%(0603)EP'               | 'CHIPR0603'    | ''          | ''            | '20210330'
 '75K'        | '0.5%'    | '1/10W'  | '0603LF'  | 'CHIP'   | 'CS37503D916'(!)        = ''              | ''                 | 'CS37503D916'           |'R0603'| '(SMR0603AW)'                  | '75K'     | '0.5%'  | '1/10W'  | 'DISCRETE' | 'RESISTOR CHIP 75K 1/10W+-0.5%(0603)'              | 'CHIPR0603'    | ''          | ''            | '20210330'
 '75K'        | '0.5%'    | '1/10W'  | '0603LF'  | 'EMPTY'  | 'CS37503D916'(!)        = ''              | ''                 | 'CS37503D916'           |'R0603'| '(SMR0603AW)'                  | '75K'     | '0.5%'  | '1/10W'  | 'IO'       | 'RESISTOR CHIP 75K 1/10W+-0.5%(0603)'              | 'CHIPR0603'    | ''          | ''            | '20210330'
 '681'        | '1%'      | '1/16W'  | '0402LF'  | 'CHIP'   | 'CS16812FB20'(!)        = 'End of Design' | 'Comp-Approve'     | 'CS16812FB20'           |'R0402'| '(R0402-0201)'                 | '681'     | '1%'    | '1/16W'  | 'DISCRETE' | 'RES CHIP 681 1/16W +-1%(0402)'                    | 'CHIPR0402'    | ''          | ''            | '20210330'
 '681'        | '1%'      | '1/16W'  | '0402LF'  | 'EMPTY'  | 'CS16812FB20'(!)        = 'End of Design' | 'Comp-Approve'     | 'CS16812FB20'           |'R0402'| '(R0402-0201)'                 | '681'     | '1%'    | '1/16W'  | 'IO'       | 'RES CHIP 681 1/16W +-1%(0402)'                    | 'CHIPR0402'    | ''          | ''            | '20210330'
 '0.47'       | '1%'      | '1/10W'  | '0603LF'  | 'CHIP'   | 'CS+4703F905'(!)        = ''              | ''                 | 'CS+4703F905'           |'R0603'| '(SMR0603AW)'                  | '0.47'    | '1%'    | '1/10W'  | 'DISCRETE' | 'RES CHIP 0.47 1/10W+-1%(0603)'                    | 'CHIPR0603'    | ''          | ''            | '20210330'
 '0.47'       | '1%'      | '1/10W'  | '0603LF'  | 'EMPTY'  | 'CS+4703F905'(!)        = ''              | ''                 | 'CS+4703F905'           |'R0603'| '(SMR0603AW)'                  | '0.47'    | '1%'    | '1/10W'  | 'IO'       | 'RES CHIP 0.47 1/10W+-1%(0603)'                    | 'CHIPR0603'    | ''          | ''            | '20210330'
 '750'        | '1%'      | '1/10W'  | '0603LF'  | 'CHIP'   | 'CS17503F902'(!)        = 'End of Design' | 'Comp-Approve'     | 'CS17503F902'           |'R0603'| '(SMR0603AW)'                  | '750'     | '1%'    | '1/10W'  | 'DISCRETE' | 'RES CHIP 750 1/10W +-1%(0603)EF'                  | 'CHIPR0603'    | ''          | ''            | '20210407'
 '750'        | '1%'      | '1/10W'  | '0603LF'  | 'EMPTY'  | 'CS17503F902'(!)        = 'End of Design' | 'Comp-Approve'     | 'CS17503F902'           |'R0603'| '(SMR0603AW)'                  | '750'     | '1%'    | '1/10W'  | 'IO'       | 'RES CHIP 750 1/10W +-1%(0603)EF'                  | 'CHIPR0603'    | ''          | ''            | '20210407'
 '0.003'      | '1%'      | '3W'     | '2512LF'  | 'CHIP'   | 'CS+003DFR03'(!)        = ''              | ''                 | 'CS+003DFR03'           |'R2512XY'| '(SMR2512AW)'                  | '0.003'   | '1%'    | '3W'     | 'DISCRETE' | 'RES CHIP 0.003 3W +-1%(2512)RLC'                  | 'CHIPR2512'    | ''          | ''            | '20210419'
 '0.003'      | '1%'      | '3W'     | '2512LF'  | 'EMPTY'  | 'CS+003DFR03'(!)        = ''              | ''                 | 'CS+003DFR03'           |'R2512XY'| '(SMR2512AW)'                  | '0.003'   | '1%'    | '3W'     | 'IO'       | 'RES CHIP 0.003 3W +-1%(2512)RLC'                  | 'CHIPR2512'    | ''          | ''            | '20210419'
 '0.0005'     | '1%'      | '3W'     | '2512LF'  | 'CHIP'   | 'CS0000DFR18'(!)        = ''              | ''                 | 'CS0000DFR18'           |'R2512XG'| '(SMR2512AW)'                  | '0.0005'  | '1%'    | '3W'     | 'DISCRETE' | 'RES CHIP 0.0005 3W +-1%(2512)RLC'                 | 'CHIPR2512'    | ''          | ''            | '20210428'
 '0.0005'     | '1%'      | '3W'     | '2512LF'  | 'EMPTY'  | 'CS0000DFR18'(!)        = ''              | ''                 | 'CS0000DFR18'           |'R2512XG'| '(SMR2512AW)'                  | '0.0005'  | '1%'    | '3W'     | 'IO'       | 'RES CHIP 0.0005 3W +-1%(2512)RLC'                 | 'CHIPR2512'    | ''          | ''            | '20210428'
 '0.001'      | '1%'      | '3W'     | '2512LF'  | 'CHIP'   | 'CS+001DFR10'(!)        = ''              | ''                 | 'CS+001DFR10'           |'R2512XJ'| '(SMR2512AW)'                  | '0.001'   | '1%'    | '3W'     | 'DISCRETE' | 'RES CHIP 0.001 3W +-1%(2512)RLC'                  | 'CHIPR2512'    | ''          | ''            | '20210428'
 '0.001'      | '1%'      | '3W'     | '2512LF'  | 'EMPTY'  | 'CS+001DFR10'(!)        = ''              | ''                 | 'CS+001DFR10'           |'R2512XJ'| '(SMR2512AW)'                  | '0.001'   | '1%'    | '3W'     | 'IO'       | 'RES CHIP 0.001 3W +-1%(2512)RLC'                  | 'CHIPR2512'    | ''          | ''            | '20210428'
 '0.68'       | '1%'      | '1/6W'   | '0402LF'  | 'CHIP'   | 'CS+6802FB00'(!)        = ''              | ''                 | 'CS+6802FB00'           |'R0402_H20'| '(R0402-0201_H20)'             | '0.68'    | '1%'    | '1/6W'   | 'DISCRETE' | 'RES CHIP 0.68 OHM 1/6W +-1%(0402)'                | 'CHIPR0402'    | ''          | ''            | '20210507'
 '0.68'       | '1%'      | '1/6W'   | '0402LF'  | 'EMPTY'  | 'CS+6802FB00'(!)        = ''              | ''                 | 'CS+6802FB00'           |'R0402_H20'| '(R0402-0201_H20)'             | '0.68'    | '1%'    | '1/6W'   | 'IO'       | 'RES CHIP 0.68 OHM 1/6W +-1%(0402)'                | 'CHIPR0402'    | ''          | ''            | '20210507'
 '374'        | '1%'      | '1/16W'  | '0402LF'  | 'CHIP'   | 'CS13742FB13'(!)        = 'End of Design' | 'Comp-Approve'     | 'CS13742FB13'           |'R0402'| '(R0402-0201)'                 | '374'     | '1%'    | '1/16W'  | 'DISCRETE' | 'RES CHIP 374 1/16W +-1%(0402)'                    | 'CHIPR0402'    | ''          | ''            | '20210514'
 '374'        | '1%'      | '1/16W'  | '0402LF'  | 'EMPTY'  | 'CS13742FB13'(!)        = 'End of Design' | 'Comp-Approve'     | 'CS13742FB13'           |'R0402'| '(R0402-0201)'                 | '374'     | '1%'    | '1/16W'  | 'IO'       | 'RES CHIP 374 1/16W +-1%(0402)'                    | 'CHIPR0402'    | ''          | ''            | '20210514'
 '3.74K'      | '0.1%'    | '1/16W'  | '0402LF'  | 'CHIP'   | 'CS23742BB01'(!)        = ''              | 'End of Life'      | 'CS23742BB01'           |'R0402_EOL'| '(R0402-0201)'                 | '3.74K'   | '0.1%'  | '1/16W'  | 'DISCRETE' | 'RES CHIP 3.74K 1/16W +-0.1%(0402)'                | 'CHIPR0402'    | ''          | ''            | '20210514'
 '3.74K'      | '0.1%'    | '1/16W'  | '0402LF'  | 'EMPTY'  | 'CS23742BB01'(!)        = ''              | 'End of Life'      | 'CS23742BB01'           |'R0402_EOL'| '(R0402-0201)'                 | '3.74K'   | '0.1%'  | '1/16W'  | 'IO'       | 'RES CHIP 3.74K 1/16W +-0.1%(0402)'                | 'CHIPR0402'    | ''          | ''            | '20210514'
 '13.3K'      | '0.1%'    | '1/16W'  | '0402LF'  | 'CHIP'   | 'CS31332BB01'(!)        = ''              | ''                 | 'CS31332BB01'           |'R0402'| '(R0402-0201)'                 | '13.3K'   | '0.1%'  | '1/16W'  | 'DISCRETE' | 'RES CHIP 13.3K 1/16W +-0.1%(0402)'                | 'CHIPR0402'    | ''          | ''            | '20210514'
 '13.3K'      | '0.1%'    | '1/16W'  | '0402LF'  | 'EMPTY'  | 'CS31332BB01'(!)        = ''              | ''                 | 'CS31332BB01'           |'R0402'| '(R0402-0201)'                 | '13.3K'   | '0.1%'  | '1/16W'  | 'IO'       | 'RES CHIP 13.3K 1/16W +-0.1%(0402)'                | 'CHIPR0402'    | ''          | ''            | '20210514'
 '90.9'       | '1%'      | '1/20W'  | '0201LF'  | 'CHIP'   | 'CS09091FE00'(!)        = ''              | ''                 | 'CS09091FE00'           |'R0201'| '(SMR0201AW)'                  | '90.9'    | '1%'    | '1/20W'  | 'DISCRETE' | 'RES CHIP 90.9 1/20W +-1%(0201)'                   | 'CHIPR0201'    | ''          | ''            | '20210520'
 '90.9'       | '1%'      | '1/20W'  | '0201LF'  | 'EMPTY'  | 'CS09091FE00'(!)        = ''              | ''                 | 'CS09091FE00'           |'R0201'| '(SMR0201AW)'                  | '90.9'    | '1%'    | '1/20W'  | 'IO'       | 'RES CHIP 90.9 1/20W +-1%(0201)'                   | 'CHIPR0201'    | ''          | ''            | '20210520'
 '280K'       | '1%'      | '1/16W'  | '0402LF'  | 'CHIP'   | 'CS42802FB05'(!)        = ''              | ''                 | 'CS42802FB05'           |'R0402'| '(R0402-0201)'                 | '280K'    | '1%'    | '1/16W'  | 'DISCRETE' | 'RES CHIP 280K 1/16W +-1%(0402)EF'                 | 'CHIPR0402'    | ''          | ''            | '20210526'
 '280K'       | '1%'      | '1/16W'  | '0402LF'  | 'EMPTY'  | 'CS42802FB05'(!)        = ''              | ''                 | 'CS42802FB05'           |'R0402'| '(R0402-0201)'                 | '280K'    | '1%'    | '1/16W'  | 'IO'       | 'RES CHIP 280K 1/16W +-1%(0402)EF'                 | 'CHIPR0402'    | ''          | ''            | '20210526'
 '53.6K'      | '0.1%'    | '1/16W'  | '0402LF'  | 'CHIP'   | 'CS35362BB03'(!)        = ''              | ''                 | 'CS35362BB03'           |'R0402'| '(R0402-0201)'                 | '53.6K'   | '0.1%'  | '1/16W'  | 'DISCRETE' | 'RES CHIP 53.6K 1/16W +-0.1%(0402)'                | 'CHIPR0402'    | ''          | ''            | '20210526'
 '53.6K'      | '0.1%'    | '1/16W'  | '0402LF'  | 'EMPTY'  | 'CS35362BB03'(!)        = ''              | ''                 | 'CS35362BB03'           |'R0402'| '(R0402-0201)'                 | '53.6K'   | '0.1%'  | '1/16W'  | 'IO'       | 'RES CHIP 53.6K 1/16W +-0.1%(0402)'                | 'CHIPR0402'    | ''          | ''            | '20210526'
 '6.65K'      | '0.1%'    | '1/16W'  | '0402LF'  | 'CHIP'   | 'CS26652BB01'(!)        = ''              | ''                 | 'CS26652BB01'           |'R0402'| '(R0402-0201)'                 | '6.65K'   | '0.1%'  | '1/16W'  | 'DISCRETE' | 'RES CHIP 6.65K 1/16W +-0.1%(0402)'                | 'CHIPR0402'    | ''          | ''            | '20210526'
 '6.65K'      | '0.1%'    | '1/16W'  | '0402LF'  | 'EMPTY'  | 'CS26652BB01'(!)        = ''              | ''                 | 'CS26652BB01'           |'R0402'| '(R0402-0201)'                 | '6.65K'   | '0.1%'  | '1/16W'  | 'IO'       | 'RES CHIP 6.65K 1/16W +-0.1%(0402)'                | 'CHIPR0402'    | ''          | ''            | '20210526'
 '3.74K'      | '0.1%'    | '1/16W'  | '0402LF'  | 'CHIP'   | 'CS23742BB00'(!)        = ''              | ''                 | 'CS23742BB00'           |'R0402'| '(R0402-0201)'                 | '3.74K'   | '0.1%'  | '1/16W'  | 'DISCRETE' | 'RES CHIP 3.74K 1/16W +-0.1%(0402)'                | 'CHIPR0402'    | ''          | ''            | '20210526'
 '3.74K'      | '0.1%'    | '1/16W'  | '0402LF'  | 'EMPTY'  | 'CS23742BB00'(!)        = ''              | ''                 | 'CS23742BB00'           |'R0402'| '(R0402-0201)'                 | '3.74K'   | '0.1%'  | '1/16W'  | 'IO'       | 'RES CHIP 3.74K 1/16W +-0.1%(0402)'                | 'CHIPR0402'    | ''          | ''            | '20210526'
 '97.6'       | '1%'      | '1/16W'  | '0402LF'  | 'CHIP'   | 'CS09762FB01'(!)        = ''              | ''                 | 'CS09762FB01'           |'R0402'| '(R0402-0201)'                 | '97.6'    | '1%'    | '1/16W'  | 'DISCRETE' | 'RES CHIP 97.6 1/16W +-1%(0402)'                   | 'CHIPR0402'    | ''          | ''            | '20210531'
 '97.6'       | '1%'      | '1/16W'  | '0402LF'  | 'EMPTY'  | 'CS09762FB01'(!)        = ''              | ''                 | 'CS09762FB01'           |'R0402'| '(R0402-0201)'                 | '97.6'    | '1%'    | '1/16W'  | 'IO'       | 'RES CHIP 97.6 1/16W +-1%(0402)'                   | 'CHIPR0402'    | ''          | ''            | '20210531'
 '0.03'       | '1%'      | '1/10W'  | '0603LF'  | 'CHIP'   | 'CS+0303F901'(!)        = ''              | ''                 | 'CS+0303F901'           |'R0603'| '(SMR0603AW)'                  | '0.03'    | '1%'    | '1/10W'  | 'DISCRETE' | 'RES CHIP 0.03 1/10W +-1%(0603)'                   | 'CHIPR0603'    | ''          | ''            | '20210531'
 '0.03'       | '1%'      | '1/10W'  | '0603LF'  | 'EMPTY'  | 'CS+0303F901'(!)        = ''              | ''                 | 'CS+0303F901'           |'R0603'| '(SMR0603AW)'                  | '0.03'    | '1%'    | '1/10W'  | 'IO'       | 'RES CHIP 0.03 1/10W +-1%(0603)'                   | 'CHIPR0603'    | ''          | ''            | '20210531'
 '0.25'       | '1%'      | '1/4W'   | '0805LF'  | 'CHIP'   | 'CS+2506FA00'(!)        = ''              | ''                 | 'CS+2506FA00'           |'R0805'| '(SMR0805AW)'                  | '0.25'    | '1%'    | '1/4W'   | 'DISCRETE' | 'RES CHIP 0.25 1/4W +-1%(0805)'                    | 'CHIPR0805'    | ''          | ''            | '20210607'
 '0.25'       | '1%'      | '1/4W'   | '0805LF'  | 'EMPTY'  | 'CS+2506FA00'(!)        = ''              | ''                 | 'CS+2506FA00'           |'R0805'| '(SMR0805AW)'                  | '0.25'    | '1%'    | '1/4W'   | 'IO'       | 'RES CHIP 0.25 1/4W +-1%(0805)'                    | 'CHIPR0805'    | ''          | ''            | '20210607'
 '75K'        | '0.1%'    | '1/16W'  | '0402LF'  | 'CHIP'   | 'CS37502BB00'(!)        = ''              | ''                 | 'CS37502BB00'           |'R0402'| '(R0402-0201)'                 | '75K'     | '0.1%'  | '1/16W'  | 'DISCRETE' | 'RES CHIP 75K 1/16W +-0.1%(0402)'                  | 'CHIPR0402'    | ''          | ''            | '20210610'
 '75K'        | '0.1%'    | '1/16W'  | '0402LF'  | 'EMPTY'  | 'CS37502BB00'(!)        = ''              | ''                 | 'CS37502BB00'           |'R0402'| '(R0402-0201)'                 | '75K'     | '0.1%'  | '1/16W'  | 'IO'       | 'RES CHIP 75K 1/16W +-0.1%(0402)'                  | 'CHIPR0402'    | ''          | ''            | '20210610'
 '4.7'        | '5%'      | '1/8W'   | '0805LF'  | 'CHIP'   | 'CS-4704JA31'(!)        = 'End of Design' | 'Comp-Approve'     | 'CS-4704JA31'           |'R0805_H26'| '(SMR0805AW)'                  | '4.7'     | '5%'    | '1/8W'   | 'DISCRETE' | 'RES CHIP 4.7 1/8W+-5%(0805)'                      | 'CHIPR0805'    | ''          | ''            | '20210610'
 '4.7'        | '5%'      | '1/8W'   | '0805LF'  | 'EMPTY'  | 'CS-4704JA31'(!)        = 'End of Design' | 'Comp-Approve'     | 'CS-4704JA31'           |'R0805_H26'| '(SMR0805AW)'                  | '4.7'     | '5%'    | '1/8W'   | 'IO'       | 'RES CHIP 4.7 1/8W+-5%(0805)'                      | 'CHIPR0805'    | ''          | ''            | '20210610'
 '300'        | '0.1%'    | '1/16W'  | '0402LF'  | 'CHIP'   | 'CS13002BB01'(!)        = ''              | ''                 | 'CS13002BB01'           |'R0402'| '(R0402-0201)'                 | '300'     | '0.1%'  | '1/16W'  | 'DISCRETE' | 'RES CHIP 300 1/16W +-0.1%(0402)'                  | 'CHIPR0402'    | ''          | ''            | '20210610'
 '300'        | '0.1%'    | '1/16W'  | '0402LF'  | 'EMPTY'  | 'CS13002BB01'(!)        = ''              | ''                 | 'CS13002BB01'           |'R0402'| '(R0402-0201)'                 | '300'     | '0.1%'  | '1/16W'  | 'IO'       | 'RES CHIP 300 1/16W +-0.1%(0402)'                  | 'CHIPR0402'    | ''          | ''            | '20210610'
 '430'        | '1%'      | '1/2W'   | '1206LF'  | 'CHIP'   | 'CS14307F200'(!)        = ''              | ''                 | 'CS14307F200'           |'R1206XF'| '(SMR1206AW)'                  | '430'     | '1%'    | '1/2W'   | 'DISCRETE' | 'RES CHIP 430 1/2W +-1%(1206)'                     | 'CHIPR1206'    | ''          | ''            | '20210616'
 '430'        | '1%'      | '1/2W'   | '1206LF'  | 'EMPTY'  | 'CS14307F200'(!)        = ''              | ''                 | 'CS14307F200'           |'R1206XF'| '(SMR1206AW)'                  | '430'     | '1%'    | '1/2W'   | 'IO'       | 'RES CHIP 430 1/2W +-1%(1206)'                     | 'CHIPR1206'    | ''          | ''            | '20210616'
 '34'         | '1%'      | '1/16W'  | '0402LF'  | 'CHIP'   | 'CS03402FB00'(!)        = 'End of Design' | 'Comp-Release Qty' | 'CS03402FB00'           |'R0402'| '(R0402-0201)'                 | '34'      | '1%'    | '1/16W'  | 'DISCRETE' | 'RES CHIP 34 1/16W +-1%(0402)'                     | 'CHIPR0402'    | ''          | ''            | '20210622'
 '34'         | '1%'      | '1/16W'  | '0402LF'  | 'EMPTY'  | 'CS03402FB00'(!)        = 'End of Design' | 'Comp-Release Qty' | 'CS03402FB00'           |'R0402'| '(R0402-0201)'                 | '34'      | '1%'    | '1/16W'  | 'IO'       | 'RES CHIP 34 1/16W +-1%(0402)'                     | 'CHIPR0402'    | ''          | ''            | '20210622'
 '300K'       | '0.1%'    | '1/16W'  | '0402LF'  | 'CHIP'   | 'CS43002BB01'(!)        = 'End of Design' | 'Comp-Approve'     | 'CS43002BB01'           |'R0402'| '(R0402-0201)'                 | '300K'    | '0.1%'  | '1/16W'  | 'DISCRETE' | 'RES CHIP 300K 1/16W +-0.1%(0402)'                 | 'CHIPR0402'    | ''          | ''            | '20210622'
 '300K'       | '0.1%'    | '1/16W'  | '0402LF'  | 'EMPTY'  | 'CS43002BB01'(!)        = 'End of Design' | 'Comp-Approve'     | 'CS43002BB01'           |'R0402'| '(R0402-0201)'                 | '300K'    | '0.1%'  | '1/16W'  | 'IO'       | 'RES CHIP 300K 1/16W +-0.1%(0402)'                 | 'CHIPR0402'    | ''          | ''            | '20210622'
 '0.0002'     | '5%'      | '1/2W'   | '0805LF'  | 'CHIP'   | 'CS00007JA00'(!)        = ''              | ''                 | 'CS00007JA00'           |'R0805_H32'| '(SMR0805AW)'                  | '0.0002'  | '5%'    | '1/2W'   | 'DISCRETE' | 'RESISTOR CHIP 0.0002 1/2W +-5%(0805)'             | 'CHIPR0805'    | ''          | ''            | '20210622'
 '0.0002'     | '5%'      | '1/2W'   | '0805LF'  | 'EMPTY'  | 'CS00007JA00'(!)        = ''              | ''                 | 'CS00007JA00'           |'R0805_H32'| '(SMR0805AW)'                  | '0.0002'  | '5%'    | '1/2W'   | 'IO'       | 'RESISTOR CHIP 0.0002 1/2W +-5%(0805)'             | 'CHIPR0805'    | ''          | ''            | '20210622'
 '169'        | '1%'      | '1/20W'  | '0201LF'  | 'CHIP'   | 'CS11691FE01'(!)        = ''              | ''                 | 'CS11691FE01'           |'R0201'| '(SMR0201AW)'                  | '169'     | '1%'    | '1/20W'  | 'DISCRETE' | 'RES CHIP 169 1/20W +-1%(0201)'                    | 'CHIPR0201'    | ''          | ''            | '20210622'
 '169'        | '1%'      | '1/20W'  | '0201LF'  | 'EMPTY'  | 'CS11691FE01'(!)        = ''              | ''                 | 'CS11691FE01'           |'R0201'| '(SMR0201AW)'                  | '169'     | '1%'    | '1/20W'  | 'IO'       | 'RES CHIP 169 1/20W +-1%(0201)'                    | 'CHIPR0201'    | ''          | ''            | '20210622'
 '8.66'       | '1%'      | '1/16W'  | '0402LF'  | 'CHIP'   | 'CS-8662FB00'(!)        = ''              | ''                 | 'CS-8662FB00'           |'R0402'| '(R0402-0201)'                 | '8.66'    | '1%'    | '1/16W'  | 'DISCRETE' | 'RES CHIP 8.66 1/16W+-1%(0402)'                    | 'CHIPR0402'    | ''          | ''            | '20210623'
 '8.66'       | '1%'      | '1/16W'  | '0402LF'  | 'EMPTY'  | 'CS-8662FB00'(!)        = ''              | ''                 | 'CS-8662FB00'           |'R0402'| '(R0402-0201)'                 | '8.66'    | '1%'    | '1/16W'  | 'IO'       | 'RES CHIP 8.66 1/16W+-1%(0402)'                    | 'CHIPR0402'    | ''          | ''            | '20210623'
 '2.15K'      | '1%'      | '1/4W'   | '1206LF'  | 'CHIP'   | 'CS22156F201'(!)        = 'End of Design' | 'Comp-Approve'     | 'CS22156F201'           |'R1206XF'| '(SMR1206AW)'                  | '2.15K'   | '1%'    | '1/4W'   | 'DISCRETE' | 'RES CHIP 2.15K 1/4W +-1%(1206)EF'                 | 'CHIPR1206'    | ''          | ''            | '20210624'
 '2.15K'      | '1%'      | '1/4W'   | '1206LF'  | 'EMPTY'  | 'CS22156F201'(!)        = 'End of Design' | 'Comp-Approve'     | 'CS22156F201'           |'R1206XF'| '(SMR1206AW)'                  | '2.15K'   | '1%'    | '1/4W'   | 'IO'       | 'RES CHIP 2.15K 1/4W +-1%(1206)EF'                 | 'CHIPR1206'    | ''          | ''            | '20210624'
 '475K'       | '1%'      | '1/8W'   | '0805LF'  | 'CHIP'   | 'CS44754FA03'(!)        = ''              | ''                 | 'CS44754FA03'           |'R0805_H26'| '(SMR0805AW)'                  | '475K'    | '1%'    | '1/8W'   | 'DISCRETE' | 'RES CHIP 475K 1/8W +-1%(0805)'                    | 'CHIPR0805'    | ''          | ''            | '20210628'
 '475K'       | '1%'      | '1/8W'   | '0805LF'  | 'EMPTY'  | 'CS44754FA03'(!)        = ''              | ''                 | 'CS44754FA03'           |'R0805_H26'| '(SMR0805AW)'                  | '475K'    | '1%'    | '1/8W'   | 'IO'       | 'RES CHIP 475K 1/8W +-1%(0805)'                    | 'CHIPR0805'    | ''          | ''            | '20210628'
 '124'        | '0.1%'    | '1/16W'  | '0402LF'  | 'CHIP'   | 'CS11242BB00'(!)        = ''              | ''                 | 'CS11242BB00'           |'R0402'| '(R0402-0201)'                 | '124'     | '0.1%'  | '1/16W'  | 'DISCRETE' | 'RES CHIP 124 1/16W+-0.1%(0402)'                   | 'CHIPR0402'    | ''          | ''            | '20210630'
 '124'        | '0.1%'    | '1/16W'  | '0402LF'  | 'EMPTY'  | 'CS11242BB00'(!)        = ''              | ''                 | 'CS11242BB00'           |'R0402'| '(R0402-0201)'                 | '124'     | '0.1%'  | '1/16W'  | 'IO'       | 'RES CHIP 124 1/16W+-0.1%(0402)'                   | 'CHIPR0402'    | ''          | ''            | '20210630'
 '909'        | '0.1%'    | '1/16W'  | '0402LF'  | 'CHIP'   | 'CS19092BB01'(!)        = ''              | ''                 | 'CS19092BB01'           |'R0402'| '(R0402-0201)'                 | '909'     | '0.1%'  | '1/16W'  | 'DISCRETE' | 'RES CHIP 909 1/16W+-0.1%(0402)'                   | 'CHIPR0402'    | ''          | ''            | '20210630'
 '909'        | '0.1%'    | '1/16W'  | '0402LF'  | 'EMPTY'  | 'CS19092BB01'(!)        = ''              | ''                 | 'CS19092BB01'           |'R0402'| '(R0402-0201)'                 | '909'     | '0.1%'  | '1/16W'  | 'IO'       | 'RES CHIP 909 1/16W+-0.1%(0402)'                   | 'CHIPR0402'    | ''          | ''            | '20210630'
 '49.9K'      | '0.1%'    | '1/16W'  | '0402LF'  | 'CHIP'   | 'CS34992BB08'(!)        = ''              | ''                 | 'CS34992BB08'           |'R0402'| '(R0402-0201)'                 | '49.9K'   | '0.1%'  | '1/16W'  | 'DISCRETE' | 'RES CHIP 49.9K 1/16W+-0.1%(0402)'                 | 'CHIPR0402'    | ''          | ''            | '20210630'
 '49.9K'      | '0.1%'    | '1/16W'  | '0402LF'  | 'EMPTY'  | 'CS34992BB08'(!)        = ''              | ''                 | 'CS34992BB08'           |'R0402'| '(R0402-0201)'                 | '49.9K'   | '0.1%'  | '1/16W'  | 'IO'       | 'RES CHIP 49.9K 1/16W+-0.1%(0402)'                 | 'CHIPR0402'    | ''          | ''            | '20210630'
 '23.2K'      | '0.1%'    | '1/16W'  | '0402LF'  | 'CHIP'   | 'CS32322BB00'(!)        = ''              | ''                 | 'CS32322BB00'           |'R0402'| '(R0402-0201)'                 | '23.2K'   | '0.1%'  | '1/16W'  | 'DISCRETE' | 'RES CHIP 23.2K 1/16W +-0.1%(0402)'                | 'CHIPR0402'    | ''          | ''            | '20210630'
 '23.2K'      | '0.1%'    | '1/16W'  | '0402LF'  | 'EMPTY'  | 'CS32322BB00'(!)        = ''              | ''                 | 'CS32322BB00'           |'R0402'| '(R0402-0201)'                 | '23.2K'   | '0.1%'  | '1/16W'  | 'IO'       | 'RES CHIP 23.2K 1/16W +-0.1%(0402)'                | 'CHIPR0402'    | ''          | ''            | '20210630'
 '1.69K'      | '0.1%'    | '1/16W'  | '0402LF'  | 'CHIP'   | 'CS21692BB00'(!)        = ''              | ''                 | 'CS21692BB00'           |'R0402'| '(R0402-0201)'                 | '1.69K'   | '0.1%'  | '1/16W'  | 'DISCRETE' | 'RES CHIP 1.69K 1/16W+-0.1%(0402)'                 | 'CHIPR0402'    | ''          | ''            | '20210630'
 '1.69K'      | '0.1%'    | '1/16W'  | '0402LF'  | 'EMPTY'  | 'CS21692BB00'(!)        = ''              | ''                 | 'CS21692BB00'           |'R0402'| '(R0402-0201)'                 | '1.69K'   | '0.1%'  | '1/16W'  | 'IO'       | 'RES CHIP 1.69K 1/16W+-0.1%(0402)'                 | 'CHIPR0402'    | ''          | ''            | '20210630'
 '3.09K'      | '0.1%'    | '1/16W'  | '0402LF'  | 'CHIP'   | 'CS23092BB02'(!)        = ''              | ''                 | 'CS23092BB02'           |'R0402'| '(R0402-0201)'                 | '3.09K'   | '0.1%'  | '1/16W'  | 'DISCRETE' | 'RES CHIP 3.09K 1/16W+-0.1%(0402)'                 | 'CHIPR0402'    | ''          | ''            | '20210630'
 '3.09K'      | '0.1%'    | '1/16W'  | '0402LF'  | 'EMPTY'  | 'CS23092BB02'(!)        = ''              | ''                 | 'CS23092BB02'           |'R0402'| '(R0402-0201)'                 | '3.09K'   | '0.1%'  | '1/16W'  | 'IO'       | 'RES CHIP 3.09K 1/16W+-0.1%(0402)'                 | 'CHIPR0402'    | ''          | ''            | '20210630'
 '1.74K'      | '0.1%'    | '1/16W'  | '0402LF'  | 'CHIP'   | 'CS21742BB02'(!)        = ''              | ''                 | 'CS21742BB02'           |'R0402'| '(R0402-0201)'                 | '1.74K'   | '0.1%'  | '1/16W'  | 'DISCRETE' | 'RES CHIP 1.74K 1/16W+-0.1%(0402)'                 | 'CHIPR0402'    | ''          | ''            | '20210630'
 '1.74K'      | '0.1%'    | '1/16W'  | '0402LF'  | 'EMPTY'  | 'CS21742BB02'(!)        = ''              | ''                 | 'CS21742BB02'           |'R0402'| '(R0402-0201)'                 | '1.74K'   | '0.1%'  | '1/16W'  | 'IO'       | 'RES CHIP 1.74K 1/16W+-0.1%(0402)'                 | 'CHIPR0402'    | ''          | ''            | '20210630'
 '2.55K'      | '0.1%'    | '1/16W'  | '0402LF'  | 'CHIP'   | 'CS22552BB01'(!)        = ''              | ''                 | 'CS22552BB01'           |'R0402'| '(R0402-0201)'                 | '2.55K'   | '0.1%'  | '1/16W'  | 'DISCRETE' | 'RES CHIP 2.55K 1/16W+-0.1%(0402)'                 | 'CHIPR0402'    | ''          | ''            | '20210630'
 '2.55K'      | '0.1%'    | '1/16W'  | '0402LF'  | 'EMPTY'  | 'CS22552BB01'(!)        = ''              | ''                 | 'CS22552BB01'           |'R0402'| '(R0402-0201)'                 | '2.55K'   | '0.1%'  | '1/16W'  | 'IO'       | 'RES CHIP 2.55K 1/16W+-0.1%(0402)'                 | 'CHIPR0402'    | ''          | ''            | '20210630'
 '1.37K'      | '0.1%'    | '1/16W'  | '0402LF'  | 'CHIP'   | 'CS21372BB00'(!)        = ''              | ''                 | 'CS21372BB00'           |'R0402'| '(R0402-0201)'                 | '1.37K'   | '0.1%'  | '1/16W'  | 'DISCRETE' | 'RES CHIP 1.37K 1/16W +-0.1%(0402)'                | 'CHIPR0402'    | ''          | ''            | '20210630'
 '1.37K'      | '0.1%'    | '1/16W'  | '0402LF'  | 'EMPTY'  | 'CS21372BB00'(!)        = ''              | ''                 | 'CS21372BB00'           |'R0402'| '(R0402-0201)'                 | '1.37K'   | '0.1%'  | '1/16W'  | 'IO'       | 'RES CHIP 1.37K 1/16W +-0.1%(0402)'                | 'CHIPR0402'    | ''          | ''            | '20210630'
 '453K'       | '1%'      | '1/16W'  | '0402LF'  | 'CHIP'   | 'CS44532FB05'(!)        = ''              | ''                 | 'CS44532FB05'           |'R0402'| '(R0402-0201)'                 | '453K'    | '1%'    | '1/16W'  | 'DISCRETE' | 'RES CHIP 453K 1/16W +-1%(0402)EF'                 | 'CHIPR0402'    | ''          | ''            | '20210630'
 '453K'       | '1%'      | '1/16W'  | '0402LF'  | 'EMPTY'  | 'CS44532FB05'(!)        = ''              | ''                 | 'CS44532FB05'           |'R0402'| '(R0402-0201)'                 | '453K'    | '1%'    | '1/16W'  | 'IO'       | 'RES CHIP 453K 1/16W +-1%(0402)EF'                 | 'CHIPR0402'    | ''          | ''            | '20210630'
 '17.4'       | '0.1%'    | '1/16W'  | '0402LF'  | 'CHIP'   | 'CS01742BB00'(!)        = ''              | ''                 | 'CS01742BB00'           |'R0402'| '(R0402-0201)'                 | '17.4'    | '0.1%'  | '1/16W'  | 'DISCRETE' | 'RES CHIP 17.4 1/16W +-0.1%( 0402)'                | 'CHIPR0402'    | ''          | ''            | '20210701'
 '17.4'       | '0.1%'    | '1/16W'  | '0402LF'  | 'EMPTY'  | 'CS01742BB00'(!)        = ''              | ''                 | 'CS01742BB00'           |'R0402'| '(R0402-0201)'                 | '17.4'    | '0.1%'  | '1/16W'  | 'IO'       | 'RES CHIP 17.4 1/16W +-0.1%( 0402)'                | 'CHIPR0402'    | ''          | ''            | '20210701'
 '91'         | '0.1%'    | '1/16W'  | '0402LF'  | 'CHIP'   | 'CS09102BB00'(!)        = ''              | ''                 | 'CS09102BB00'           |'R0402'| '(R0402-0201)'                 | '91'      | '0.1%'  | '1/16W'  | 'DISCRETE' | 'RES CHIP 91 1/16W +-0.1%( 0402)'                  | 'CHIPR0402'    | ''          | ''            | '20210701'
 '91'         | '0.1%'    | '1/16W'  | '0402LF'  | 'EMPTY'  | 'CS09102BB00'(!)        = ''              | ''                 | 'CS09102BB00'           |'R0402'| '(R0402-0201)'                 | '91'      | '0.1%'  | '1/16W'  | 'IO'       | 'RES CHIP 91 1/16W +-0.1%( 0402)'                  | 'CHIPR0402'    | ''          | ''            | '20210701'
 '332'        | '0.1%'    | '1/16W'  | '0402LF'  | 'CHIP'   | 'CS13322BB00'(!)        = ''              | ''                 | 'CS13322BB00'           |'R0402'| '(R0402-0201)'                 | '332'     | '0.1%'  | '1/16W'  | 'DISCRETE' | 'RES CHIP 332 1/16W +-0.1%( 0402)'                 | 'CHIPR0402'    | ''          | ''            | '20210702'
 '332'        | '0.1%'    | '1/16W'  | '0402LF'  | 'EMPTY'  | 'CS13322BB00'(!)        = ''              | ''                 | 'CS13322BB00'           |'R0402'| '(R0402-0201)'                 | '332'     | '0.1%'  | '1/16W'  | 'IO'       | 'RES CHIP 332 1/16W +-0.1%( 0402)'                 | 'CHIPR0402'    | ''          | ''            | '20210702'
 '374'        | '0.1%'    | '1/16W'  | '0402LF'  | 'CHIP'   | 'CS13742BB00'(!)        = ''              | ''                 | 'CS13742BB00'           |'R0402'| '(R0402-0201)'                 | '374'     | '0.1%'  | '1/16W'  | 'DISCRETE' | 'RES CHIP 374 1/16W +-0.1%( 0402)'                 | 'CHIPR0402'    | ''          | ''            | '20210702'
 '374'        | '0.1%'    | '1/16W'  | '0402LF'  | 'EMPTY'  | 'CS13742BB00'(!)        = ''              | ''                 | 'CS13742BB00'           |'R0402'| '(R0402-0201)'                 | '374'     | '0.1%'  | '1/16W'  | 'IO'       | 'RES CHIP 374 1/16W +-0.1%( 0402)'                 | 'CHIPR0402'    | ''          | ''            | '20210702'
 '590'        | '0.1%'    | '1/16W'  | '0402LF'  | 'CHIP'   | 'CS15902BB00'(!)        = ''              | ''                 | 'CS15902BB00'           |'R0402'| '(R0402-0201)'                 | '590'     | '0.1%'  | '1/16W'  | 'DISCRETE' | 'RES CHIP 590 1/16W +-0.1%( 0402)'                 | 'CHIPR0402'    | ''          | ''            | '20210702'
 '590'        | '0.1%'    | '1/16W'  | '0402LF'  | 'EMPTY'  | 'CS15902BB00'(!)        = ''              | ''                 | 'CS15902BB00'           |'R0402'| '(R0402-0201)'                 | '590'     | '0.1%'  | '1/16W'  | 'IO'       | 'RES CHIP 590 1/16W +-0.1%( 0402)'                 | 'CHIPR0402'    | ''          | ''            | '20210702'
 '300K'       | '1%'      | '1/16W'  | '0402LF'  | 'CHIP'   | 'CS43002FB01'(!)        = 'End of Design' | 'Comp-Approve'     | 'CS43002FB01'           |'R0402'| '(R0402-0201)'                 | '300K'    | '1%'    | '1/16W'  | 'DISCRETE' | 'RES CHIP 300K 1/16W +-1%(0402)EF'                 | 'CHIPR0402'    | ''          | ''            | '20210702'
 '300K'       | '1%'      | '1/16W'  | '0402LF'  | 'EMPTY'  | 'CS43002FB01'(!)        = 'End of Design' | 'Comp-Approve'     | 'CS43002FB01'           |'R0402'| '(R0402-0201)'                 | '300K'    | '1%'    | '1/16W'  | 'IO'       | 'RES CHIP 300K 1/16W +-1%(0402)EF'                 | 'CHIPR0402'    | ''          | ''            | '20210702'
 '3.92K'      | '0.1%'    | '1/16W'  | '0402LF'  | 'CHIP'   | 'CS23922BB00'(!)        = 'End of Design' | 'Comp-Approve'     | 'CS23922BB00'           |'R0402'| '(R0402-0201)'                 | '3.92K'   | '0.1%'  | '1/16W'  | 'DISCRETE' | 'RES CHIP 3.92K 1/16W +-0.1%(0402)'                | 'CHIPR0402'    | ''          | ''            | '20210702'
 '3.92K'      | '0.1%'    | '1/16W'  | '0402LF'  | 'EMPTY'  | 'CS23922BB00'(!)        = 'End of Design' | 'Comp-Approve'     | 'CS23922BB00'           |'R0402'| '(R0402-0201)'                 | '3.92K'   | '0.1%'  | '1/16W'  | 'IO'       | 'RES CHIP 3.92K 1/16W +-0.1%(0402)'                | 'CHIPR0402'    | ''          | ''            | '20210702'
 '17.4'       | '1%'      | '1/16W'  | '0402LF'  | 'CHIP'   | 'CS01742FB00'(!)        = ''              | ''                 | 'CS01742FB00'           |'R0402'| '(R0402-0201)'                 | '17.4'    | '1%'    | '1/16W'  | 'DISCRETE' | 'RES CHIP 17.4 1/16W +-1%( 0402)'                  | 'CHIPR0402'    | ''          | ''            | '20210707'
 '17.4'       | '1%'      | '1/16W'  | '0402LF'  | 'EMPTY'  | 'CS01742FB00'(!)        = ''              | ''                 | 'CS01742FB00'           |'R0402'| '(R0402-0201)'                 | '17.4'    | '1%'    | '1/16W'  | 'IO'       | 'RES CHIP 17.4 1/16W +-1%( 0402)'                  | 'CHIPR0402'    | ''          | ''            | '20210707'
 '84.5'       | '1%'      | '1/16W'  | '0402LF'  | 'CHIP'   | 'CS08452FB01'(!)        = 'End of Design' | 'Comp-Approve'     | 'CS08452FB01'           |'R0402'| '(R0402-0201)'                 | '84.5'    | '1%'    | '1/16W'  | 'DISCRETE' | 'RES CHIP 84.5 1/16W 1%(0402)'                     | 'CHIPR0402'    | ''          | ''            | '20210707'
 '84.5'       | '1%'      | '1/16W'  | '0402LF'  | 'EMPTY'  | 'CS08452FB01'(!)        = 'End of Design' | 'Comp-Approve'     | 'CS08452FB01'           |'R0402'| '(R0402-0201)'                 | '84.5'    | '1%'    | '1/16W'  | 'IO'       | 'RES CHIP 84.5 1/16W 1%(0402)'                     | 'CHIPR0402'    | ''          | ''            | '20210707'
 '5.1'        | '5%'      | '1/16W'  | '0402LF'  | 'CHIP'   | 'CS-5102JB02'(!)        = ''              | ''                 | 'CS-5102JB02'           |'R0402'| '(R0402-0201)'                 | '5.1'     | '5%'    | '1/16W'  | 'DISCRETE' | 'RES CHIP 5.1 1/16W +-5%(0402)EF'                  | 'CHIPR0402'    | ''          | ''            | '20210715'
 '5.1'        | '5%'      | '1/16W'  | '0402LF'  | 'EMPTY'  | 'CS-5102JB02'(!)        = ''              | ''                 | 'CS-5102JB02'           |'R0402'| '(R0402-0201)'                 | '5.1'     | '5%'    | '1/16W'  | 'IO'       | 'RES CHIP 5.1 1/16W +-5%(0402)EF'                  | 'CHIPR0402'    | ''          | ''            | '20210715'
 '2.4K'       | '1%'      | '1/16W'  | '0402LF'  | 'CHIP'   | 'CS22402FB02'(!)        = ''              | ''                 | 'CS22402FB02'           |'R0402'| '(R0402-0201)'                 | '2.4K'    | '1%'    | '1/16W'  | 'DISCRETE' | 'RES CHIP 2.4K 1/16W+-1%(0402)EF'                  | 'CHIPR0402'    | ''          | ''            | '20210715'
 '2.4K'       | '1%'      | '1/16W'  | '0402LF'  | 'EMPTY'  | 'CS22402FB02'(!)        = ''              | ''                 | 'CS22402FB02'           |'R0402'| '(R0402-0201)'                 | '2.4K'    | '1%'    | '1/16W'  | 'IO'       | 'RES CHIP 2.4K 1/16W+-1%(0402)EF'                  | 'CHIPR0402'    | ''          | ''            | '20210715'
 '4.64K'      | '0.5%'    | '1/16W'  | '0402LF'  | 'CHIP'   | 'CS24642DB01'(!)        = ''              | ''                 | 'CS24642DB01'           |'R0402'| '(R0402-0201)'                 | '4.64K'   | '0.5%'  | '1/16W'  | 'DISCRETE' | 'RES CHIP 4.64K 1/16W +-0.5%(0402)EF'              | 'CHIPR0402'    | ''          | ''            | '20210715'
 '4.64K'      | '0.5%'    | '1/16W'  | '0402LF'  | 'EMPTY'  | 'CS24642DB01'(!)        = ''              | ''                 | 'CS24642DB01'           |'R0402'| '(R0402-0201)'                 | '4.64K'   | '0.5%'  | '1/16W'  | 'IO'       | 'RES CHIP 4.64K 1/16W +-0.5%(0402)EF'              | 'CHIPR0402'    | ''          | ''            | '20210715'
 '15.4K'      | '1%'      | '1/16W'  | '0402LF'  | 'CHIP'   | 'CS31542FB02'(!)        = ''              | ''                 | 'CS31542FB02'           |'R0402'| '(R0402-0201)'                 | '15.4K'   | '1%'    | '1/16W'  | 'DISCRETE' | 'RES CHIP 15.4K 1/16W +-1%(0402)EF'                | 'CHIPR0402'    | ''          | ''            | '20210715'
 '15.4K'      | '1%'      | '1/16W'  | '0402LF'  | 'EMPTY'  | 'CS31542FB02'(!)        = ''              | ''                 | 'CS31542FB02'           |'R0402'| '(R0402-0201)'                 | '15.4K'   | '1%'    | '1/16W'  | 'IO'       | 'RES CHIP 15.4K 1/16W +-1%(0402)EF'                | 'CHIPR0402'    | ''          | ''            | '20210715'
 '18.2K'      | '0.1%'    | '1/16W'  | '0402LF'  | 'CHIP'   | 'CS31822BB01'(!)        = ''              | ''                 | 'CS31822BB01'           |'R0402'| '(R0402-0201)'                 | '18.2K'   | '0.1%'  | '1/16W'  | 'DISCRETE' | 'RES CHIP 18.2K 1/16W +-0.1%(0402)EF'              | 'CHIPR0402'    | ''          | ''            | '20210715'
 '18.2K'      | '0.1%'    | '1/16W'  | '0402LF'  | 'EMPTY'  | 'CS31822BB01'(!)        = ''              | ''                 | 'CS31822BB01'           |'R0402'| '(R0402-0201)'                 | '18.2K'   | '0.1%'  | '1/16W'  | 'IO'       | 'RES CHIP 18.2K 1/16W +-0.1%(0402)EF'              | 'CHIPR0402'    | ''          | ''            | '20210715'
 '127K'       | '1%'      | '1/16W'  | '0402LF'  | 'CHIP'   | 'CS41272FB07'(!)        = ''              | ''                 | 'CS41272FB07'           |'R0402'| '(R0402-0201)'                 | '127K'    | '1%'    | '1/16W'  | 'DISCRETE' | 'RES CHIP 127K 1/16W +-1%(0402)EF'                 | 'CHIPR0402'    | ''          | ''            | '20210715'
 '127K'       | '1%'      | '1/16W'  | '0402LF'  | 'EMPTY'  | 'CS41272FB07'(!)        = ''              | ''                 | 'CS41272FB07'           |'R0402'| '(R0402-0201)'                 | '127K'    | '1%'    | '1/16W'  | 'IO'       | 'RES CHIP 127K 1/16W +-1%(0402)EF'                 | 'CHIPR0402'    | ''          | ''            | '20210715'
 '0'          | '5%'      | '1/4W'   | '1206LF'  | 'CHIP'   | 'CS00006J207'(!)        = 'End of Design' | 'Comp-Approve'     | 'CS00006J207'           |'R1206XF'| '(SMR1206AW)'                  | '0'       | '5%'    | '1/4W'   | 'DISCRETE' | 'RES CHIP 0 1/4W +-5%(1206)EF'                     | 'CHIPR1206'    | ''          | ''            | '20210715'
 '0'          | '5%'      | '1/4W'   | '1206LF'  | 'EMPTY'  | 'CS00006J207'(!)        = 'End of Design' | 'Comp-Approve'     | 'CS00006J207'           |'R1206XF'| '(SMR1206AW)'                  | '0'       | '5%'    | '1/4W'   | 'IO'       | 'RES CHIP 0 1/4W +-5%(1206)EF'                     | 'CHIPR1206'    | ''          | ''            | '20210715'
 '3.3'        | '1%'      | '1/16W'  | '0402LF'  | 'CHIP'   | 'CS-3302FB01'(!)        = 'End of Design' | 'Comp-Approve'     | 'CS-3302FB01'           |'R0402'| '(R0402-0201)'                 | '3.3'     | '1%'    | '1/16W'  | 'DISCRETE' | 'RES CHIP 3.3 1/16W +-1%(0402)EF'                  | 'CHIPR0402'    | ''          | ''            | '20210715'
 '3.3'        | '1%'      | '1/16W'  | '0402LF'  | 'EMPTY'  | 'CS-3302FB01'(!)        = 'End of Design' | 'Comp-Approve'     | 'CS-3302FB01'           |'R0402'| '(R0402-0201)'                 | '3.3'     | '1%'    | '1/16W'  | 'IO'       | 'RES CHIP 3.3 1/16W +-1%(0402)EF'                  | 'CHIPR0402'    | ''          | ''            | '20210715'
 '470'        | '1%'      | '1/16W'  | '0402LF'  | 'CHIP'   | 'CS14702FB04'(!)        = 'End of Design' | 'Comp-Approve'     | 'CS14702FB04'           |'R0402'| '(R0402-0201)'                 | '470'     | '1%'    | '1/16W'  | 'DISCRETE' | 'RES CHIP 470 1/16W +-1%(0402)EF'                  | 'CHIPR0402'    | ''          | ''            | '20210715'
 '470'        | '1%'      | '1/16W'  | '0402LF'  | 'EMPTY'  | 'CS14702FB04'(!)        = 'End of Design' | 'Comp-Approve'     | 'CS14702FB04'           |'R0402'| '(R0402-0201)'                 | '470'     | '1%'    | '1/16W'  | 'IO'       | 'RES CHIP 470 1/16W +-1%(0402)EF'                  | 'CHIPR0402'    | ''          | ''            | '20210715'
 '3.9K'       | '5%'      | '1/16W'  | '0402LF'  | 'CHIP'   | 'CS23902JB04'(!)        = 'End of Design' | 'Comp-Approve'     | 'CS23902JB04'           |'R0402'| '(R0402-0201)'                 | '3.9K'    | '5%'    | '1/16W'  | 'DISCRETE' | 'RES CHIP 3.9K 1/16W +-5%(0402)EF'                 | 'CHIPR0402'    | ''          | ''            | '20210715'
 '3.9K'       | '5%'      | '1/16W'  | '0402LF'  | 'EMPTY'  | 'CS23902JB04'(!)        = 'End of Design' | 'Comp-Approve'     | 'CS23902JB04'           |'R0402'| '(R0402-0201)'                 | '3.9K'    | '5%'    | '1/16W'  | 'IO'       | 'RES CHIP 3.9K 1/16W +-5%(0402)EF'                 | 'CHIPR0402'    | ''          | ''            | '20210715'
 '4.32K'      | '1%'      | '1/16W'  | '0402LF'  | 'CHIP'   | 'CS24322FB03'(!)        = 'End of Design' | 'Comp-Approve'     | 'CS24322FB03'           |'R0402'| '(R0402-0201)'                 | '4.32K'   | '1%'    | '1/16W'  | 'DISCRETE' | 'RES CHIP 4.32K 1/16W +-1%(0402)EF'                | 'CHIPR0402'    | ''          | ''            | '20210715'
 '4.32K'      | '1%'      | '1/16W'  | '0402LF'  | 'EMPTY'  | 'CS24322FB03'(!)        = 'End of Design' | 'Comp-Approve'     | 'CS24322FB03'           |'R0402'| '(R0402-0201)'                 | '4.32K'   | '1%'    | '1/16W'  | 'IO'       | 'RES CHIP 4.32K 1/16W +-1%(0402)EF'                | 'CHIPR0402'    | ''          | ''            | '20210715'
 '9.09K'      | '1%'      | '1/16W'  | '0402LF'  | 'CHIP'   | 'CS29092FB05'(!)        = 'End of Design' | 'Comp-Approve'     | 'CS29092FB05'           |'R0402'| '(R0402-0201)'                 | '9.09K'   | '1%'    | '1/16W'  | 'DISCRETE' | 'RES CHIP 9.09K 1/16W +-1%(0402)EF'                | 'CHIPR0402'    | ''          | ''            | '20210715'
 '9.09K'      | '1%'      | '1/16W'  | '0402LF'  | 'EMPTY'  | 'CS29092FB05'(!)        = 'End of Design' | 'Comp-Approve'     | 'CS29092FB05'           |'R0402'| '(R0402-0201)'                 | '9.09K'   | '1%'    | '1/16W'  | 'IO'       | 'RES CHIP 9.09K 1/16W +-1%(0402)EF'                | 'CHIPR0402'    | ''          | ''            | '20210715'
 '30.1K'      | '1%'      | '1/16W'  | '0402LF'  | 'CHIP'   | 'CS33012FB03'(!)        = 'End of Design' | 'Comp-Approve'     | 'CS33012FB03'           |'R0402'| '(R0402-0201)'                 | '30.1K'   | '1%'    | '1/16W'  | 'DISCRETE' | 'RES CHIP 30.1K 1/16W +-1%(0402)EF'                | 'CHIPR0402'    | ''          | ''            | '20210715'
 '30.1K'      | '1%'      | '1/16W'  | '0402LF'  | 'EMPTY'  | 'CS33012FB03'(!)        = 'End of Design' | 'Comp-Approve'     | 'CS33012FB03'           |'R0402'| '(R0402-0201)'                 | '30.1K'   | '1%'    | '1/16W'  | 'IO'       | 'RES CHIP 30.1K 1/16W +-1%(0402)EF'                | 'CHIPR0402'    | ''          | ''            | '20210715'
 '84.5K'      | '1%'      | '1/16W'  | '0402LF'  | 'CHIP'   | 'CS38452FB05'(!)        = 'End of Design' | 'Comp-Approve'     | 'CS38452FB05'           |'R0402'| '(R0402-0201)'                 | '84.5K'   | '1%'    | '1/16W'  | 'DISCRETE' | 'RES CHIP 84.5K 1/16W +-1%(0402)EF'                | 'CHIPR0402'    | ''          | ''            | '20210715'
 '84.5K'      | '1%'      | '1/16W'  | '0402LF'  | 'EMPTY'  | 'CS38452FB05'(!)        = 'End of Design' | 'Comp-Approve'     | 'CS38452FB05'           |'R0402'| '(R0402-0201)'                 | '84.5K'   | '1%'    | '1/16W'  | 'IO'       | 'RES CHIP 84.5K 1/16W +-1%(0402)EF'                | 'CHIPR0402'    | ''          | ''            | '20210715'
 '196K'       | '1%'      | '1/16W'  | '0402LF'  | 'CHIP'   | 'CS41962FB03'(!)        = 'End of Design' | 'Comp-Approve'     | 'CS41962FB03'           |'R0402'| '(R0402-0201)'                 | '196K'    | '1%'    | '1/16W'  | 'DISCRETE' | 'RES CHIP 196K 1/16W +-1%(0402)EF'                 | 'CHIPR0402'    | ''          | ''            | '20210715'
 '196K'       | '1%'      | '1/16W'  | '0402LF'  | 'EMPTY'  | 'CS41962FB03'(!)        = 'End of Design' | 'Comp-Approve'     | 'CS41962FB03'           |'R0402'| '(R0402-0201)'                 | '196K'    | '1%'    | '1/16W'  | 'IO'       | 'RES CHIP 196K 1/16W +-1%(0402)EF'                 | 'CHIPR0402'    | ''          | ''            | '20210715'
 '18K'        | '1%'      | '1/16W'  | '0402LF'  | 'CHIP'   | 'CS31802FB04'(!)        = ''              | ''                 | 'CS31802FB04'           |'R0402'| '(R0402-0201)'                 | '18K'     | '1%'    | '1/16W'  | 'DISCRETE' | 'RES CHIP 18K 1/16W +-1%(0402)EF'                  | 'CHIPR0402'    | ''          | ''            | '20210719'
 '18K'        | '1%'      | '1/16W'  | '0402LF'  | 'EMPTY'  | 'CS31802FB04'(!)        = ''              | ''                 | 'CS31802FB04'           |'R0402'| '(R0402-0201)'                 | '18K'     | '1%'    | '1/16W'  | 'IO'       | 'RES CHIP 18K 1/16W +-1%(0402)EF'                  | 'CHIPR0402'    | ''          | ''            | '20210719'
 '4.7'        | '1%'      | '1/16W'  | '0402LF'  | 'CHIP'   | 'CS-4702FB09'(!)        = ''              | ''                 | 'CS-4702FB09'           |'R0402'| '(R0402-0201)'                 | '4.7'     | '1%'    | '1/16W'  | 'DISCRETE' | 'RES CHIP 4.7 1/16W +-1%(0402)EF'                  | 'CHIPR0402'    | ''          | ''            | '20210719'
 '4.7'        | '1%'      | '1/16W'  | '0402LF'  | 'EMPTY'  | 'CS-4702FB09'(!)        = ''              | ''                 | 'CS-4702FB09'           |'R0402'| '(R0402-0201)'                 | '4.7'     | '1%'    | '1/16W'  | 'IO'       | 'RES CHIP 4.7 1/16W +-1%(0402)EF'                  | 'CHIPR0402'    | ''          | ''            | '20210719'
 '5.23K'      | '1%'      | '1/16W'  | '0402LF'  | 'CHIP'   | 'CS25232FB08'(!)        = ''              | ''                 | 'CS25232FB08'           |'R0402'| '(R0402-0201)'                 | '5.23K'   | '1%'    | '1/16W'  | 'DISCRETE' | 'RES CHIP 5.23K 1/16W +-1%(0402)EF'                | 'CHIPR0402'    | ''          | ''            | '20210719'
 '5.23K'      | '1%'      | '1/16W'  | '0402LF'  | 'EMPTY'  | 'CS25232FB08'(!)        = ''              | ''                 | 'CS25232FB08'           |'R0402'| '(R0402-0201)'                 | '5.23K'   | '1%'    | '1/16W'  | 'IO'       | 'RES CHIP 5.23K 1/16W +-1%(0402)EF'                | 'CHIPR0402'    | ''          | ''            | '20210719'
 '7.32K'      | '0.1%'    | '1/16W'  | '0402LF'  | 'CHIP'   | 'CS27322BB09'(!)        = ''              | ''                 | 'CS27322BB09'           |'R0402'| '(R0402-0201)'                 | '7.32K'   | '0.1%'  | '1/16W'  | 'DISCRETE' | 'RES CHIP 7.32K 1/16W +-0.1% (0402)EF'             | 'CHIPR0402'    | ''          | ''            | '20210719'
 '7.32K'      | '0.1%'    | '1/16W'  | '0402LF'  | 'EMPTY'  | 'CS27322BB09'(!)        = ''              | ''                 | 'CS27322BB09'           |'R0402'| '(R0402-0201)'                 | '7.32K'   | '0.1%'  | '1/16W'  | 'IO'       | 'RES CHIP 7.32K 1/16W +-0.1% (0402)EF'             | 'CHIPR0402'    | ''          | ''            | '20210719'
 '11.8K'      | '0.1%'    | '1/16W'  | '0402LF'  | 'CHIP'   | 'CS31182BB06'(!)        = ''              | ''                 | 'CS31182BB06'           |'R0402'| '(R0402-0201)'                 | '11.8K'   | '0.1%'  | '1/16W'  | 'DISCRETE' | 'RES CHIP 11.8K 1/16W +-0.1%(0402)EF'              | 'CHIPR0402'    | ''          | ''            | '20210719'
 '11.8K'      | '0.1%'    | '1/16W'  | '0402LF'  | 'EMPTY'  | 'CS31182BB06'(!)        = ''              | ''                 | 'CS31182BB06'           |'R0402'| '(R0402-0201)'                 | '11.8K'   | '0.1%'  | '1/16W'  | 'IO'       | 'RES CHIP 11.8K 1/16W +-0.1%(0402)EF'              | 'CHIPR0402'    | ''          | ''            | '20210719'
 '12.4K'      | '0.1%'    | '1/16W'  | '0402LF'  | 'CHIP'   | 'CS31242BB10'(!)        = ''              | ''                 | 'CS31242BB10'           |'R0402'| '(R0402-0201)'                 | '12.4K'   | '0.1%'  | '1/16W'  | 'DISCRETE' | 'RES CHIP 12.4K 1/16W +-0.1%( 0402)EF'             | 'CHIPR0402'    | ''          | ''            | '20210719'
 '12.4K'      | '0.1%'    | '1/16W'  | '0402LF'  | 'EMPTY'  | 'CS31242BB10'(!)        = ''              | ''                 | 'CS31242BB10'           |'R0402'| '(R0402-0201)'                 | '12.4K'   | '0.1%'  | '1/16W'  | 'IO'       | 'RES CHIP 12.4K 1/16W +-0.1%( 0402)EF'             | 'CHIPR0402'    | ''          | ''            | '20210719'
 '26.1K'      | '0.1%'    | '1/16W'  | '0402LF'  | 'CHIP'   | 'CS32612BB02'(!)        = ''              | ''                 | 'CS32612BB02'           |'R0402'| '(R0402-0201)'                 | '26.1K'   | '0.1%'  | '1/16W'  | 'DISCRETE' | 'RES CHIP 26.1K 1/16W +-0.1%(0402)EF'              | 'CHIPR0402'    | ''          | ''            | '20210720'
 '26.1K'      | '0.1%'    | '1/16W'  | '0402LF'  | 'EMPTY'  | 'CS32612BB02'(!)        = ''              | ''                 | 'CS32612BB02'           |'R0402'| '(R0402-0201)'                 | '26.1K'   | '0.1%'  | '1/16W'  | 'IO'       | 'RES CHIP 26.1K 1/16W +-0.1%(0402)EF'              | 'CHIPR0402'    | ''          | ''            | '20210720'
 '36K'        | '0.1%'    | '1/16W'  | '0402LF'  | 'CHIP'   | 'CS33602BB01'(!)        = ''              | ''                 | 'CS33602BB01'           |'R0402'| '(R0402-0201)'                 | '36K'     | '0.1%'  | '1/16W'  | 'DISCRETE' | 'RES CHIP 36K 1/16W +-0.1%(0402)EF'                | 'CHIPR0402'    | ''          | ''            | '20210720'
 '36K'        | '0.1%'    | '1/16W'  | '0402LF'  | 'EMPTY'  | 'CS33602BB01'(!)        = ''              | ''                 | 'CS33602BB01'           |'R0402'| '(R0402-0201)'                 | '36K'     | '0.1%'  | '1/16W'  | 'IO'       | 'RES CHIP 36K 1/16W +-0.1%(0402)EF'                | 'CHIPR0402'    | ''          | ''            | '20210720'
 '23.2K'      | '1%'      | '1/16W'  | '0402LF'  | 'CHIP'   | 'CS32322FB03'(!)        = 'End of Design' | 'Comp-Approve'     | 'CS32322FB03'           |'R0402'| '(R0402-0201)'                 | '23.2K'   | '1%'    | '1/16W'  | 'DISCRETE' | 'RES CHIP 23.2K 1/16W +-1%(0402)EF'                | 'CHIPR0402'    | ''          | ''            | '20210720'
 '23.2K'      | '1%'      | '1/16W'  | '0402LF'  | 'EMPTY'  | 'CS32322FB03'(!)        = 'End of Design' | 'Comp-Approve'     | 'CS32322FB03'           |'R0402'| '(R0402-0201)'                 | '23.2K'   | '1%'    | '1/16W'  | 'IO'       | 'RES CHIP 23.2K 1/16W +-1%(0402)EF'                | 'CHIPR0402'    | ''          | ''            | '20210720'
 '0.003'      | '1%'      | '3W'     | '2512LF'  | 'CHIP'   | 'CS+003DFR06'(!)        = ''              | ''                 | 'CS+003DFR06'           |'R2512XZ'| '(SMR2512AW)'                  | '0.003'   | '1%'    | '3W'     | 'DISCRETE' | 'RES CHIP 0.003 3W +-1%(2512)CYN'                  | 'CHIPR2512'    | ''          | ''            | '20210727'
 '0.003'      | '1%'      | '3W'     | '2512LF'  | 'EMPTY'  | 'CS+003DFR06'(!)        = ''              | ''                 | 'CS+003DFR06'           |'R2512XZ'| '(SMR2512AW)'                  | '0.003'   | '1%'    | '3W'     | 'IO'       | 'RES CHIP 0.003 3W +-1%(2512)CYN'                  | 'CHIPR2512'    | ''          | ''            | '20210727'
 '316'        | '1%'      | '1/16W'  | '0402LF'  | 'CHIP'   | 'CS13162FB01'(!)        = ''              | ''                 | 'CS13162FB01'           |'R0402'| '(R0402-0201)'                 | '316'     | '1%'    | '1/16W'  | 'DISCRETE' | 'RES CHIP 316 1/16W +-1%(0402)EF'                  | 'CHIPR0402'    | ''          | ''            | '20210727'
 '316'        | '1%'      | '1/16W'  | '0402LF'  | 'EMPTY'  | 'CS13162FB01'(!)        = ''              | ''                 | 'CS13162FB01'           |'R0402'| '(R0402-0201)'                 | '316'     | '1%'    | '1/16W'  | 'IO'       | 'RES CHIP 316 1/16W +-1%(0402)EF'                  | 'CHIPR0402'    | ''          | ''            | '20210727'
 '1K'         | '5%'      | '1/4W'   | '1206LF'  | 'CHIP'   | 'CS21006J202'(!)        = ''              | ''                 | 'CS21006J202'           |'R1206XN'| '(SMR1206AW)'                  | '1K'      | '5%'    | '1/4W'   | 'DISCRETE' | 'RES CHIP 1K 1/4W +-5%(1206)EF'                    | 'CHIPR1206'    | ''          | ''            | '20210727'
 '1K'         | '5%'      | '1/4W'   | '1206LF'  | 'EMPTY'  | 'CS21006J202'(!)        = ''              | ''                 | 'CS21006J202'           |'R1206XN'| '(SMR1206AW)'                  | '1K'      | '5%'    | '1/4W'   | 'IO'       | 'RES CHIP 1K 1/4W +-5%(1206)EF'                    | 'CHIPR1206'    | ''          | ''            | '20210727'
 '2.2K'       | '0.1%'    | '1/16W'  | '0402LF'  | 'CHIP'   | 'CS22202BB02'(!)        = ''              | ''                 | 'CS22202BB02'           |'R0402'| '(R0402-0201)'                 | '2.2K'    | '0.1%'  | '1/16W'  | 'DISCRETE' | 'RES CHIP 2.2K 1/16W +-0.1%(0402)'                 | 'CHIPR0402'    | ''          | ''            | '20210730'
 '2.2K'       | '0.1%'    | '1/16W'  | '0402LF'  | 'EMPTY'  | 'CS22202BB02'(!)        = ''              | ''                 | 'CS22202BB02'           |'R0402'| '(R0402-0201)'                 | '2.2K'    | '0.1%'  | '1/16W'  | 'IO'       | 'RES CHIP 2.2K 1/16W +-0.1%(0402)'                 | 'CHIPR0402'    | ''          | ''            | '20210730'
 '0.05'       | '1%'      | '1/2W'   | '1206LF'  | 'CHIP'   | 'CS+0507F200'(!)        = ''              | ''                 | 'CS+0507F200'           |'R1206XQ'| '(SMR1206AW)'                  | '0.05'    | '1%'    | '1/2W'   | 'DISCRETE' | 'RES CHIP 0.05 1/2W +-1%(1206)'                    | 'CHIPR1206'    | ''          | ''            | '20210802'
 '0.05'       | '1%'      | '1/2W'   | '1206LF'  | 'EMPTY'  | 'CS+0507F200'(!)        = ''              | ''                 | 'CS+0507F200'           |'R1206XQ'| '(SMR1206AW)'                  | '0.05'    | '1%'    | '1/2W'   | 'IO'       | 'RES CHIP 0.05 1/2W +-1%(1206)'                    | 'CHIPR1206'    | ''          | ''            | '20210802'
 '27.4'       | '1%'      | '1/20W'  | '0201LF'  | 'CHIP'   | 'CS02741FE02'(!)        = ''              | ''                 | 'CS02741FE02'           |'R0201'| '(SMR0201AW)'                  | '27.4'    | '1%'    | '1/20W'  | 'DISCRETE' | 'RES CHIP 27.4 1/20W +-1%(0201)EF'                 | 'CHIPR0201'    | ''          | ''            | '20210804'
 '27.4'       | '1%'      | '1/20W'  | '0201LF'  | 'EMPTY'  | 'CS02741FE02'(!)        = ''              | ''                 | 'CS02741FE02'           |'R0201'| '(SMR0201AW)'                  | '27.4'    | '1%'    | '1/20W'  | 'IO'       | 'RES CHIP 27.4 1/20W +-1%(0201)EF'                 | 'CHIPR0201'    | ''          | ''            | '20210804'
 '1.5K'       | '1%'      | '1/20W'  | '0201LF'  | 'CHIP'   | 'CS21501FE14'(!)        = ''              | ''                 | 'CS21501FE14'           |'R0201'| '(SMR0201AW)'                  | '1.5K'    | '1%'    | '1/20W'  | 'DISCRETE' | 'RES CHIP 1.5K 1/20W +-1%(0201)EF'                 | 'CHIPR0201'    | ''          | ''            | '20210804'
 '1.5K'       | '1%'      | '1/20W'  | '0201LF'  | 'EMPTY'  | 'CS21501FE14'(!)        = ''              | ''                 | 'CS21501FE14'           |'R0201'| '(SMR0201AW)'                  | '1.5K'    | '1%'    | '1/20W'  | 'IO'       | 'RES CHIP 1.5K 1/20W +-1%(0201)EF'                 | 'CHIPR0201'    | ''          | ''            | '20210804'
 '1.24K'      | '1%'      | '1/16W'  | '0402LF'  | 'CHIP'   | 'CS21242FB04'(!)        = 'End of Design' | 'Comp-Approve'     | 'CS21242FB04'           |'R0402'| '(R0402-0201)'                 | '1.24K'   | '1%'    | '1/16W'  | 'DISCRETE' | 'RES CHIP 1.24K 1/16W +-1%(0402)EF'                | 'CHIPR0402'    | ''          | ''            | '20210804'
 '1.24K'      | '1%'      | '1/16W'  | '0402LF'  | 'EMPTY'  | 'CS21242FB04'(!)        = 'End of Design' | 'Comp-Approve'     | 'CS21242FB04'           |'R0402'| '(R0402-0201)'                 | '1.24K'   | '1%'    | '1/16W'  | 'IO'       | 'RES CHIP 1.24K 1/16W +-1%(0402)EF'                | 'CHIPR0402'    | ''          | ''            | '20210804'
 '1.69K'      | '1%'      | '1/16W'  | '0402LF'  | 'CHIP'   | 'CS21692FB04'(!)        = 'End of Design' | 'Comp-Approve'     | 'CS21692FB04'           |'R0402'| '(R0402-0201)'                 | '1.69K'   | '1%'    | '1/16W'  | 'DISCRETE' | 'RES CHIP 1.69K 1/16W +-1%(0402)EF'                | 'CHIPR0402'    | ''          | ''            | '20210804'
 '1.69K'      | '1%'      | '1/16W'  | '0402LF'  | 'EMPTY'  | 'CS21692FB04'(!)        = 'End of Design' | 'Comp-Approve'     | 'CS21692FB04'           |'R0402'| '(R0402-0201)'                 | '1.69K'   | '1%'    | '1/16W'  | 'IO'       | 'RES CHIP 1.69K 1/16W +-1%(0402)EF'                | 'CHIPR0402'    | ''          | ''            | '20210804'
 '2.74K'      | '1%'      | '1/16W'  | '0402LF'  | 'CHIP'   | 'CS22742FB05'(!)        = 'End of Design' | 'Comp-Approve'     | 'CS22742FB05'           |'R0402'| '(R0402-0201)'                 | '2.74K'   | '1%'    | '1/16W'  | 'DISCRETE' | 'RES CHIP 2.74K 1/16W +-1%(0402)EF'                | 'CHIPR0402'    | ''          | ''            | '20210804'
 '2.74K'      | '1%'      | '1/16W'  | '0402LF'  | 'EMPTY'  | 'CS22742FB05'(!)        = 'End of Design' | 'Comp-Approve'     | 'CS22742FB05'           |'R0402'| '(R0402-0201)'                 | '2.74K'   | '1%'    | '1/16W'  | 'IO'       | 'RES CHIP 2.74K 1/16W +-1%(0402)EF'                | 'CHIPR0402'    | ''          | ''            | '20210804'
 '5.49K'      | '1%'      | '1/16W'  | '0402LF'  | 'CHIP'   | 'CS25492FB02'(!)        = 'End of Design' | 'Comp-Approve'     | 'CS25492FB02'           |'R0402'| '(R0402-0201)'                 | '5.49K'   | '1%'    | '1/16W'  | 'DISCRETE' | 'RES CHIP 5.49K 1/16W +-1%(0402) EF'               | 'CHIPR0402'    | ''          | ''            | '20210804'
 '5.49K'      | '1%'      | '1/16W'  | '0402LF'  | 'EMPTY'  | 'CS25492FB02'(!)        = 'End of Design' | 'Comp-Approve'     | 'CS25492FB02'           |'R0402'| '(R0402-0201)'                 | '5.49K'   | '1%'    | '1/16W'  | 'IO'       | 'RES CHIP 5.49K 1/16W +-1%(0402) EF'               | 'CHIPR0402'    | ''          | ''            | '20210804'
 '680'        | '0.1%'    | '1/16W'  | '0402LF'  | 'CHIP'   | 'CS16802BB00'(!)        = ''              | ''                 | 'CS16802BB00'           |'R0402'| '(R0402-0201)'                 | '680'     | '0.1%'  | '1/16W'  | 'DISCRETE' | 'RES CHIP 680 1/16W +-0.1%(0402)'                  | 'CHIPR0402'    | ''          | ''            | '20210804'
 '680'        | '0.1%'    | '1/16W'  | '0402LF'  | 'EMPTY'  | 'CS16802BB00'(!)        = ''              | ''                 | 'CS16802BB00'           |'R0402'| '(R0402-0201)'                 | '680'     | '0.1%'  | '1/16W'  | 'IO'       | 'RES CHIP 680 1/16W +-0.1%(0402)'                  | 'CHIPR0402'    | ''          | ''            | '20210804'
 '15K'        | '1%'      | '1/16W'  | '0402LF'  | 'CHIP'   | 'CS31502FB12'(!)        = ''              | ''                 | 'CS31502FB12'           |'R0402'| '(R0402-0201)'                 | '15K'     | '1%'    | '1/16W'  | 'DISCRETE' | 'RES CHIP 15K 1/16W +-1%(0402)TAI'                 | 'CHIPR0402'    | ''          | ''            | '20210809'
 '15K'        | '1%'      | '1/16W'  | '0402LF'  | 'EMPTY'  | 'CS31502FB12'(!)        = ''              | ''                 | 'CS31502FB12'           |'R0402'| '(R0402-0201)'                 | '15K'     | '1%'    | '1/16W'  | 'IO'       | 'RES CHIP 15K 1/16W +-1%(0402)TAI'                 | 'CHIPR0402'    | ''          | ''            | '20210809'
 '1.65K'      | '0.1%'    | '1/16W'  | '0402LF'  | 'CHIP'   | 'CS21652BB00'(!)        = ''              | ''                 | 'CS21652BB00'           |'R0402'| '(R0402-0201)'                 | '1.65K'   | '0.1%'  | '1/16W'  | 'DISCRETE' | 'RES CHIP 1.65K 1/16W +-0.1%(0402)'                | 'CHIPR0402'    | ''          | ''            | '20210811'
 '1.65K'      | '0.1%'    | '1/16W'  | '0402LF'  | 'EMPTY'  | 'CS21652BB00'(!)        = ''              | ''                 | 'CS21652BB00'           |'R0402'| '(R0402-0201)'                 | '1.65K'   | '0.1%'  | '1/16W'  | 'IO'       | 'RES CHIP 1.65K 1/16W +-0.1%(0402)'                | 'CHIPR0402'    | ''          | ''            | '20210811'
 '2.87K'      | '0.1%'    | '1/16W'  | '0402LF'  | 'CHIP'   | 'CS22872BB01'(!)        = ''              | ''                 | 'CS22872BB01'           |'R0402'| '(R0402-0201)'                 | '2.87K'   | '0.1%'  | '1/16W'  | 'DISCRETE' | 'RES CHIP 2.87K 1/16W+-0.1%( 0402)'                | 'CHIPR0402'    | ''          | ''            | '20210811'
 '2.87K'      | '0.1%'    | '1/16W'  | '0402LF'  | 'EMPTY'  | 'CS22872BB01'(!)        = ''              | ''                 | 'CS22872BB01'           |'R0402'| '(R0402-0201)'                 | '2.87K'   | '0.1%'  | '1/16W'  | 'IO'       | 'RES CHIP 2.87K 1/16W+-0.1%( 0402)'                | 'CHIPR0402'    | ''          | ''            | '20210811'
 '1.13K'      | '0.1%'    | '1/16W'  | '0402LF'  | 'CHIP'   | 'CS21132BB00'(!)        = ''              | ''                 | 'CS21132BB00'           |'R0402'| '(R0402-0201)'                 | '1.13K'   | '0.1%'  | '1/16W'  | 'DISCRETE' | 'RES CHIP 1.13K 1/16W+-0.1%( 0402)'                | 'CHIPR0402'    | ''          | ''            | '20210811'
 '1.13K'      | '0.1%'    | '1/16W'  | '0402LF'  | 'EMPTY'  | 'CS21132BB00'(!)        = ''              | ''                 | 'CS21132BB00'           |'R0402'| '(R0402-0201)'                 | '1.13K'   | '0.1%'  | '1/16W'  | 'IO'       | 'RES CHIP 1.13K 1/16W+-0.1%( 0402)'                | 'CHIPR0402'    | ''          | ''            | '20210811'
 '4.53K'      | '0.1%'    | '1/16W'  | '0402LF'  | 'CHIP'   | 'CS24532BB00'(!)        = ''              | ''                 | 'CS24532BB00'           |'R0402'| '(R0402-0201)'                 | '4.53K'   | '0.1%'  | '1/16W'  | 'DISCRETE' | 'RES CHIP 4.53K 1/16W+-0.1%( 0402)'                | 'CHIPR0402'    | ''          | ''            | '20210811'
 '4.53K'      | '0.1%'    | '1/16W'  | '0402LF'  | 'EMPTY'  | 'CS24532BB00'(!)        = ''              | ''                 | 'CS24532BB00'           |'R0402'| '(R0402-0201)'                 | '4.53K'   | '0.1%'  | '1/16W'  | 'IO'       | 'RES CHIP 4.53K 1/16W+-0.1%( 0402)'                | 'CHIPR0402'    | ''          | ''            | '20210811'
 '360'        | '1%'      | '1/16W'  | '0402LF'  | 'CHIP'   | 'CS13602FB00'(!)        = 'End of Design' | 'Comp-Approve'     | 'CS13602FB00'           |'R0402'| '(R0402-0201)'                 | '360'     | '1%'    | '1/16W'  | 'DISCRETE' | 'RES CHIP 360 1/16W +-1%(0402)'                    | 'CHIPR0402'    | ''          | ''            | '20210817'
 '360'        | '1%'      | '1/16W'  | '0402LF'  | 'EMPTY'  | 'CS13602FB00'(!)        = 'End of Design' | 'Comp-Approve'     | 'CS13602FB00'           |'R0402'| '(R0402-0201)'                 | '360'     | '1%'    | '1/16W'  | 'IO'       | 'RES CHIP 360 1/16W +-1%(0402)'                    | 'CHIPR0402'    | ''          | ''            | '20210817'
 '0.0002'     | '1%'      | '4W'     | '2725LF'  | 'CHIP'   | 'CS0000FFT11'(!)        = ''              | ''                 | 'CS0000FFT11'           |'R2725'| '(SMR2725AW)'                  | '0.0002'  | '1%'    | '4W'     | 'DISCRETE' | 'RES CHIP 0.0002 4W +-1%(2725)RLC'                 | 'CHIPR2725'    | ''          | ''            | '20210817'
 '0.0002'     | '1%'      | '4W'     | '2725LF'  | 'EMPTY'  | 'CS0000FFT11'(!)        = ''              | ''                 | 'CS0000FFT11'           |'R2725'| '(SMR2725AW)'                  | '0.0002'  | '1%'    | '4W'     | 'IO'       | 'RES CHIP 0.0002 4W +-1%(2725)RLC'                 | 'CHIPR2725'    | ''          | ''            | '20210817'
 '10K'        | '1%'      | '1/2W'   | '1206LF'  | 'CHIP'   | 'CS31007F200'(!)        = ''              | ''                 | 'CS31007F200'           |'R1206XI'| '(SMR1206AW)'                  | '10K'     | '1%'    | '1/2W'   | 'DISCRETE' | 'RES CHIP 10K 1/2W +-1%(1206)'                     | 'CHIPR1206'    | ''          | ''            | '20210820'
 '10K'        | '1%'      | '1/2W'   | '1206LF'  | 'EMPTY'  | 'CS31007F200'(!)        = ''              | ''                 | 'CS31007F200'           |'R1206XI'| '(SMR1206AW)'                  | '10K'     | '1%'    | '1/2W'   | 'IO'       | 'RES CHIP 10K 1/2W +-1%(1206)'                     | 'CHIPR1206'    | ''          | ''            | '20210820'
 '20K'        | '0.1%'    | '1/4W'   | '1206LF'  | 'CHIP'   | 'CS32006B200'(!)        = ''              | ''                 | 'CS32006B200'           |'R1206XM'| '(SMR1206AW)'                  | '20K'     | '0.1%'  | '1/4W'   | 'DISCRETE' | 'RES CHIP 20K 1/4W +-0.1%(1206)'                   | 'CHIPR1206'    | ''          | ''            | '20210823'
 '20K'        | '0.1%'    | '1/4W'   | '1206LF'  | 'EMPTY'  | 'CS32006B200'(!)        = ''              | ''                 | 'CS32006B200'           |'R1206XM'| '(SMR1206AW)'                  | '20K'     | '0.1%'  | '1/4W'   | 'IO'       | 'RES CHIP 20K 1/4W +-0.1%(1206)'                   | 'CHIPR1206'    | ''          | ''            | '20210823'
 '20K'        | '1%'      | '1/8W'   | '0805LF'  | 'CHIP'   | 'CS32004FA05'(!)        = ''              | ''                 | 'CS32004FA05'           |'R0805_H26'| '(SMR0805AW)'                  | '20K'     | '1%'    | '1/8W'   | 'DISCRETE' | 'RES CHIP 20K 1/8W +-1%(0805)EF'                   | 'CHIPR0805'    | ''          | ''            | '20210824'
 '20K'        | '1%'      | '1/8W'   | '0805LF'  | 'EMPTY'  | 'CS32004FA05'(!)        = ''              | ''                 | 'CS32004FA05'           |'R0805_H26'| '(SMR0805AW)'                  | '20K'     | '1%'    | '1/8W'   | 'IO'       | 'RES CHIP 20K 1/8W +-1%(0805)EF'                   | 'CHIPR0805'    | ''          | ''            | '20210824'
 '100'        | '1%'      | '1/8W'   | '0805LF'  | 'CHIP'   | 'CS11004FA05'(!)        = ''              | ''                 | 'CS11004FA05'           |'R0805_H26'| '(SMR0805AW)'                  | '100'     | '1%'    | '1/8W'   | 'DISCRETE' | 'RES CHIP 100 1/8W +-1%(0805)EF'                   | 'CHIPR0805'    | ''          | ''            | '20210824'
 '100'        | '1%'      | '1/8W'   | '0805LF'  | 'EMPTY'  | 'CS11004FA05'(!)        = ''              | ''                 | 'CS11004FA05'           |'R0805_H26'| '(SMR0805AW)'                  | '100'     | '1%'    | '1/8W'   | 'IO'       | 'RES CHIP 100 1/8W +-1%(0805)EF'                   | 'CHIPR0805'    | ''          | ''            | '20210824'
 '3.3K'       | '1%'      | '1/8W'   | '0805LF'  | 'CHIP'   | 'CS23304FA00'(!)        = ''              | ''                 | 'CS23304FA00'           |'R0805_H26'| '(SMR0805AW)'                  | '3.3K'    | '1%'    | '1/8W'   | 'DISCRETE' | 'RES CHIP 3.3K 1/8W +-1%(0805)EF'                  | 'CHIPR0805'    | ''          | ''            | '20210824'
 '3.3K'       | '1%'      | '1/8W'   | '0805LF'  | 'EMPTY'  | 'CS23304FA00'(!)        = ''              | ''                 | 'CS23304FA00'           |'R0805_H26'| '(SMR0805AW)'                  | '3.3K'    | '1%'    | '1/8W'   | 'IO'       | 'RES CHIP 3.3K 1/8W +-1%(0805)EF'                  | 'CHIPR0805'    | ''          | ''            | '20210824'
 '43K'        | '1%'      | '1/8W'   | '0805LF'  | 'CHIP'   | 'CS34304FA01'(!)        = ''              | ''                 | 'CS34304FA01'           |'R0805_H26'| '(SMR0805AW)'                  | '43K'     | '1%'    | '1/8W'   | 'DISCRETE' | 'RES CHIP 43K 1/8W +-1%(0805)EF'                   | 'CHIPR0805'    | ''          | ''            | '20210824'
 '43K'        | '1%'      | '1/8W'   | '0805LF'  | 'EMPTY'  | 'CS34304FA01'(!)        = ''              | ''                 | 'CS34304FA01'           |'R0805_H26'| '(SMR0805AW)'                  | '43K'     | '1%'    | '1/8W'   | 'IO'       | 'RES CHIP 43K 1/8W +-1%(0805)EF'                   | 'CHIPR0805'    | ''          | ''            | '20210824'
 '174K'       | '1%'      | '1/8W'   | '0805LF'  | 'CHIP'   | 'CS41744FA01'(!)        = ''              | ''                 | 'CS41744FA01'           |'R0805_H26'| '(SMR0805AW)'                  | '174K'    | '1%'    | '1/8W'   | 'DISCRETE' | 'RES CHIP 174K 1/8W +-1%(0805)EF'                  | 'CHIPR0805'    | ''          | ''            | '20210824'
 '174K'       | '1%'      | '1/8W'   | '0805LF'  | 'EMPTY'  | 'CS41744FA01'(!)        = ''              | ''                 | 'CS41744FA01'           |'R0805_H26'| '(SMR0805AW)'                  | '174K'    | '1%'    | '1/8W'   | 'IO'       | 'RES CHIP 174K 1/8W +-1%(0805)EF'                  | 'CHIPR0805'    | ''          | ''            | '20210824'
 '2.05M'      | '1%'      | '1/8W'   | '0805LF'  | 'CHIP'   | 'CS52054FA01'(!)        = ''              | ''                 | 'CS52054FA01'           |'R0805_H26'| '(SMR0805AW)'                  | '2.05M'   | '1%'    | '1/8W'   | 'DISCRETE' | 'RES CHIP 2.05M 1/8W +-1%(0805)EF'                 | 'CHIPR0805'    | ''          | ''            | '20210824'
 '2.05M'      | '1%'      | '1/8W'   | '0805LF'  | 'EMPTY'  | 'CS52054FA01'(!)        = ''              | ''                 | 'CS52054FA01'           |'R0805_H26'| '(SMR0805AW)'                  | '2.05M'   | '1%'    | '1/8W'   | 'IO'       | 'RES CHIP 2.05M 1/8W +-1%(0805)EF'                 | 'CHIPR0805'    | ''          | ''            | '20210824'
 '330K'       | '1%'      | '1/16W'  | '0402LF'  | 'CHIP'   | 'CS43302FB06'(!)        = ''              | ''                 | 'CS43302FB06'           |'R0402'| '(R0402-0201)'                 | '330K'    | '1%'    | '1/16W'  | 'DISCRETE' | 'RES CHIP 330K 1/16W +-1%(0402)EF'                 | 'CHIPR0402'    | ''          | ''            | '20210824'
 '330K'       | '1%'      | '1/16W'  | '0402LF'  | 'EMPTY'  | 'CS43302FB06'(!)        = ''              | ''                 | 'CS43302FB06'           |'R0402'| '(R0402-0201)'                 | '330K'    | '1%'    | '1/16W'  | 'IO'       | 'RES CHIP 330K 1/16W +-1%(0402)EF'                 | 'CHIPR0402'    | ''          | ''            | '20210824'
 '43K'        | '1%'      | '1/10W'  | '0603LF'  | 'CHIP'   | 'CS34303F905'(!)        = ''              | ''                 | 'CS34303F905'           |'R0603'| '(SMR0603AW)'                  | '43K'     | '1%'    | '1/10W'  | 'DISCRETE' | 'RES CHIP 43K 1/10W +-1%(0603)EF'                  | 'CHIPR0603'    | ''          | ''            | '20210824'
 '43K'        | '1%'      | '1/10W'  | '0603LF'  | 'EMPTY'  | 'CS34303F905'(!)        = ''              | ''                 | 'CS34303F905'           |'R0603'| '(SMR0603AW)'                  | '43K'     | '1%'    | '1/10W'  | 'IO'       | 'RES CHIP 43K 1/10W +-1%(0603)EF'                  | 'CHIPR0603'    | ''          | ''            | '20210824'
 '1K'         | '0.5%'    | '1/20W'  | '0201LF'  | 'CHIP'   | 'CS21001DE02'(!)        = ''              | ''                 | 'CS21001DE02'           |'R0201'| '(SMR0201AW)'                  | '1K'      | '0.5%'  | '1/20W'  | 'DISCRETE' | 'RES CHIP 1K 1/20W +-0.5%(0201)'                   | 'CHIPR0201'    | ''          | ''            | '20210825'
 '1K'         | '0.5%'    | '1/20W'  | '0201LF'  | 'EMPTY'  | 'CS21001DE02'(!)        = ''              | ''                 | 'CS21001DE02'           |'R0201'| '(SMR0201AW)'                  | '1K'      | '0.5%'  | '1/20W'  | 'IO'       | 'RES CHIP 1K 1/20W +-0.5%(0201)'                   | 'CHIPR0201'    | ''          | ''            | '20210825'
 '910'        | '1%'      | '1/2W'   | '1206LF'  | 'CHIP'   | 'CS19107F200'(!)        = ''              | ''                 | 'CS19107F200'           |'R1206XF'| '(SMR1206AW)'                  | '910'     | '1%'    | '1/2W'   | 'DISCRETE' | 'RES CHIP 910 1/2W +-1%(1206)'                     | 'CHIPR1206'    | ''          | ''            | '20210830'
 '910'        | '1%'      | '1/2W'   | '1206LF'  | 'EMPTY'  | 'CS19107F200'(!)        = ''              | ''                 | 'CS19107F200'           |'R1206XF'| '(SMR1206AW)'                  | '910'     | '1%'    | '1/2W'   | 'IO'       | 'RES CHIP 910 1/2W +-1%(1206)'                     | 'CHIPR1206'    | ''          | ''            | '20210830'
 '261'        | '1%'      | '1/10W'  | '0603LF'  | 'CHIP'   | 'CS12613F900'(!)        = ''              | ''                 | 'CS12613F900'           |'R0603'| '(SMR0603AW)'                  | '261'     | '1%'    | '1/10W'  | 'DISCRETE' | 'RES CHIP 261 1/10W +-1%(0603)'                    | 'CHIPR0603'    | ''          | ''            | '20210830'
 '261'        | '1%'      | '1/10W'  | '0603LF'  | 'EMPTY'  | 'CS12613F900'(!)        = ''              | ''                 | 'CS12613F900'           |'R0603'| '(SMR0603AW)'                  | '261'     | '1%'    | '1/10W'  | 'IO'       | 'RES CHIP 261 1/10W +-1%(0603)'                    | 'CHIPR0603'    | ''          | ''            | '20210830'
 '330'        | '1%'      | '1/2W'   | '1206LF'  | 'CHIP'   | 'CS13307F201'(!)        = ''              | ''                 | 'CS13307F201'           |'R1206XT'| '(SMR1206AW)'                  | '330'     | '1%'    | '1/2W'   | 'DISCRETE' | 'RES CHIP 330 1/2W+-1%(1206)SR'                    | 'CHIPR1206'    | ''          | ''            | '20210910'
 '330'        | '1%'      | '1/2W'   | '1206LF'  | 'EMPTY'  | 'CS13307F201'(!)        = ''              | ''                 | 'CS13307F201'           |'R1206XT'| '(SMR1206AW)'                  | '330'     | '1%'    | '1/2W'   | 'IO'       | 'RES CHIP 330 1/2W+-1%(1206)SR'                    | 'CHIPR1206'    | ''          | ''            | '20210910'
 '0'          | ''        | '1/3W'   | '0603LF'  | 'CHIP'   | 'CS0000CT900'(!)        = ''              | ''                 | 'CS0000CT900'           |'R0603'| '(SMR0603AW)'                  | '0'       | ''      | '1/3W'   | 'DISCRETE' | 'RES CHIP 0 1/3W (0603)WTC'                        | 'CHIPR0603'    | ''          | ''            | '20210910'
 '0'          | ''        | '1/3W'   | '0603LF'  | 'EMPTY'  | 'CS0000CT900'(!)        = ''              | ''                 | 'CS0000CT900'           |'R0603'| '(SMR0603AW)'                  | '0'       | ''      | '1/3W'   | 'IO'       | 'RES CHIP 0 1/3W (0603)WTC'                        | 'CHIPR0603'    | ''          | ''            | '20210910'
 '158K'       | '1%'      | '1/16W'  | '0402LF'  | 'CHIP'   | 'CS41582FB02'(!)        = ''              | ''                 | 'CS41582FB02'           |'R0402'| '(R0402-0201)'                 | '158K'    | '1%'    | '1/16W'  | 'DISCRETE' | 'RES CHIP 158K 1/16W +-1% (0402)EF'                | 'CHIPR0402'    | ''          | ''            | '20210916'
 '158K'       | '1%'      | '1/16W'  | '0402LF'  | 'EMPTY'  | 'CS41582FB02'(!)        = ''              | ''                 | 'CS41582FB02'           |'R0402'| '(R0402-0201)'                 | '158K'    | '1%'    | '1/16W'  | 'IO'       | 'RES CHIP 158K 1/16W +-1% (0402)EF'                | 'CHIPR0402'    | ''          | ''            | '20210916'
 '95.3K'      | '1%'      | '1/8W'   | '0805LF'  | 'CHIP'   | 'CS39534FA04'(!)        = ''              | ''                 | 'CS39534FA04'           |'R0805_H26'| '(SMR0805AW)'                  | '95.3K'   | '1%'    | '1/8W'   | 'DISCRETE' | 'RES CHIP 95.3K 1/8W +-1%(0805)EF'                 | 'CHIPR0805'    | ''          | ''            | '20210916'
 '95.3K'      | '1%'      | '1/8W'   | '0805LF'  | 'EMPTY'  | 'CS39534FA04'(!)        = ''              | ''                 | 'CS39534FA04'           |'R0805_H26'| '(SMR0805AW)'                  | '95.3K'   | '1%'    | '1/8W'   | 'IO'       | 'RES CHIP 95.3K 1/8W +-1%(0805)EF'                 | 'CHIPR0805'    | ''          | ''            | '20210916'
 '10'         | '1%'      | '1/10W'  | '0603LF'  | 'CHIP'   | 'CS01003F904'(!)        = 'End of Design' | 'Comp-Approve'     | 'CS01003F904'           |'R0603_H24'| '(SMR0603AW)'                  | '10'      | '1%'    | '1/10W'  | 'DISCRETE' | 'RES CHIP 10 1/10W +-1%(0603)EF'                   | 'CHIPR0603'    | ''          | ''            | '20210916'
 '10'         | '1%'      | '1/10W'  | '0603LF'  | 'EMPTY'  | 'CS01003F904'(!)        = 'End of Design' | 'Comp-Approve'     | 'CS01003F904'           |'R0603_H24'| '(SMR0603AW)'                  | '10'      | '1%'    | '1/10W'  | 'IO'       | 'RES CHIP 10 1/10W +-1%(0603)EF'                   | 'CHIPR0603'    | ''          | ''            | '20210916'
 '2.26K'      | '1%'      | '1/16W'  | '0402LF'  | 'CHIP'   | 'CS22262FB02'(!)        = 'End of Design' | 'Comp-Approve'     | 'CS22262FB02'           |'R0402'| '(R0402-0201)'                 | '2.26K'   | '1%'    | '1/16W'  | 'DISCRETE' | 'RES CHIP 2.26K 1/16W +-1%(0402)EF'                | 'CHIPR0402'    | ''          | ''            | '20210916'
 '2.26K'      | '1%'      | '1/16W'  | '0402LF'  | 'EMPTY'  | 'CS22262FB02'(!)        = 'End of Design' | 'Comp-Approve'     | 'CS22262FB02'           |'R0402'| '(R0402-0201)'                 | '2.26K'   | '1%'    | '1/16W'  | 'IO'       | 'RES CHIP 2.26K 1/16W +-1%(0402)EF'                | 'CHIPR0402'    | ''          | ''            | '20210916'
 '499K'       | '1%'      | '1/16W'  | '0402LF'  | 'CHIP'   | 'CS44992FB04'(!)        = 'End of Design' | 'Comp-Approve'     | 'CS44992FB04'           |'R0402'| '(R0402-0201)'                 | '499K'    | '1%'    | '1/16W'  | 'DISCRETE' | 'RES CHIP 499K 1/16W +-1% (0402)EF'                | 'CHIPR0402'    | ''          | ''            | '20210916'
 '499K'       | '1%'      | '1/16W'  | '0402LF'  | 'EMPTY'  | 'CS44992FB04'(!)        = 'End of Design' | 'Comp-Approve'     | 'CS44992FB04'           |'R0402'| '(R0402-0201)'                 | '499K'    | '1%'    | '1/16W'  | 'IO'       | 'RES CHIP 499K 1/16W +-1% (0402)EF'                | 'CHIPR0402'    | ''          | ''            | '20210916'
 '2.49K'      | '0.1%'    | '1/16W'  | '0402LF'  | 'CHIP'   | 'CS22492BB00'(!)        = ''              | ''                 | 'CS22492BB00'           |'R0402'| '(R0402-0201)'                 | '2.49K'   | '0.1%'  | '1/16W'  | 'DISCRETE' | 'RES CHIP 2.49K 1/16W +-0.1%(0402)'                | 'CHIPR0402'    | ''          | ''            | '20210916'
 '2.49K'      | '0.1%'    | '1/16W'  | '0402LF'  | 'EMPTY'  | 'CS22492BB00'(!)        = ''              | ''                 | 'CS22492BB00'           |'R0402'| '(R0402-0201)'                 | '2.49K'   | '0.1%'  | '1/16W'  | 'IO'       | 'RES CHIP 2.49K 1/16W +-0.1%(0402)'                | 'CHIPR0402'    | ''          | ''            | '20210916'
 '2.43K'      | '1%'      | '1/16W'  | '0402LF'  | 'CHIP'   | 'CS22432FB01'(!)        = 'End of Design' | 'Comp-Approve'     | 'CS22432FB01'           |'R0402'| '(R0402-0201)'                 | '2.43K'   | '1%'    | '1/16W'  | 'DISCRETE' | 'RES CHIP 2.43K 1/16W +-1%(0402)EF'                | 'CHIPR0402'    | ''          | ''            | '20210916'
 '2.43K'      | '1%'      | '1/16W'  | '0402LF'  | 'EMPTY'  | 'CS22432FB01'(!)        = 'End of Design' | 'Comp-Approve'     | 'CS22432FB01'           |'R0402'| '(R0402-0201)'                 | '2.43K'   | '1%'    | '1/16W'  | 'IO'       | 'RES CHIP 2.43K 1/16W +-1%(0402)EF'                | 'CHIPR0402'    | ''          | ''            | '20210916'
 '0.040'      | '1%'      | '1/2W'   | '1206LF'  | 'CHIP'   | 'CS+0407F200'(!)        = ''              | ''                 | 'CS+0407F200'           |'R1206XG'| '(SMR1206AW)'                  | '0.040'   | '1%'    | '1/2W'   | 'DISCRETE' | 'RES CHIP 0.040 1/2W,1%(1206)'                     | 'CHIPR1206'    | ''          | ''            | '20210917'
 '0.040'      | '1%'      | '1/2W'   | '1206LF'  | 'EMPTY'  | 'CS+0407F200'(!)        = ''              | ''                 | 'CS+0407F200'           |'R1206XG'| '(SMR1206AW)'                  | '0.040'   | '1%'    | '1/2W'   | 'IO'       | 'RES CHIP 0.040 1/2W,1%(1206)'                     | 'CHIPR1206'    | ''          | ''            | '20210917'
 '0'          | '5%'      | '1/4W'   | '0603LF'  | 'CHIP'   | 'CS00006J903'(!)        = ''              | ''                 | 'CS00006J903'           |'R0603_H26'| '(SMR0603AW)'                  | '0'       | '5%'    | '1/4W'   | 'DISCRETE' | 'RES CHIP 0 1/4W +-5%(0603)ERO'                    | 'CHIPR0603'    | ''          | ''            | '20210927'
 '0'          | '5%'      | '1/4W'   | '0603LF'  | 'EMPTY'  | 'CS00006J903'(!)        = ''              | ''                 | 'CS00006J903'           |'R0603_H26'| '(SMR0603AW)'                  | '0'       | '5%'    | '1/4W'   | 'IO'       | 'RES CHIP 0 1/4W +-5%(0603)ERO'                    | 'CHIPR0603'    | ''          | ''            | '20210927'
 '0.0005'     | '1%'      | '1.5W'   | '1206LF'  | 'CHIP'   | 'CS0000EF201'(!)        = ''              | ''                 | 'CS0000EF201'           |'R1206XS'| '(SMR1206AW)'                  | '0.0005'  | '1%'    | '1.5W'   | 'DISCRETE' | 'RES CHIP 0.0005 1.5W +-1% (1206)'                 | 'CHIPR1206'    | ''          | ''            | '20210928'
 '0.0005'     | '1%'      | '1.5W'   | '1206LF'  | 'EMPTY'  | 'CS0000EF201'(!)        = ''              | ''                 | 'CS0000EF201'           |'R1206XS'| '(SMR1206AW)'                  | '0.0005'  | '1%'    | '1.5W'   | 'IO'       | 'RES CHIP 0.0005 1.5W +-1% (1206)'                 | 'CHIPR1206'    | ''          | ''            | '20210928'
 '261'        | '1%'      | '1/10W'  | '0603LF'  | 'CHIP'   | 'CS12613F902'(!)        = ''              | ''                 | 'CS12613F902'           |'R0603_H24'| '(SMR0603AW)'                  | '261'     | '1%'    | '1/10W'  | 'DISCRETE' | 'RES CHIP 261 1/10W +-1%(0603)EF'                  | 'CHIPR0603'    | ''          | ''            | '20211026'
 '261'        | '1%'      | '1/10W'  | '0603LF'  | 'EMPTY'  | 'CS12613F902'(!)        = ''              | ''                 | 'CS12613F902'           |'R0603_H24'| '(SMR0603AW)'                  | '261'     | '1%'    | '1/10W'  | 'IO'       | 'RES CHIP 261 1/10W +-1%(0603)EF'                  | 'CHIPR0603'    | ''          | ''            | '20211026'
 '49.9'       | '1%'      | '1/10W'  | '0603LF'  | 'CHIP'   | 'CS04993F909'(!)        = 'End of Design' | 'Comp-Approve'     | 'CS04993F909'           |'R0603'| '(SMR0603AW)'                  | '49.9'    | '1%'    | '1/10W'  | 'DISCRETE' | 'RES CHIP 49.9 1/10W +-1%(0603)EF'                 | 'CHIPR0603'    | ''          | ''            | '20211026'
 '49.9'       | '1%'      | '1/10W'  | '0603LF'  | 'EMPTY'  | 'CS04993F909'(!)        = 'End of Design' | 'Comp-Approve'     | 'CS04993F909'           |'R0603'| '(SMR0603AW)'                  | '49.9'    | '1%'    | '1/10W'  | 'IO'       | 'RES CHIP 49.9 1/10W +-1%(0603)EF'                 | 'CHIPR0603'    | ''          | ''            | '20211026'
 '0'          | '5%'      | '1/4W'   | '0603LF'  | 'CHIP'   | 'CS00006J900'(!)        = ''              | ''                 | 'CS00006J900'           |'R0603'| '(SMR0603AW)'                  | '0'       | '5%'    | '1/4W'   | 'DISCRETE' | 'RES CHIP 0 1/4W +-5%(0603)'                       | 'CHIPR0603'    | ''          | ''            | '20211026'
 '0'          | '5%'      | '1/4W'   | '0603LF'  | 'EMPTY'  | 'CS00006J900'(!)        = ''              | ''                 | 'CS00006J900'           |'R0603'| '(SMR0603AW)'                  | '0'       | '5%'    | '1/4W'   | 'IO'       | 'RES CHIP 0 1/4W +-5%(0603)'                       | 'CHIPR0603'    | ''          | ''            | '20211026'
 '47K'        | '0.1%'    | '1/16W'  | '0402LF'  | 'CHIP'   | 'CS34702BB05'(!)        = ''              | ''                 | 'CS34702BB05'           |'R0402'| '(R0402-0201)'                 | '47K'     | '0.1%'  | '1/16W'  | 'DISCRETE' | 'RES CHIP 47K 1/16W +-0.1%(0402)EF'                | 'CHIPR0402'    | ''          | ''            | '20211028'
 '47K'        | '0.1%'    | '1/16W'  | '0402LF'  | 'EMPTY'  | 'CS34702BB05'(!)        = ''              | ''                 | 'CS34702BB05'           |'R0402'| '(R0402-0201)'                 | '47K'     | '0.1%'  | '1/16W'  | 'IO'       | 'RES CHIP 47K 1/16W +-0.1%(0402)EF'                | 'CHIPR0402'    | ''          | ''            | '20211028'
 '24K'        | '1%'      | '1/16W'  | '0402LF'  | 'CHIP'   | 'CS32402FB03'(!)        = ''              | ''                 | 'CS32402FB03'           |'R0402'| '(R0402-0201)'                 | '24K'     | '1%'    | '1/16W'  | 'DISCRETE' | 'RES CHIP 24K 1/16W +-1%(0402)EF'                  | 'CHIPR0402'    | ''          | ''            | '20211111'
 '24K'        | '1%'      | '1/16W'  | '0402LF'  | 'EMPTY'  | 'CS32402FB03'(!)        = ''              | ''                 | 'CS32402FB03'           |'R0402'| '(R0402-0201)'                 | '24K'     | '1%'    | '1/16W'  | 'IO'       | 'RES CHIP 24K 1/16W +-1%(0402)EF'                  | 'CHIPR0402'    | ''          | ''            | '20211111'
 '18.7K'      | '1%'      | '1/16W'  | '0402LF'  | 'CHIP'   | 'CS31872FB05'(!)        = ''              | ''                 | 'CS31872FB05'           |'R0402'| '(R0402-0201)'                 | '18.7K'   | '1%'    | '1/16W'  | 'DISCRETE' | 'RES CHIP 18.7K 1/16W +-1%(0402)EF'                | 'CHIPR0402'    | ''          | ''            | '20211111'
 '18.7K'      | '1%'      | '1/16W'  | '0402LF'  | 'EMPTY'  | 'CS31872FB05'(!)        = ''              | ''                 | 'CS31872FB05'           |'R0402'| '(R0402-0201)'                 | '18.7K'   | '1%'    | '1/16W'  | 'IO'       | 'RES CHIP 18.7K 1/16W +-1%(0402)EF'                | 'CHIPR0402'    | ''          | ''            | '20211111'
 '820K'       | '1%'      | '1/16W'  | '0402LF'  | 'CHIP'   | 'CS48202FB00'(!)        = 'End of Design' | 'Comp-Approve'     | 'CS48202FB00'           |'R0402'| '(R0402-0201)'                 | '820K'    | '1%'    | '1/16W'  | 'DISCRETE' | 'RES CHIP 820K 1/16W +-1%(0402)'                   | 'CHIPR0402'    | ''          | ''            | '20211124'
 '820K'       | '1%'      | '1/16W'  | '0402LF'  | 'EMPTY'  | 'CS48202FB00'(!)        = 'End of Design' | 'Comp-Approve'     | 'CS48202FB00'           |'R0402'| '(R0402-0201)'                 | '820K'    | '1%'    | '1/16W'  | 'IO'       | 'RES CHIP 820K 1/16W +-1%(0402)'                   | 'CHIPR0402'    | ''          | ''            | '20211124'
 '36'         | '1%'      | '1/20W'  | '0201LF'  | 'CHIP'   | 'CS03601FE00'(!)        = ''              | ''                 | 'CS03601FE00'           |'R0201'| '(SMR0201AW)'                  | '36'      | '1%'    | '1/20W'  | 'DISCRETE' | 'RES CHIP 36 1/20W,+-1%(0201)'                     | 'CHIPR0201'    | ''          | ''            | '20211130'
 '36'         | '1%'      | '1/20W'  | '0201LF'  | 'EMPTY'  | 'CS03601FE00'(!)        = ''              | ''                 | 'CS03601FE00'           |'R0201'| '(SMR0201AW)'                  | '36'      | '1%'    | '1/20W'  | 'IO'       | 'RES CHIP 36 1/20W,+-1%(0201)'                     | 'CHIPR0201'    | ''          | ''            | '20211130'
 '75K'        | '0.1%'    | '1/16W'  | '0402LF'  | 'CHIP'   | 'CS37502BB01'(!)        = ''              | ''                 | 'CS37502BB01'           |'R0402'| '(R0402-0201)'                 | '75K'     | '0.1%'  | '1/16W'  | 'DISCRETE' | 'RES CHIP 75K 1/16W +-0.1%(0402)EF'                | 'CHIPR0402'    | ''          | ''            | '20211207'
 '75K'        | '0.1%'    | '1/16W'  | '0402LF'  | 'EMPTY'  | 'CS37502BB01'(!)        = ''              | ''                 | 'CS37502BB01'           |'R0402'| '(R0402-0201)'                 | '75K'     | '0.1%'  | '1/16W'  | 'IO'       | 'RES CHIP 75K 1/16W +-0.1%(0402)EF'                | 'CHIPR0402'    | ''          | ''            | '20211207'
 '2K'         | '0.1%'    | '1/16W'  | '0402LF'  | 'CHIP'   | 'CS22002BB07'(!)        = ''              | ''                 | 'CS22002BB07'           |'R0402'| '(R0402-0201)'                 | '2K'      | '0.1%'  | '1/16W'  | 'DISCRETE' | 'RES CHIP 2K 1/16W +-0.1%(0402)EF'                 | 'CHIPR0402'    | ''          | ''            | '20211207'
 '2K'         | '0.1%'    | '1/16W'  | '0402LF'  | 'EMPTY'  | 'CS22002BB07'(!)        = ''              | ''                 | 'CS22002BB07'           |'R0402'| '(R0402-0201)'                 | '2K'      | '0.1%'  | '1/16W'  | 'IO'       | 'RES CHIP 2K 1/16W +-0.1%(0402)EF'                 | 'CHIPR0402'    | ''          | ''            | '20211207'
 '2.2'        | '1%'      | '1/8W'   | '0805LF'  | 'CHIP'   | 'CS-2204FA02'(!)        = 'End of Design' | 'Comp-Approve'     | 'CS-2204FA02'           |'R0805'| '(SMR0805AW)'                  | '2.2'     | '1%'    | '1/8W'   | 'DISCRETE' | 'RES CHIP 2.2 1/8W +-1%(0805)EF'                   | 'CHIPR0805'    | ''          | ''            | '20211210'
 '2.2'        | '1%'      | '1/8W'   | '0805LF'  | 'EMPTY'  | 'CS-2204FA02'(!)        = 'End of Design' | 'Comp-Approve'     | 'CS-2204FA02'           |'R0805'| '(SMR0805AW)'                  | '2.2'     | '1%'    | '1/8W'   | 'IO'       | 'RES CHIP 2.2 1/8W +-1%(0805)EF'                   | 'CHIPR0805'    | ''          | ''            | '20211210'
 '1.65K'      | '1%'      | '1/16W'  | '0402LF'  | 'CHIP'   | 'CS21652FB05'(!)        = 'End of Design' | 'Comp-Approve'     | 'CS21652FB05'           |'R0402'| '(R0402-0201)'                 | '1.65K'   | '1%'    | '1/16W'  | 'DISCRETE' | 'RES CHIP 1.65K 1/16W +-1%(0402)EF'                | 'CHIPR0402'    | ''          | ''            | '20211214'
 '1.65K'      | '1%'      | '1/16W'  | '0402LF'  | 'EMPTY'  | 'CS21652FB05'(!)        = 'End of Design' | 'Comp-Approve'     | 'CS21652FB05'           |'R0402'| '(R0402-0201)'                 | '1.65K'   | '1%'    | '1/16W'  | 'IO'       | 'RES CHIP 1.65K 1/16W +-1%(0402)EF'                | 'CHIPR0402'    | ''          | ''            | '20211214'
 '3.83K'      | '1%'      | '1/16W'  | '0402LF'  | 'CHIP'   | 'CS23832FB04'(!)        = 'End of Design' | 'Comp-Approve'     | 'CS23832FB04'           |'R0402'| '(R0402-0201)'                 | '3.83K'   | '1%'    | '1/16W'  | 'DISCRETE' | 'RES CHIP 3.83K 1/16W +-1%(0402)EF'                | 'CHIPR0402'    | ''          | ''            | '20211214'
 '3.83K'      | '1%'      | '1/16W'  | '0402LF'  | 'EMPTY'  | 'CS23832FB04'(!)        = 'End of Design' | 'Comp-Approve'     | 'CS23832FB04'           |'R0402'| '(R0402-0201)'                 | '3.83K'   | '1%'    | '1/16W'  | 'IO'       | 'RES CHIP 3.83K 1/16W +-1%(0402)EF'                | 'CHIPR0402'    | ''          | ''            | '20211214'
 '4.99K'      | '0.1%'    | '1/16W'  | '0402LF'  | 'CHIP'   | 'CS24992BB04'(!)        = ''              | ''                 | 'CS24992BB04'           |'R0402'| '(R0402-0201)'                 | '4.99K'   | '0.1%'  | '1/16W'  | 'DISCRETE' | 'RES CHIP 4.99K 1/16W +-0.1%(0402)EF'              | 'CHIPR0402'    | ''          | ''            | '20211216'
 '4.99K'      | '0.1%'    | '1/16W'  | '0402LF'  | 'EMPTY'  | 'CS24992BB04'(!)        = ''              | ''                 | 'CS24992BB04'           |'R0402'| '(R0402-0201)'                 | '4.99K'   | '0.1%'  | '1/16W'  | 'IO'       | 'RES CHIP 4.99K 1/16W +-0.1%(0402)EF'              | 'CHIPR0402'    | ''          | ''            | '20211216'
 '9.53K'      | '1%'      | '1/16W'  | '0402LF'  | 'CHIP'   | 'CS29532FB06'(!)        = ''              | ''                 | 'CS29532FB06'           |'R0402'| '(R0402-0201)'                 | '9.53K'   | '1%'    | '1/16W'  | 'DISCRETE' | 'RES CHIP 9.53K 1/16W +-1%(0402)EF'                | 'CHIPR0402'    | ''          | ''            | '20211216'
 '9.53K'      | '1%'      | '1/16W'  | '0402LF'  | 'EMPTY'  | 'CS29532FB06'(!)        = ''              | ''                 | 'CS29532FB06'           |'R0402'| '(R0402-0201)'                 | '9.53K'   | '1%'    | '1/16W'  | 'IO'       | 'RES CHIP 9.53K 1/16W +-1%(0402)EF'                | 'CHIPR0402'    | ''          | ''            | '20211216'
 '37.4K'      | '1%'      | '1/16W'  | '0402LF'  | 'CHIP'   | 'CS33742FB05'(!)        = 'End of Design' | 'Comp-Approve'     | 'CS33742FB05'           |'R0402'| '(R0402-0201)'                 | '37.4K'   | '1%'    | '1/16W'  | 'DISCRETE' | 'RES CHIP 37.4K 1/16W +-1%(0402)EF'                | 'CHIPR0402'    | ''          | ''            | '20211216'
 '37.4K'      | '1%'      | '1/16W'  | '0402LF'  | 'EMPTY'  | 'CS33742FB05'(!)        = 'End of Design' | 'Comp-Approve'     | 'CS33742FB05'           |'R0402'| '(R0402-0201)'                 | '37.4K'   | '1%'    | '1/16W'  | 'IO'       | 'RES CHIP 37.4K 1/16W +-1%(0402)EF'                | 'CHIPR0402'    | ''          | ''            | '20211216'
 '3.01K'      | '1%'      | '1/16W'  | '0402LF'  | 'CHIP'   | 'CS23012FB04'(!)        = 'End of Design' | 'Comp-Approve'     | 'CS23012FB04'           |'R0402'| '(R0402-0201)'                 | '3.01K'   | '1%'    | '1/16W'  | 'DISCRETE' | 'RES CHIP 3.01K 1/16W +-1%(0402)EF'                | 'CHIPR0402'    | ''          | ''            | '20211222'
 '3.01K'      | '1%'      | '1/16W'  | '0402LF'  | 'EMPTY'  | 'CS23012FB04'(!)        = 'End of Design' | 'Comp-Approve'     | 'CS23012FB04'           |'R0402'| '(R0402-0201)'                 | '3.01K'   | '1%'    | '1/16W'  | 'IO'       | 'RES CHIP 3.01K 1/16W +-1%(0402)EF'                | 'CHIPR0402'    | ''          | ''            | '20211222'
 '3K'         | '1%'      | '1/16W'  | '0402LF'  | 'CHIP'   | 'CS23002FB02'(!)        = 'End of Design' | 'Comp-Approve'     | 'CS23002FB02'           |'R0402'| '(R0402-0201)'                 | '3K'      | '1%'    | '1/16W'  | 'DISCRETE' | 'RES CHIP 3K 1/16W +-1%(0402)EF'                   | 'CHIPR0402'    | ''          | ''            | '20211222'
 '3K'         | '1%'      | '1/16W'  | '0402LF'  | 'EMPTY'  | 'CS23002FB02'(!)        = 'End of Design' | 'Comp-Approve'     | 'CS23002FB02'           |'R0402'| '(R0402-0201)'                 | '3K'      | '1%'    | '1/16W'  | 'IO'       | 'RES CHIP 3K 1/16W +-1%(0402)EF'                   | 'CHIPR0402'    | ''          | ''            | '20211222'
 '8.2K'       | '1%'      | '1/16W'  | '0402LF'  | 'CHIP'   | 'CS28202FB01'(!)        = 'End of Design' | 'Comp-Approve'     | 'CS28202FB01'           |'R0402'| '(R0402-0201)'                 | '8.2K'    | '1%'    | '1/16W'  | 'DISCRETE' | 'RES CHIP 8.2K 1/16W +-1%(0402)EF'                 | 'CHIPR0402'    | ''          | ''            | '20211222'
 '8.2K'       | '1%'      | '1/16W'  | '0402LF'  | 'EMPTY'  | 'CS28202FB01'(!)        = 'End of Design' | 'Comp-Approve'     | 'CS28202FB01'           |'R0402'| '(R0402-0201)'                 | '8.2K'    | '1%'    | '1/16W'  | 'IO'       | 'RES CHIP 8.2K 1/16W +-1%(0402)EF'                 | 'CHIPR0402'    | ''          | ''            | '20211222'
 '825'        | '1%'      | '1/16W'  | '0402LF'  | 'CHIP'   | 'CS18252FB03'(!)        = 'End of Design' | 'Comp-Approve'     | 'CS18252FB03'           |'R0402'| '(R0402-0201)'                 | '825'     | '1%'    | '1/16W'  | 'DISCRETE' | 'RES CHIP 825 1/16W +-1% (0402) EF'                | 'CHIPR0402'    | ''          | ''            | '20211222'
 '825'        | '1%'      | '1/16W'  | '0402LF'  | 'EMPTY'  | 'CS18252FB03'(!)        = 'End of Design' | 'Comp-Approve'     | 'CS18252FB03'           |'R0402'| '(R0402-0201)'                 | '825'     | '1%'    | '1/16W'  | 'IO'       | 'RES CHIP 825 1/16W +-1% (0402) EF'                | 'CHIPR0402'    | ''          | ''            | '20211222'
 '2.8K'       | '1%'      | '1/16W'  | '0402LF'  | 'CHIP'   | 'CS22802FB04'(!)        = 'End of Design' | 'Comp-Approve'     | 'CS22802FB04'           |'R0402'| '(R0402-0201)'                 | '2.8K'    | '1%'    | '1/16W'  | 'DISCRETE' | 'RES CHIP 2.8K 1/16W +-1%(0402)EF'                 | 'CHIPR0402'    | ''          | ''            | '20211222'
 '2.8K'       | '1%'      | '1/16W'  | '0402LF'  | 'EMPTY'  | 'CS22802FB04'(!)        = 'End of Design' | 'Comp-Approve'     | 'CS22802FB04'           |'R0402'| '(R0402-0201)'                 | '2.8K'    | '1%'    | '1/16W'  | 'IO'       | 'RES CHIP 2.8K 1/16W +-1%(0402)EF'                 | 'CHIPR0402'    | ''          | ''            | '20211222'
 '3.3'        | '1%'      | '1/10W'  | '0603LF'  | 'CHIP'   | 'CS-3303F905'(!)        = ''              | ''                 | 'CS-3303F905'           |'R0603'| '(SMR0603AW)'                  | '3.3'     | '1%'    | '1/10W'  | 'DISCRETE' | 'RES CHIP 3.3 1/10W +-1%(0603)EF'                  | 'CHIPR0603'    | ''          | ''            | '20211224'
 '3.3'        | '1%'      | '1/10W'  | '0603LF'  | 'EMPTY'  | 'CS-3303F905'(!)        = ''              | ''                 | 'CS-3303F905'           |'R0603'| '(SMR0603AW)'                  | '3.3'     | '1%'    | '1/10W'  | 'IO'       | 'RES CHIP 3.3 1/10W +-1%(0603)EF'                  | 'CHIPR0603'    | ''          | ''            | '20211224'
 '499'        | '1%'      | '1/10W'  | '0603LF'  | 'CHIP'   | 'CS14993F901'(!)        = 'End of Design' | 'Comp-Approve'     | 'CS14993F901'           |'R0603'| '(SMR0603AW)'                  | '499'     | '1%'    | '1/10W'  | 'DISCRETE' | 'RES CHIP 499 1/10W +-1%(0603)EF'                  | 'CHIPR0603'    | ''          | ''            | '20211227'
 '499'        | '1%'      | '1/10W'  | '0603LF'  | 'EMPTY'  | 'CS14993F901'(!)        = 'End of Design' | 'Comp-Approve'     | 'CS14993F901'           |'R0603'| '(SMR0603AW)'                  | '499'     | '1%'    | '1/10W'  | 'IO'       | 'RES CHIP 499 1/10W +-1%(0603)EF'                  | 'CHIPR0603'    | ''          | ''            | '20211227'
 '48.7K'      | '1%'      | '1/16W'  | '0402LF'  | 'CHIP'   | 'CS34872FB03'(!)        = 'End of Design' | 'Comp-Approve'     | 'CS34872FB03'           |'R0402'| '(R0402-0201)'                 | '48.7K'   | '1%'    | '1/16W'  | 'DISCRETE' | 'RES CHIP 48.7K 1/16W +-1%(0402)EF'                | 'CHIPR0402'    | ''          | ''            | '20211227'
 '48.7K'      | '1%'      | '1/16W'  | '0402LF'  | 'EMPTY'  | 'CS34872FB03'(!)        = 'End of Design' | 'Comp-Approve'     | 'CS34872FB03'           |'R0402'| '(R0402-0201)'                 | '48.7K'   | '1%'    | '1/16W'  | 'IO'       | 'RES CHIP 48.7K 1/16W +-1%(0402)EF'                | 'CHIPR0402'    | ''          | ''            | '20211227'
 '1.3K'       | '1%'      | '1/16W'  | '0402LF'  | 'CHIP'   | 'CS21302FB07'(!)        = ''              | ''                 | 'CS21302FB07'           |'R0402'| '(R0402-0201)'                 | '1.3K'    | '1%'    | '1/16W'  | 'DISCRETE' | 'RES CHIP 1.3K 1/16W +-1%(0402)EF'                 | 'CHIPR0402'    | ''          | ''            | '20220106'
 '1.3K'       | '1%'      | '1/16W'  | '0402LF'  | 'EMPTY'  | 'CS21302FB07'(!)        = ''              | ''                 | 'CS21302FB07'           |'R0402'| '(R0402-0201)'                 | '1.3K'    | '1%'    | '1/16W'  | 'IO'       | 'RES CHIP 1.3K 1/16W +-1%(0402)EF'                 | 'CHIPR0402'    | ''          | ''            | '20220106'
 '499K'       | '1%'      | '1/8W'   | '0805LF'  | 'CHIP'   | 'CS44994FA04'(!)        = ''              | ''                 | 'CS44994FA04'           |'R0805_H26'| '(SMR0805AW)'                  | '499K'    | '1%'    | '1/8W'   | 'DISCRETE' | 'RES CHIP 499K 1/8W+-1%(0805)EF'                   | 'CHIPR0805'    | ''          | ''            | '20220107'
 '499K'       | '1%'      | '1/8W'   | '0805LF'  | 'EMPTY'  | 'CS44994FA04'(!)        = ''              | ''                 | 'CS44994FA04'           |'R0805_H26'| '(SMR0805AW)'                  | '499K'    | '1%'    | '1/8W'   | 'IO'       | 'RES CHIP 499K 1/8W+-1%(0805)EF'                   | 'CHIPR0805'    | ''          | ''            | '20220107'
 '1'          | '1%'      | '2W'     | '2512LF'  | 'CHIP'   | 'CS-100AFR03'(!)        = ''              | ''                 | 'CS-100AFR03'           |'R2512XU_H30'| '(SMR2512AW)'                  | '1'       | '1%'    | '2W'     | 'DISCRETE' | 'RES CHIP 1 2W +-1%(2512)EF'                       | 'CHIPR2512'    | ''          | ''            | '20220111'
 '1'          | '1%'      | '2W'     | '2512LF'  | 'EMPTY'  | 'CS-100AFR03'(!)        = ''              | ''                 | 'CS-100AFR03'           |'R2512XU_H30'| '(SMR2512AW)'                  | '1'       | '1%'    | '2W'     | 'IO'       | 'RES CHIP 1 2W +-1%(2512)EF'                       | 'CHIPR2512'    | ''          | ''            | '20220111'
 '3.01'       | '1%'      | '1/16W'  | '0402LF'  | 'CHIP'   | 'CS-3012FB00'(!)        = ''              | ''                 | 'CS-3012FB00'           |'R0402'| '(R0402-0201)'                 | '3.01'    | '1%'    | '1/16W'  | 'DISCRETE' | 'RES CHIP 3.01 1/16W +-1% (0402)EF'                | 'CHIPR0402'    | ''          | ''            | '20220111'
 '3.01'       | '1%'      | '1/16W'  | '0402LF'  | 'EMPTY'  | 'CS-3012FB00'(!)        = ''              | ''                 | 'CS-3012FB00'           |'R0402'| '(R0402-0201)'                 | '3.01'    | '1%'    | '1/16W'  | 'IO'       | 'RES CHIP 3.01 1/16W +-1% (0402)EF'                | 'CHIPR0402'    | ''          | ''            | '20220111'
 '4.99'       | '1%'      | '1/16W'  | '0402LF'  | 'CHIP'   | 'CS-4992FB02'(!)        = 'End of Design' | 'Comp-Approve'     | 'CS-4992FB02'           |'R0402'| '(R0402-0201)'                 | '4.99'    | '1%'    | '1/16W'  | 'DISCRETE' | 'RES CHIP 4.99 1/16W +-1%(0402)EF'                 | 'CHIPR0402'    | ''          | ''            | '20220111'
 '4.99'       | '1%'      | '1/16W'  | '0402LF'  | 'EMPTY'  | 'CS-4992FB02'(!)        = 'End of Design' | 'Comp-Approve'     | 'CS-4992FB02'           |'R0402'| '(R0402-0201)'                 | '4.99'    | '1%'    | '1/16W'  | 'IO'       | 'RES CHIP 4.99 1/16W +-1%(0402)EF'                 | 'CHIPR0402'    | ''          | ''            | '20220111'
 '1.07K'      | '1%'      | '1/16W'  | '0402LF'  | 'CHIP'   | 'CS21072FB04'(!)        = ''              | ''                 | 'CS21072FB04'           |'R0402'| '(R0402-0201)'                 | '1.07K'   | '1%'    | '1/16W'  | 'DISCRETE' | 'RES CHIP 1.07K 1/16W +-1%(0402)EF'                | 'CHIPR0402'    | ''          | ''            | '20220118'
 '1.07K'      | '1%'      | '1/16W'  | '0402LF'  | 'EMPTY'  | 'CS21072FB04'(!)        = ''              | ''                 | 'CS21072FB04'           |'R0402'| '(R0402-0201)'                 | '1.07K'   | '1%'    | '1/16W'  | 'IO'       | 'RES CHIP 1.07K 1/16W +-1%(0402)EF'                | 'CHIPR0402'    | ''          | ''            | '20220118'
 '390K'       | '1%'      | '1/16W'  | '0402LF'  | 'CHIP'   | 'CS43902FB01'(!)        = ''              | ''                 | 'CS43902FB01'           |'R0402'| '(R0402-0201)'                 | '390K'    | '1%'    | '1/16W'  | 'DISCRETE' | 'RES CHIP 390K 1/16W +-1%(0402)EF'                 | 'CHIPR0402'    | ''          | ''            | '20220207'
 '390K'       | '1%'      | '1/16W'  | '0402LF'  | 'EMPTY'  | 'CS43902FB01'(!)        = ''              | ''                 | 'CS43902FB01'           |'R0402'| '(R0402-0201)'                 | '390K'    | '1%'    | '1/16W'  | 'IO'       | 'RES CHIP 390K 1/16W +-1%(0402)EF'                 | 'CHIPR0402'    | ''          | ''            | '20220207'
 '1.96K'      | '1%'      | '1/16W'  | '0402LF'  | 'CHIP'   | 'CS21962FB05'(!)        = ''              | ''                 | 'CS21962FB05'           |'R0402'| '(R0402-0201)'                 | '1.96K'   | '1%'    | '1/16W'  | 'DISCRETE' | 'RES CHIP 1.96K 1/16W +-1%(0402)EF'                | 'CHIPR0402'    | ''          | ''            | '20220208'
 '1.96K'      | '1%'      | '1/16W'  | '0402LF'  | 'EMPTY'  | 'CS21962FB05'(!)        = ''              | ''                 | 'CS21962FB05'           |'R0402'| '(R0402-0201)'                 | '1.96K'   | '1%'    | '1/16W'  | 'IO'       | 'RES CHIP 1.96K 1/16W +-1%(0402)EF'                | 'CHIPR0402'    | ''          | ''            | '20220208'
 '3.09K'      | '1%'      | '1/16W'  | '0402LF'  | 'CHIP'   | 'CS23092FB04'(!)        = ''              | ''                 | 'CS23092FB04'           |'R0402'| '(R0402-0201)'                 | '3.09K'   | '1%'    | '1/16W'  | 'DISCRETE' | 'RES CHIP 3.09K 1/16W +-1%(0402)EF'                | 'CHIPR0402'    | ''          | ''            | '20220209'
 '3.09K'      | '1%'      | '1/16W'  | '0402LF'  | 'EMPTY'  | 'CS23092FB04'(!)        = ''              | ''                 | 'CS23092FB04'           |'R0402'| '(R0402-0201)'                 | '3.09K'   | '1%'    | '1/16W'  | 'IO'       | 'RES CHIP 3.09K 1/16W +-1%(0402)EF'                | 'CHIPR0402'    | ''          | ''            | '20220209'
 '8.66K'      | '1%'      | '1/16W'  | '0402LF'  | 'CHIP'   | 'CS28662FB02'(!)        = 'End of Design' | 'Comp-Approve'     | 'CS28662FB02'           |'R0402'| '(R0402-0201)'                 | '8.66K'   | '1%'    | '1/16W'  | 'DISCRETE' | 'RES CHIP 8.66K 1/16W +-1%(0402)EF'                | 'CHIPR0402'    | ''          | ''            | '20220216'
 '8.66K'      | '1%'      | '1/16W'  | '0402LF'  | 'EMPTY'  | 'CS28662FB02'(!)        = 'End of Design' | 'Comp-Approve'     | 'CS28662FB02'           |'R0402'| '(R0402-0201)'                 | '8.66K'   | '1%'    | '1/16W'  | 'IO'       | 'RES CHIP 8.66K 1/16W +-1%(0402)EF'                | 'CHIPR0402'    | ''          | ''            | '20220216'
 '4.7'        | '5%'      | '1W'     | '2512LF'  | 'CHIP'   | 'CS-4708JR01'(!)        = ''              | ''                 | 'CS-4708JR01'           |'R2512XAA'| '(SMR2512AW)'                  | '4.7'     | '5%'    | '1W'     | 'DISCRETE' | 'RES CHIP 4.7 1W +-5%(2512)SR'                     | 'CHIPR2512'    | ''          | ''            | '20220225'
 '4.7'        | '5%'      | '1W'     | '2512LF'  | 'EMPTY'  | 'CS-4708JR01'(!)        = ''              | ''                 | 'CS-4708JR01'           |'R2512XAA'| '(SMR2512AW)'                  | '4.7'     | '5%'    | '1W'     | 'IO'       | 'RES CHIP 4.7 1W +-5%(2512)SR'                     | 'CHIPR2512'    | ''          | ''            | '20220225'
 '51'         | '5%'      | '1/8W'   | '0805LF'  | 'CHIP'   | 'CS05104JA01'(!)        = ''              | ''                 | 'CS05104JA01'           |'R0805_H26'| '(SMR0805AW)'                  | '51'      | '5%'    | '1/8W'   | 'DISCRETE' | 'RES CHIP 51 1/8W +-5%(0805)EF'                    | 'CHIPR0805'    | ''          | ''            | '20220301'
 '51'         | '5%'      | '1/8W'   | '0805LF'  | 'EMPTY'  | 'CS05104JA01'(!)        = ''              | ''                 | 'CS05104JA01'           |'R0805_H26'| '(SMR0805AW)'                  | '51'      | '5%'    | '1/8W'   | 'IO'       | 'RES CHIP 51 1/8W +-5%(0805)EF'                    | 'CHIPR0805'    | ''          | ''            | '20220301'
 '1'          | '5%'      | '1W'     | '2512LF'  | 'CHIP'   | 'CS-1008JR00'(!)        = ''              | ''                 | 'CS-1008JR00'           |'R2512XU_H30'| '(SMR2512AW)'                  | '1'       | '5%'    | '1W'     | 'DISCRETE' | 'RES CHIP 1 1W +-5%(2512)SR'                       | 'CHIPR2512'    | ''          | ''            | '20220301'
 '1'          | '5%'      | '1W'     | '2512LF'  | 'EMPTY'  | 'CS-1008JR00'(!)        = ''              | ''                 | 'CS-1008JR00'           |'R2512XU_H30'| '(SMR2512AW)'                  | '1'       | '5%'    | '1W'     | 'IO'       | 'RES CHIP 1 1W +-5%(2512)SR'                       | 'CHIPR2512'    | ''          | ''            | '20220301'
 '0'          | ''        | '1/16W'  | '0402LF'  | 'CHIP'   | 'CS00002TB03'(!)        = ''              | ''                 | 'CS00002TB03'           |'R0402'| '(R0402-0201)'                 | '0'       | ''      | '1/16W'  | 'DISCRETE' | 'RES CHIP 0 1/16W (0402)EF'                        | 'CHIPR0402'    | ''          | ''            | '20220301'
 '0'          | ''        | '1/16W'  | '0402LF'  | 'EMPTY'  | 'CS00002TB03'(!)        = ''              | ''                 | 'CS00002TB03'           |'R0402'| '(R0402-0201)'                 | '0'       | ''      | '1/16W'  | 'IO'       | 'RES CHIP 0 1/16W (0402)EF'                        | 'CHIPR0402'    | ''          | ''            | '20220301'
 '38.3K'      | '0.1%'    | '1/16W'  | '0402LF'  | 'CHIP'   | 'CS33832BB00'(!)        = ''              | ''                 | 'CS33832BB00'           |'R0402'| '(R0402-0201)'                 | '38.3K'   | '0.1%'  | '1/16W'  | 'DISCRETE' | 'RES CHIP 38.3K 1/16W  +-0.1%(0402)'               | 'CHIPR0402'    | ''          | ''            | '20220316'
 '38.3K'      | '0.1%'    | '1/16W'  | '0402LF'  | 'EMPTY'  | 'CS33832BB00'(!)        = ''              | ''                 | 'CS33832BB00'           |'R0402'| '(R0402-0201)'                 | '38.3K'   | '0.1%'  | '1/16W'  | 'IO'       | 'RES CHIP 38.3K 1/16W  +-0.1%(0402)'               | 'CHIPR0402'    | ''          | ''            | '20220316'
 '110'        | '1%'      | '1/16W'  | '0402LF'  | 'CHIP'   | 'CS11102FB03'(!)        = ''              | ''                 | 'CS11102FB03'           |'R0402'| '(R0402-0201)'                 | '110'     | '1%'    | '1/16W'  | 'DISCRETE' | 'RES CHIP 110 1/16W +-1%(0402)EF'                  | 'CHIPR0402'    | ''          | ''            | '20220316'
 '110'        | '1%'      | '1/16W'  | '0402LF'  | 'EMPTY'  | 'CS11102FB03'(!)        = ''              | ''                 | 'CS11102FB03'           |'R0402'| '(R0402-0201)'                 | '110'     | '1%'    | '1/16W'  | 'IO'       | 'RES CHIP 110 1/16W +-1%(0402)EF'                  | 'CHIPR0402'    | ''          | ''            | '20220316'
 '3.32K'      | '1%'      | '1/16W'  | '0402LF'  | 'CHIP'   | 'CS23322FB05'(!)        = 'End of Design' | 'Comp-Approve'     | 'CS23322FB05'           |'R0402'| '(R0402-0201)'                 | '3.32K'   | '1%'    | '1/16W'  | 'DISCRETE' | 'RES CHIP 3.32K 1/16W +-1%(0402)EF'                | 'CHIPR0402'    | ''          | ''            | '20220316'
 '3.32K'      | '1%'      | '1/16W'  | '0402LF'  | 'EMPTY'  | 'CS23322FB05'(!)        = 'End of Design' | 'Comp-Approve'     | 'CS23322FB05'           |'R0402'| '(R0402-0201)'                 | '3.32K'   | '1%'    | '1/16W'  | 'IO'       | 'RES CHIP 3.32K 1/16W +-1%(0402)EF'                | 'CHIPR0402'    | ''          | ''            | '20220316'
 '0.03'       | '1%'      | '1/2W'   | '0805LF'  | 'CHIP'   | 'CS+0307FA00'(!)        = ''              | ''                 | 'CS+0307FA00'           |'R0805'| '(SMR0805AW)'                  | '0.03'    | '1%'    | '1/2W'   | 'DISCRETE' | 'RES CHIP 0.03 1/2W 1%(0805)'                      | 'CHIPR0805'    | ''          | ''            | '20220316'
 '0.03'       | '1%'      | '1/2W'   | '0805LF'  | 'EMPTY'  | 'CS+0307FA00'(!)        = ''              | ''                 | 'CS+0307FA00'           |'R0805'| '(SMR0805AW)'                  | '0.03'    | '1%'    | '1/2W'   | 'IO'       | 'RES CHIP 0.03 1/2W 1%(0805)'                      | 'CHIPR0805'    | ''          | ''            | '20220316'
 '0'          | ''        | '1/8W'   | '0402LF'  | 'CHIP'   | 'CS00004TB04'(!)        = ''              | ''                 | 'CS00004TB04'           |'R0402_H20'| '(R0402-0201_H20)'             | '0'       | ''      | '1/8W'   | 'DISCRETE' | 'RES CHIP 0 OHM 1/8W JUMPER (0402)'                | 'CHIPR0402'    | ''          | ''            | '20220316'
 '0'          | ''        | '1/8W'   | '0402LF'  | 'EMPTY'  | 'CS00004TB04'(!)        = ''              | ''                 | 'CS00004TB04'           |'R0402_H20'| '(R0402-0201_H20)'             | '0'       | ''      | '1/8W'   | 'IO'       | 'RES CHIP 0 OHM 1/8W JUMPER (0402)'                | 'CHIPR0402'    | ''          | ''            | '20220316'
 '10.7K'      | '0.1%'    | '1/16W'  | '0402LF'  | 'CHIP'   | 'CS31072BB03'(!)        = ''              | ''                 | 'CS31072BB03'           |'R0402'| '(R0402-0201)'                 | '10.7K'   | '0.1%'  | '1/16W'  | 'DISCRETE' | 'RES CHIP 10.7K 1/16W +-0.1%(0402)EF'              | 'CHIPR0402'    | ''          | ''            | '20220316'
 '10.7K'      | '0.1%'    | '1/16W'  | '0402LF'  | 'EMPTY'  | 'CS31072BB03'(!)        = ''              | ''                 | 'CS31072BB03'           |'R0402'| '(R0402-0201)'                 | '10.7K'   | '0.1%'  | '1/16W'  | 'IO'       | 'RES CHIP 10.7K 1/16W +-0.1%(0402)EF'              | 'CHIPR0402'    | ''          | ''            | '20220316'
 '38.3K'      | '0.1%'    | '1/16W'  | '0402LF'  | 'CHIP'   | 'CS33832BB06'(!)        = ''              | ''                 | 'CS33832BB06'           |'R0402'| '(R0402-0201)'                 | '38.3K'   | '0.1%'  | '1/16W'  | 'DISCRETE' | 'RES CHIP 38.3K 1/16W +-0.1%(0402)EF'              | 'CHIPR0402'    | ''          | ''            | '20220316'
 '38.3K'      | '0.1%'    | '1/16W'  | '0402LF'  | 'EMPTY'  | 'CS33832BB06'(!)        = ''              | ''                 | 'CS33832BB06'           |'R0402'| '(R0402-0201)'                 | '38.3K'   | '0.1%'  | '1/16W'  | 'IO'       | 'RES CHIP 38.3K 1/16W +-0.1%(0402)EF'              | 'CHIPR0402'    | ''          | ''            | '20220316'
 '11.3K'      | '0.1%'    | '1/16W'  | '0402LF'  | 'CHIP'   | 'CS31132BB02'(!)        = ''              | ''                 | 'CS31132BB02'           |'R0402'| '(R0402-0201)'                 | '11.3K'   | '0.1%'  | '1/16W'  | 'DISCRETE' | 'RES CHIP 11.3K 1/16W +-0.1%(0402)EF'              | 'CHIPR0402'    | ''          | ''            | '20220316'
 '11.3K'      | '0.1%'    | '1/16W'  | '0402LF'  | 'EMPTY'  | 'CS31132BB02'(!)        = ''              | ''                 | 'CS31132BB02'           |'R0402'| '(R0402-0201)'                 | '11.3K'   | '0.1%'  | '1/16W'  | 'IO'       | 'RES CHIP 11.3K 1/16W +-0.1%(0402)EF'              | 'CHIPR0402'    | ''          | ''            | '20220316'
 '243'        | '1%'      | '1/4W'   | '1206LF'  | 'CHIP'   | 'CS12436F201'(!)        = ''              | ''                 | 'CS12436F201'           |'R1206XN'| '(SMR1206AW)'                  | '243'     | '1%'    | '1/4W'   | 'DISCRETE' | 'RES CHIP 243 1/4W +-1%(1206)EF'                   | 'CHIPR1206'    | ''          | ''            | '20220322'
 '243'        | '1%'      | '1/4W'   | '1206LF'  | 'EMPTY'  | 'CS12436F201'(!)        = ''              | ''                 | 'CS12436F201'           |'R1206XN'| '(SMR1206AW)'                  | '243'     | '1%'    | '1/4W'   | 'IO'       | 'RES CHIP 243 1/4W +-1%(1206)EF'                   | 'CHIPR1206'    | ''          | ''            | '20220322'
 '634'        | '1%'      | '1/16W'  | '0402LF'  | 'CHIP'   | 'CS16342FB01'(!)        = 'End of Design' | 'Comp-Approve'     | 'CS16342FB01'           |'R0402'| '(R0402-0201)'                 | '634'     | '1%'    | '1/16W'  | 'DISCRETE' | 'RES CHIP 634 1/16W +-1%(0402)EF'                  | 'CHIPR0402'    | ''          | ''            | '20220406'
 '634'        | '1%'      | '1/16W'  | '0402LF'  | 'EMPTY'  | 'CS16342FB01'(!)        = 'End of Design' | 'Comp-Approve'     | 'CS16342FB01'           |'R0402'| '(R0402-0201)'                 | '634'     | '1%'    | '1/16W'  | 'IO'       | 'RES CHIP 634 1/16W +-1%(0402)EF'                  | 'CHIPR0402'    | ''          | ''            | '20220406'
 '0'          | '1%'      | '1/10W'  | '0603LF'  | 'CHIP'   | 'CS00003F905'(!)        = ''              | ''                 | 'CS00003F905'           |'R0603'| '(SMR0603AW)'                  | '0'       | '1%'    | '1/10W'  | 'DISCRETE' | 'RES CHIP 0 1/10W +-1% (0603)EF'                   | 'CHIPR0603'    | ''          | ''            | '20220407'
 '0'          | '1%'      | '1/10W'  | '0603LF'  | 'EMPTY'  | 'CS00003F905'(!)        = ''              | ''                 | 'CS00003F905'           |'R0603'| '(SMR0603AW)'                  | '0'       | '1%'    | '1/10W'  | 'IO'       | 'RES CHIP 0 1/10W +-1% (0603)EF'                   | 'CHIPR0603'    | ''          | ''            | '20220407'
 '487'        | '1%'      | '1/16W'  | '0402LF'  | 'CHIP'   | 'CS14872FB01'(!)        = ''              | ''                 | 'CS14872FB01'           |'R0402'| '(R0402-0201)'                 | '487'     | '1%'    | '1/16W'  | 'DISCRETE' | 'RES CHIP 487 1/16W +-1%(0402) EF'                 | 'CHIPR0402'    | ''          | ''            | '20220407'
 '487'        | '1%'      | '1/16W'  | '0402LF'  | 'EMPTY'  | 'CS14872FB01'(!)        = ''              | ''                 | 'CS14872FB01'           |'R0402'| '(R0402-0201)'                 | '487'     | '1%'    | '1/16W'  | 'IO'       | 'RES CHIP 487 1/16W +-1%(0402) EF'                 | 'CHIPR0402'    | ''          | ''            | '20220407'
 '5.62K'      | '1%'      | '1/16W'  | '0402LF'  | 'CHIP'   | 'CS25622FB04'(!)        = ''              | ''                 | 'CS25622FB04'           |'R0402'| '(R0402-0201)'                 | '5.62K'   | '1%'    | '1/16W'  | 'DISCRETE' | 'RES CHIP 5.62K 1/16W +-1%(0402)EF'                | 'CHIPR0402'    | ''          | ''            | '20220408'
 '5.62K'      | '1%'      | '1/16W'  | '0402LF'  | 'EMPTY'  | 'CS25622FB04'(!)        = ''              | ''                 | 'CS25622FB04'           |'R0402'| '(R0402-0201)'                 | '5.62K'   | '1%'    | '1/16W'  | 'IO'       | 'RES CHIP 5.62K 1/16W +-1%(0402)EF'                | 'CHIPR0402'    | ''          | ''            | '20220408'
 '20K'        | '1%'      | '1/4W'   | '1206LF'  | 'CHIP'   | 'CS32006F205'(!)        = ''              | ''                 | 'CS32006F205'           |'R1206XN'| '(SMR1206AW)'                  | '20K'     | '1%'    | '1/4W'   | 'DISCRETE' | 'RES CHIP 20K 1/4W +-1%(1206)EF'                   | 'CHIPR1206'    | ''          | ''            | '20220408'
 '20K'        | '1%'      | '1/4W'   | '1206LF'  | 'EMPTY'  | 'CS32006F205'(!)        = ''              | ''                 | 'CS32006F205'           |'R1206XN'| '(SMR1206AW)'                  | '20K'     | '1%'    | '1/4W'   | 'IO'       | 'RES CHIP 20K 1/4W +-1%(1206)EF'                   | 'CHIPR1206'    | ''          | ''            | '20220408'
 '32.4K'      | '1%'      | '1/16W'  | '0402LF'  | 'CHIP'   | 'CS33242FB03'(!)        = 'End of Design' | 'Comp-Approve'     | 'CS33242FB03'           |'R0402'| '(R0402-0201)'                 | '32.4K'   | '1%'    | '1/16W'  | 'DISCRETE' | 'RES CHIP 32.4K 1/16W +-1%(0402)EF'                | 'CHIPR0402'    | ''          | ''            | '20220413'
 '32.4K'      | '1%'      | '1/16W'  | '0402LF'  | 'EMPTY'  | 'CS33242FB03'(!)        = 'End of Design' | 'Comp-Approve'     | 'CS33242FB03'           |'R0402'| '(R0402-0201)'                 | '32.4K'   | '1%'    | '1/16W'  | 'IO'       | 'RES CHIP 32.4K 1/16W +-1%(0402)EF'                | 'CHIPR0402'    | ''          | ''            | '20220413'
 '6.19K'      | '1%'      | '1/10W'  | '0603LF'  | 'CHIP'   | 'CS26193F901'(!)        = ''              | ''                 | 'CS26193F901'           |'R0603'| '(SMR0603AW)'                  | '6.19K'   | '1%'    | '1/10W'  | 'DISCRETE' | 'RES CHIP 6.19K 1/10W +-1%(0603)EF'                | 'CHIPR0603'    | ''          | ''            | '20220421'
 '6.19K'      | '1%'      | '1/10W'  | '0603LF'  | 'EMPTY'  | 'CS26193F901'(!)        = ''              | ''                 | 'CS26193F901'           |'R0603'| '(SMR0603AW)'                  | '6.19K'   | '1%'    | '1/10W'  | 'IO'       | 'RES CHIP 6.19K 1/10W +-1%(0603)EF'                | 'CHIPR0603'    | ''          | ''            | '20220421'
 '68.1'       | '1%'      | '1/16W'  | '0402LF'  | 'CHIP'   | 'CS06812FB03'(!)        = 'End of Design' | 'Comp-Approve'     | 'CS06812FB03'           |'R0402'| '(R0402-0201)'                 | '68.1'    | '1%'    | '1/16W'  | 'DISCRETE' | 'RES CHIP 68.1 1/16W +-1%(0402)EF'                 | 'CHIPR0402'    | ''          | ''            | '20220421'
 '68.1'       | '1%'      | '1/16W'  | '0402LF'  | 'EMPTY'  | 'CS06812FB03'(!)        = 'End of Design' | 'Comp-Approve'     | 'CS06812FB03'           |'R0402'| '(R0402-0201)'                 | '68.1'    | '1%'    | '1/16W'  | 'IO'       | 'RES CHIP 68.1 1/16W +-1%(0402)EF'                 | 'CHIPR0402'    | ''          | ''            | '20220421'
 '10.5K'      | '1%'      | '1/16W'  | '0402LF'  | 'CHIP'   | 'CS31052FB03'(!)        = ''              | ''                 | 'CS31052FB03'           |'R0402'| '(R0402-0201)'                 | '10.5K'   | '1%'    | '1/16W'  | 'DISCRETE' | 'RES CHIP 10.5K 1/16W +-1%(0402)EF'                | 'CHIPR0402'    | ''          | ''            | '20220426'
 '10.5K'      | '1%'      | '1/16W'  | '0402LF'  | 'EMPTY'  | 'CS31052FB03'(!)        = ''              | ''                 | 'CS31052FB03'           |'R0402'| '(R0402-0201)'                 | '10.5K'   | '1%'    | '1/16W'  | 'IO'       | 'RES CHIP 10.5K 1/16W +-1%(0402)EF'                | 'CHIPR0402'    | ''          | ''            | '20220426'
 '124K'       | '1%'      | '1/16W'  | '0402LF'  | 'CHIP'   | 'CS41242FB04'(!)        = ''              | ''                 | 'CS41242FB04'           |'R0402'| '(R0402-0201)'                 | '124K'    | '1%'    | '1/16W'  | 'DISCRETE' | 'RES CHIP 124K 1/16W +-1%(0402)EF'                 | 'CHIPR0402'    | ''          | ''            | '20220510'
 '124K'       | '1%'      | '1/16W'  | '0402LF'  | 'EMPTY'  | 'CS41242FB04'(!)        = ''              | ''                 | 'CS41242FB04'           |'R0402'| '(R0402-0201)'                 | '124K'    | '1%'    | '1/16W'  | 'IO'       | 'RES CHIP 124K 1/16W +-1%(0402)EF'                 | 'CHIPR0402'    | ''          | ''            | '20220510'
 '0.1'        | '1%'      | '2W'     | '2512LF'  | 'CHIP'   | 'CS+100AFR00'(!)        = ''              | ''                 | 'CS+100AFR00'           |'R2512XAB'| '(SMR2512AW)'                  | '0.1'     | '1%'    | '2W'     | 'DISCRETE' | 'RES CHIP 0.1 2W +-1%(2512)'                       | 'CHIPR2512'    | ''          | ''            | '20220510'
 '0.1'        | '1%'      | '2W'     | '2512LF'  | 'EMPTY'  | 'CS+100AFR00'(!)        = ''              | ''                 | 'CS+100AFR00'           |'R2512XAB'| '(SMR2512AW)'                  | '0.1'     | '1%'    | '2W'     | 'IO'       | 'RES CHIP 0.1 2W +-1%(2512)'                       | 'CHIPR2512'    | ''          | ''            | '20220510'
 '348K'       | '1%'      | '1/4W'   | '1206LF'  | 'CHIP'   | 'CS43486F201'(!)        = ''              | ''                 | 'CS43486F201'           |'R1206XB'| '(SMR1206AW)'                  | '348K'    | '1%'    | '1/4W'   | 'DISCRETE' | 'RES CHIP 348K 1/4W +-1%(1206)'                    | 'CHIPR1206'    | ''          | ''            | '20220510'
 '348K'       | '1%'      | '1/4W'   | '1206LF'  | 'EMPTY'  | 'CS43486F201'(!)        = ''              | ''                 | 'CS43486F201'           |'R1206XB'| '(SMR1206AW)'                  | '348K'    | '1%'    | '1/4W'   | 'IO'       | 'RES CHIP 348K 1/4W +-1%(1206)'                    | 'CHIPR1206'    | ''          | ''            | '20220510'
 '191K'       | '1%'      | '1/4W'   | '1206LF'  | 'CHIP'   | 'CS41916F200'(!)        = ''              | ''                 | 'CS41916F200'           |'R1206XB'| '(SMR1206AW)'                  | '191K'    | '1%'    | '1/4W'   | 'DISCRETE' | 'RES CHIP 191K 1/4W +-1% (1206)'                   | 'CHIPR1206'    | ''          | ''            | '20220510'
 '191K'       | '1%'      | '1/4W'   | '1206LF'  | 'EMPTY'  | 'CS41916F200'(!)        = ''              | ''                 | 'CS41916F200'           |'R1206XB'| '(SMR1206AW)'                  | '191K'    | '1%'    | '1/4W'   | 'IO'       | 'RES CHIP 191K 1/4W +-1% (1206)'                   | 'CHIPR1206'    | ''          | ''            | '20220510'
 '6.34K'      | '1%'      | '1/16W'  | '0402LF'  | 'CHIP'   | 'CS26342FB02'(!)        = 'End of Design' | 'Comp-Approve'     | 'CS26342FB02'           |'R0402'| '(R0402-0201)'                 | '6.34K'   | '1%'    | '1/16W'  | 'DISCRETE' | 'RES CHIP 6.34K 1/16W +-1%(0402)EF'                | 'CHIPR0402'    | ''          | ''            | '20220510'
 '6.34K'      | '1%'      | '1/16W'  | '0402LF'  | 'EMPTY'  | 'CS26342FB02'(!)        = 'End of Design' | 'Comp-Approve'     | 'CS26342FB02'           |'R0402'| '(R0402-0201)'                 | '6.34K'   | '1%'    | '1/16W'  | 'IO'       | 'RES CHIP 6.34K 1/16W +-1%(0402)EF'                | 'CHIPR0402'    | ''          | ''            | '20220510'
 '7.5'        | '1%'      | '1/16W'  | '0402LF'  | 'CHIP'   | 'CS-7502FB02'(!)        = ''              | ''                 | 'CS-7502FB02'           |'R0402'| '(R0402-0201)'                 | '7.5'     | '1%'    | '1/16W'  | 'DISCRETE' | 'RES CHIP 7.5 1/16W +-1%(0402)EF'                  | 'CHIPR0402'    | ''          | ''            | '20220512'
 '7.5'        | '1%'      | '1/16W'  | '0402LF'  | 'EMPTY'  | 'CS-7502FB02'(!)        = ''              | ''                 | 'CS-7502FB02'           |'R0402'| '(R0402-0201)'                 | '7.5'     | '1%'    | '1/16W'  | 'IO'       | 'RES CHIP 7.5 1/16W +-1%(0402)EF'                  | 'CHIPR0402'    | ''          | ''            | '20220512'
 '4.7'        | '5%'      | '1/10W'  | '0603LF'  | 'CHIP'   | 'CS-4703J917'(!)        = ''              | ''                 | 'CS-4703J917'           |'R0603'| '(SMR0603AW)'                  | '4.7'     | '5%'    | '1/10W'  | 'DISCRETE' | 'RES CHIP 4.7 1/10W +-5%(0603)'                    | 'CHIPR0603'    | ''          | ''            | '20220519'
 '4.7'        | '5%'      | '1/10W'  | '0603LF'  | 'EMPTY'  | 'CS-4703J917'(!)        = ''              | ''                 | 'CS-4703J917'           |'R0603'| '(SMR0603AW)'                  | '4.7'     | '5%'    | '1/10W'  | 'IO'       | 'RES CHIP 4.7 1/10W +-5%(0603)'                    | 'CHIPR0603'    | ''          | ''            | '20220519'
 '47K'        | '1%'      | '1/4W'   | '1206LF'  | 'CHIP'   | 'CS34706F200'(!)        = ''              | ''                 | 'CS34706F200'           |'R1206XM'| '(SMR1206AW)'                  | '47K'     | '1%'    | '1/4W'   | 'DISCRETE' | 'RES CHIP 47K 1/4W 1%(1206)'                       | 'CHIPR1206'    | ''          | ''            | '20220520'
 '47K'        | '1%'      | '1/4W'   | '1206LF'  | 'EMPTY'  | 'CS34706F200'(!)        = ''              | ''                 | 'CS34706F200'           |'R1206XM'| '(SMR1206AW)'                  | '47K'     | '1%'    | '1/4W'   | 'IO'       | 'RES CHIP 47K 1/4W 1%(1206)'                       | 'CHIPR1206'    | ''          | ''            | '20220520'
 '0.005'      | '1%'      | '1W'     | '1206LF'  | 'CHIP'   | 'CS+0058F202'(!)        = 'End of Design' | 'Comp-Approve'     | 'CS+0058F202'           |'R1206XG'| '(SMR1206AW)'                  | '0.005'   | '1%'    | '1W'     | 'DISCRETE' | 'RES CHIP 0.005 1W +-1%(1206)EF'                   | 'CHIPR1206'    | ''          | ''            | '20220524'
 '0.005'      | '1%'      | '1W'     | '1206LF'  | 'EMPTY'  | 'CS+0058F202'(!)        = 'End of Design' | 'Comp-Approve'     | 'CS+0058F202'           |'R1206XG'| '(SMR1206AW)'                  | '0.005'   | '1%'    | '1W'     | 'IO'       | 'RES CHIP 0.005 1W +-1%(1206)EF'                   | 'CHIPR1206'    | ''          | ''            | '20220524'
 '237K'       | '1%'      | '1/16W'  | '0402LF'  | 'CHIP'   | 'CS42372FB04'(!)        = ''              | ''                 | 'CS42372FB04'           |'R0402'| '(R0402-0201)'                 | '237K'    | '1%'    | '1/16W'  | 'DISCRETE' | 'RES CHIP 237K 1/16W +-1% (0402)EF'                | 'CHIPR0402'    | ''          | ''            | '20220606'
 '237K'       | '1%'      | '1/16W'  | '0402LF'  | 'EMPTY'  | 'CS42372FB04'(!)        = ''              | ''                 | 'CS42372FB04'           |'R0402'| '(R0402-0201)'                 | '237K'    | '1%'    | '1/16W'  | 'IO'       | 'RES CHIP 237K 1/16W +-1% (0402)EF'                | 'CHIPR0402'    | ''          | ''            | '20220606'
 '56.2K'      | '0.1%'    | '1/16W'  | '0402LF'  | 'CHIP'   | 'CS35622BB04'(!)        = ''              | ''                 | 'CS35622BB04'           |'R0402'| '(R0402-0201)'                 | '56.2K'   | '0.1%'  | '1/16W'  | 'DISCRETE' | 'RES CHIP 56.2K 1/16W +-0.1%(0402)YGO'             | 'CHIPR0402'    | ''          | ''            | '20220608'
 '56.2K'      | '0.1%'    | '1/16W'  | '0402LF'  | 'EMPTY'  | 'CS35622BB04'(!)        = ''              | ''                 | 'CS35622BB04'           |'R0402'| '(R0402-0201)'                 | '56.2K'   | '0.1%'  | '1/16W'  | 'IO'       | 'RES CHIP 56.2K 1/16W +-0.1%(0402)YGO'             | 'CHIPR0402'    | ''          | ''            | '20220608'
 '12.4K'      | '1%'      | '1/16W'  | '0402LF'  | 'CHIP'   | 'CS31242FB09'(!)        = ''              | ''                 | 'CS31242FB09'           |'R0402'| '(R0402-0201)'                 | '12.4K'   | '1%'    | '1/16W'  | 'DISCRETE' | 'RES CHIP 12.4K 1/16W +-1% (0402)YGO'              | 'CHIPR0402'    | ''          | ''            | '20220608'
 '12.4K'      | '1%'      | '1/16W'  | '0402LF'  | 'EMPTY'  | 'CS31242FB09'(!)        = ''              | ''                 | 'CS31242FB09'           |'R0402'| '(R0402-0201)'                 | '12.4K'   | '1%'    | '1/16W'  | 'IO'       | 'RES CHIP 12.4K 1/16W +-1% (0402)YGO'              | 'CHIPR0402'    | ''          | ''            | '20220608'
 '20K'        | '0.1%'    | '1/16W'  | '0402LF'  | 'CHIP'   | 'CS32002BB10'(!)        = ''              | ''                 | 'CS32002BB10'           |'R0402'| '(R0402-0201)'                 | '20K'     | '0.1%'  | '1/16W'  | 'DISCRETE' | 'RES CHIP 20K 1/16W +-0.1%(0402)YGO'               | 'CHIPR0402'    | ''          | ''            | '20220608'
 '20K'        | '0.1%'    | '1/16W'  | '0402LF'  | 'EMPTY'  | 'CS32002BB10'(!)        = ''              | ''                 | 'CS32002BB10'           |'R0402'| '(R0402-0201)'                 | '20K'     | '0.1%'  | '1/16W'  | 'IO'       | 'RES CHIP 20K 1/16W +-0.1%(0402)YGO'               | 'CHIPR0402'    | ''          | ''            | '20220608'
 '10K'        | '1%'      | '1/16W'  | '0402LF'  | 'CHIP'   | 'CS31002FB10'(!)        = ''              | ''                 | 'CS31002FB10'           |'R0402'| '(R0402-0201)'                 | '10K'     | '1%'    | '1/16W'  | 'DISCRETE' | 'RES CHIP 10K(1%,1/16W,0402)YGO'                   | 'CHIPR0402'    | ''          | ''            | '20220608'
 '10K'        | '1%'      | '1/16W'  | '0402LF'  | 'EMPTY'  | 'CS31002FB10'(!)        = ''              | ''                 | 'CS31002FB10'           |'R0402'| '(R0402-0201)'                 | '10K'     | '1%'    | '1/16W'  | 'IO'       | 'RES CHIP 10K(1%,1/16W,0402)YGO'                   | 'CHIPR0402'    | ''          | ''            | '20220608'
 '5.36K'      | '1%'      | '1/16W'  | '0402LF'  | 'CHIP'   | 'CS25362FB06'(!)        = ''              | ''                 | 'CS25362FB06'           |'R0402'| '(R0402-0201)'                 | '5.36K'   | '1%'    | '1/16W'  | 'DISCRETE' | 'RES CHIP 5.36K 1/16W +-1% (0402)YGO'              | 'CHIPR0402'    | ''          | ''            | '20220608'
 '5.36K'      | '1%'      | '1/16W'  | '0402LF'  | 'EMPTY'  | 'CS25362FB06'(!)        = ''              | ''                 | 'CS25362FB06'           |'R0402'| '(R0402-0201)'                 | '5.36K'   | '1%'    | '1/16W'  | 'IO'       | 'RES CHIP 5.36K 1/16W +-1% (0402)YGO'              | 'CHIPR0402'    | ''          | ''            | '20220608'
 '10.7K'      | '0.1%'    | '1/16W'  | '0402LF'  | 'CHIP'   | 'CS31072BB00'(!)        = ''              | ''                 | 'CS31072BB00'           |'R0402'| '(R0402-0201)'                 | '10.7K'   | '0.1%'  | '1/16W'  | 'DISCRETE' | 'RES CHIP 10.7K 1/16W +-0.1%(0402)'                | 'CHIPR0402'    | ''          | ''            | '20220610'
 '10.7K'      | '0.1%'    | '1/16W'  | '0402LF'  | 'EMPTY'  | 'CS31072BB00'(!)        = ''              | ''                 | 'CS31072BB00'           |'R0402'| '(R0402-0201)'                 | '10.7K'   | '0.1%'  | '1/16W'  | 'IO'       | 'RES CHIP 10.7K 1/16W +-0.1%(0402)'                | 'CHIPR0402'    | ''          | ''            | '20220610'
 '1.91K'      | '1%'      | '1/16W'  | '0402LF'  | 'CHIP'   | 'CS21912FB13'(!)        = 'End of Design' | 'Comp-Approve'     | 'CS21912FB13'           |'R0402'| '(R0402-0201)'                 | '1.91K'   | '1%'    | '1/16W'  | 'DISCRETE' | 'RES CHIP 1.91K 1/16W +-1%(0402)'                  | 'CHIPR0402'    | ''          | ''            | '20220610'
 '1.91K'      | '1%'      | '1/16W'  | '0402LF'  | 'EMPTY'  | 'CS21912FB13'(!)        = 'End of Design' | 'Comp-Approve'     | 'CS21912FB13'           |'R0402'| '(R0402-0201)'                 | '1.91K'   | '1%'    | '1/16W'  | 'IO'       | 'RES CHIP 1.91K 1/16W +-1%(0402)'                  | 'CHIPR0402'    | ''          | ''            | '20220610'
 '20M'        | '1%'      | '1/16W'  | '0402LF'  | 'CHIP'   | 'CS62002FB01'(!)        = ''              | ''                 | 'CS62002FB01'           |'R0402'| '(R0402-0201)'                 | '20M'     | '1%'    | '1/16W'  | 'DISCRETE' | 'RES CHIP 20M 1/16W +-1%(0402)EF'                  | 'CHIPR0402'    | ''          | ''            | '20220613'
 '20M'        | '1%'      | '1/16W'  | '0402LF'  | 'EMPTY'  | 'CS62002FB01'(!)        = ''              | ''                 | 'CS62002FB01'           |'R0402'| '(R0402-0201)'                 | '20M'     | '1%'    | '1/16W'  | 'IO'       | 'RES CHIP 20M 1/16W +-1%(0402)EF'                  | 'CHIPR0402'    | ''          | ''            | '20220613'
 '30K'        | '1%'      | '1/16W'  | '0402LF'  | 'CHIP'   | 'CS33002FB02'(!)        = 'End of Design' | 'Comp-Approve'     | 'CS33002FB02'           |'R0402'| '(R0402-0201)'                 | '30K'     | '1%'    | '1/16W'  | 'DISCRETE' | 'RES CHIP 30K 1/16W +-1%(0402)EF'                  | 'CHIPR0402'    | ''          | ''            | '20220616'
 '30K'        | '1%'      | '1/16W'  | '0402LF'  | 'EMPTY'  | 'CS33002FB02'(!)        = 'End of Design' | 'Comp-Approve'     | 'CS33002FB02'           |'R0402'| '(R0402-0201)'                 | '30K'     | '1%'    | '1/16W'  | 'IO'       | 'RES CHIP 30K 1/16W +-1%(0402)EF'                  | 'CHIPR0402'    | ''          | ''            | '20220616'
 '13.7K'      | '1%'      | '1/16W'  | '0402LF'  | 'CHIP'   | 'CS31372FB03'(!)        = 'End of Design' | 'Comp-Approve'     | 'CS31372FB03'           |'R0402'| '(R0402-0201)'                 | '13.7K'   | '1%'    | '1/16W'  | 'DISCRETE' | 'RES CHIP 13.7K 1/16W +-1%(0402)EF'                | 'CHIPR0402'    | ''          | ''            | '20220622'
 '13.7K'      | '1%'      | '1/16W'  | '0402LF'  | 'EMPTY'  | 'CS31372FB03'(!)        = 'End of Design' | 'Comp-Approve'     | 'CS31372FB03'           |'R0402'| '(R0402-0201)'                 | '13.7K'   | '1%'    | '1/16W'  | 'IO'       | 'RES CHIP 13.7K 1/16W +-1%(0402)EF'                | 'CHIPR0402'    | ''          | ''            | '20220622'
 '16.9K'      | '1%'      | '1/16W'  | '0402LF'  | 'CHIP'   | 'CS31692FB13'(!)        = ''              | ''                 | 'CS31692FB13'           |'R0402'| '(R0402-0201)'                 | '16.9K'   | '1%'    | '1/16W'  | 'DISCRETE' | 'RES CHIP 16.9K 1/16W +-1% (0402)WTC'              | 'CHIPR0402'    | ''          | ''            | '20220624'
 '16.9K'      | '1%'      | '1/16W'  | '0402LF'  | 'EMPTY'  | 'CS31692FB13'(!)        = ''              | ''                 | 'CS31692FB13'           |'R0402'| '(R0402-0201)'                 | '16.9K'   | '1%'    | '1/16W'  | 'IO'       | 'RES CHIP 16.9K 1/16W +-1% (0402)WTC'              | 'CHIPR0402'    | ''          | ''            | '20220624'
 '16.9K'      | '1%'      | '1/16W'  | '0402LF'  | 'CHIP'   | 'CS31692FB14'(!)        = ''              | ''                 | 'CS31692FB14'           |'R0402'| '(R0402-0201)'                 | '16.9K'   | '1%'    | '1/16W'  | 'DISCRETE' | 'RES CHIP 16.9K 1/16W +-1% (0402)YGO'              | 'CHIPR0402'    | ''          | ''            | '20220624'
 '16.9K'      | '1%'      | '1/16W'  | '0402LF'  | 'EMPTY'  | 'CS31692FB14'(!)        = ''              | ''                 | 'CS31692FB14'           |'R0402'| '(R0402-0201)'                 | '16.9K'   | '1%'    | '1/16W'  | 'IO'       | 'RES CHIP 16.9K 1/16W +-1% (0402)YGO'              | 'CHIPR0402'    | ''          | ''            | '20220624'
 '120K'       | '1%'      | '1/16W'  | '0402LF'  | 'CHIP'   | 'CS41202FB15'(!)        = ''              | ''                 | 'CS41202FB15'           |'R0402'| '(R0402-0201)'                 | '120K'    | '1%'    | '1/16W'  | 'DISCRETE' | 'RES CHIP 120K 1/16W +-1%( 0402)CYN'               | 'CHIPR0402'    | ''          | ''            | '20220624'
 '120K'       | '1%'      | '1/16W'  | '0402LF'  | 'EMPTY'  | 'CS41202FB15'(!)        = ''              | ''                 | 'CS41202FB15'           |'R0402'| '(R0402-0201)'                 | '120K'    | '1%'    | '1/16W'  | 'IO'       | 'RES CHIP 120K 1/16W +-1%( 0402)CYN'               | 'CHIPR0402'    | ''          | ''            | '20220624'
 '120K'       | '1%'      | '1/16W'  | '0402LF'  | 'CHIP'   | 'CS41202FB16'(!)        = ''              | ''                 | 'CS41202FB16'           |'R0402'| '(R0402-0201)'                 | '120K'    | '1%'    | '1/16W'  | 'DISCRETE' | 'RES CHIP 120K 1/16W +-1%( 0402)YGO'               | 'CHIPR0402'    | ''          | ''            | '20220624'
 '120K'       | '1%'      | '1/16W'  | '0402LF'  | 'EMPTY'  | 'CS41202FB16'(!)        = ''              | ''                 | 'CS41202FB16'           |'R0402'| '(R0402-0201)'                 | '120K'    | '1%'    | '1/16W'  | 'IO'       | 'RES CHIP 120K 1/16W +-1%( 0402)YGO'               | 'CHIPR0402'    | ''          | ''            | '20220624'
 '0'          | '1%'      | '1/2W'   | '1206LF'  | 'CHIP'   | 'CS00007F201'(!)        = ''              | ''                 | 'CS00007F201'           |'R1206XI'| '(SMR1206AW)'                  | '0'       | '1%'    | '1/2W'   | 'DISCRETE' | 'RES CHIP 0 1/2W +-1%(1206)WTC'                    | 'CHIPR1206'    | ''          | ''            | '20220624'
 '0'          | '1%'      | '1/2W'   | '1206LF'  | 'EMPTY'  | 'CS00007F201'(!)        = ''              | ''                 | 'CS00007F201'           |'R1206XI'| '(SMR1206AW)'                  | '0'       | '1%'    | '1/2W'   | 'IO'       | 'RES CHIP 0 1/2W +-1%(1206)WTC'                    | 'CHIPR1206'    | ''          | ''            | '20220624'
 '0'          | '1%'      | '1/2W'   | '1206LF'  | 'CHIP'   | 'CS00007F202'(!)        = ''              | ''                 | 'CS00007F202'           |'R1206XF'| '(SMR1206AW)'                  | '0'       | '1%'    | '1/2W'   | 'DISCRETE' | 'RES CHIP 0 1/2W +-1%(1206)YGO'                    | 'CHIPR1206'    | ''          | ''            | '20220624'
 '0'          | '1%'      | '1/2W'   | '1206LF'  | 'EMPTY'  | 'CS00007F202'(!)        = ''              | ''                 | 'CS00007F202'           |'R1206XF'| '(SMR1206AW)'                  | '0'       | '1%'    | '1/2W'   | 'IO'       | 'RES CHIP 0 1/2W +-1%(1206)YGO'                    | 'CHIPR1206'    | ''          | ''            | '20220624'
 '127'        | '1%'      | '1/16W'  | '0402LF'  | 'CHIP'   | 'CS11272FB21'(!)        = 'End of Design' | 'Comp-Approve'     | 'CS11272FB21'           |'R0402'| '(R0402-0201)'                 | '127'     | '1%'    | '1/16W'  | 'DISCRETE' | 'RES CHIP 127 1/16W +-1%(0402)'                    | 'CHIPR0402'    | ''          | ''            | '20220704'
 '127'        | '1%'      | '1/16W'  | '0402LF'  | 'EMPTY'  | 'CS11272FB21'(!)        = 'End of Design' | 'Comp-Approve'     | 'CS11272FB21'           |'R0402'| '(R0402-0201)'                 | '127'     | '1%'    | '1/16W'  | 'IO'       | 'RES CHIP 127 1/16W +-1%(0402)'                    | 'CHIPR0402'    | ''          | ''            | '20220704'
 '0.001'      | '1%'      | '2W'     | '2512LF'  | 'CHIP'   | 'CS+001AFR12'(!)        = ''              | ''                 | 'CS+001AFR12'           |'R2512XG'| '(SMR2512AW)'                  | '0.001'   | '1%'    | '2W'     | 'DISCRETE' | 'RES CHIP 0.001 2W +-1%(2512)RLC'                  | 'CHIPR2512'    | ''          | ''            | '20220704'
 '0.001'      | '1%'      | '2W'     | '2512LF'  | 'EMPTY'  | 'CS+001AFR12'(!)        = ''              | ''                 | 'CS+001AFR12'           |'R2512XG'| '(SMR2512AW)'                  | '0.001'   | '1%'    | '2W'     | 'IO'       | 'RES CHIP 0.001 2W +-1%(2512)RLC'                  | 'CHIPR2512'    | ''          | ''            | '20220704'
 '7.5M'       | '1%'      | '1/16W'  | '0402LF'  | 'CHIP'   | 'CS57502FB00'(!)        = ''              | ''                 | 'CS57502FB00'           |'R0402'| '(R0402-0201)'                 | '7.5M'    | '1%'    | '1/16W'  | 'DISCRETE' | 'RES CHIP 7.5M 1/16W +-1%(0402)'                   | 'CHIPR0402'    | ''          | ''            | '20220704'
 '7.5M'       | '1%'      | '1/16W'  | '0402LF'  | 'EMPTY'  | 'CS57502FB00'(!)        = ''              | ''                 | 'CS57502FB00'           |'R0402'| '(R0402-0201)'                 | '7.5M'    | '1%'    | '1/16W'  | 'IO'       | 'RES CHIP 7.5M 1/16W +-1%(0402)'                   | 'CHIPR0402'    | ''          | ''            | '20220704'
 '619K'       | '1%'      | '1/8W'   | '0805LF'  | 'CHIP'   | 'CS46194FA00'(!)        = ''              | ''                 | 'CS46194FA00'           |'R0805'| '(SMR0805AW)'                  | '619K'    | '1%'    | '1/8W'   | 'DISCRETE' | 'RES CHIP 619K 1/8W +-1%(0805)'                    | 'CHIPR0805'    | ''          | ''            | '20220715'
 '619K'       | '1%'      | '1/8W'   | '0805LF'  | 'EMPTY'  | 'CS46194FA00'(!)        = ''              | ''                 | 'CS46194FA00'           |'R0805'| '(SMR0805AW)'                  | '619K'    | '1%'    | '1/8W'   | 'IO'       | 'RES CHIP 619K 1/8W +-1%(0805)'                    | 'CHIPR0805'    | ''          | ''            | '20220715'
 '97.6K'      | '1%'      | '1/8W'   | '0805LF'  | 'CHIP'   | 'CS39764FA00'(!)        = ''              | ''                 | 'CS39764FA00'           |'R0805'| '(SMR0805AW)'                  | '97.6K'   | '1%'    | '1/8W'   | 'DISCRETE' | 'RES CHIP 97.6K 1/8W +-1%(0805)'                   | 'CHIPR0805'    | ''          | ''            | '20220715'
 '97.6K'      | '1%'      | '1/8W'   | '0805LF'  | 'EMPTY'  | 'CS39764FA00'(!)        = ''              | ''                 | 'CS39764FA00'           |'R0805'| '(SMR0805AW)'                  | '97.6K'   | '1%'    | '1/8W'   | 'IO'       | 'RES CHIP 97.6K 1/8W +-1%(0805)'                   | 'CHIPR0805'    | ''          | ''            | '20220715'
 '16K'        | '1%'      | '1/16W'  | '0402LF'  | 'CHIP'   | 'CS31602FB01'(!)        = 'End of Design' | 'Comp-Approve'     | 'CS31602FB01'           |'R0402'| '(R0402-0201)'                 | '16K'     | '1%'    | '1/16W'  | 'DISCRETE' | 'RES CHIP 16K 1/16W +-1%(0402)EF'                  | 'CHIPR0402'    | ''          | ''            | '20220802'
 '16K'        | '1%'      | '1/16W'  | '0402LF'  | 'EMPTY'  | 'CS31602FB01'(!)        = 'End of Design' | 'Comp-Approve'     | 'CS31602FB01'           |'R0402'| '(R0402-0201)'                 | '16K'     | '1%'    | '1/16W'  | 'IO'       | 'RES CHIP 16K 1/16W +-1%(0402)EF'                  | 'CHIPR0402'    | ''          | ''            | '20220802'
 '374K'       | '1%'      | '1/16W'  | '0402LF'  | 'CHIP'   | 'CS43742FB00'(!)        = 'End of Design' | 'Comp-Approve'     | 'CS43742FB00'           |'R0402'| '(R0402-0201)'                 | '374K'    | '1%'    | '1/16W'  | 'DISCRETE' | 'RES CHIP 374K 1/16W +-1%(0402)'                   | 'CHIPR0402'    | ''          | ''            | '20220803'
 '374K'       | '1%'      | '1/16W'  | '0402LF'  | 'EMPTY'  | 'CS43742FB00'(!)        = 'End of Design' | 'Comp-Approve'     | 'CS43742FB00'           |'R0402'| '(R0402-0201)'                 | '374K'    | '1%'    | '1/16W'  | 'IO'       | 'RES CHIP 374K 1/16W +-1%(0402)'                   | 'CHIPR0402'    | ''          | ''            | '20220803'
 '10K'        | '1%'      | '1/20W'  | '0201LF'  | 'CHIP'   | 'CS31001FE16'(!)        = ''              | ''                 | 'CS31001FE16'           |'R0201'| '(SMR0201AW)'                  | '10K'     | '1%'    | '1/20W'  | 'DISCRETE' | 'RES CHIP 10K 1/20W +-1%(0201)YGO'                 | 'CHIPR0201'    | ''          | ''            | '20220816'
 '10K'        | '1%'      | '1/20W'  | '0201LF'  | 'EMPTY'  | 'CS31001FE16'(!)        = ''              | ''                 | 'CS31001FE16'           |'R0201'| '(SMR0201AW)'                  | '10K'     | '1%'    | '1/20W'  | 'IO'       | 'RES CHIP 10K 1/20W +-1%(0201)YGO'                 | 'CHIPR0201'    | ''          | ''            | '20220816'
 '0.03'       | '1%'      | '1/2W'   | '0805LF'  | 'CHIP'   | 'CS+0307FA02'(!)        = ''              | ''                 | 'CS+0307FA02'           |'R0805_H26'| '(SMR0805AW)'                  | '0.03'    | '1%'    | '1/2W'   | 'DISCRETE' | 'RES CHIP 0.03 1/2W 1%(0805)H0.55'                 | 'CHIPR0805'    | ''          | ''            | '20220818'
 '0.03'       | '1%'      | '1/2W'   | '0805LF'  | 'EMPTY'  | 'CS+0307FA02'(!)        = ''              | ''                 | 'CS+0307FA02'           |'R0805_H26'| '(SMR0805AW)'                  | '0.03'    | '1%'    | '1/2W'   | 'IO'       | 'RES CHIP 0.03 1/2W 1%(0805)H0.55'                 | 'CHIPR0805'    | ''          | ''            | '20220818'
 '470'        | '1%'      | '1/20W'  | '0201LF'  | 'CHIP'   | 'CS14701FE10'(!)        = ''              | ''                 | 'CS14701FE10'           |'R0201'| '(SMR0201AW)'                  | '470'     | '1%'    | '1/20W'  | 'DISCRETE' | 'RES CHIP 470 1/20W +-1% (0201)YGO'                | 'CHIPR0201'    | ''          | ''            | '20220818'
 '470'        | '1%'      | '1/20W'  | '0201LF'  | 'EMPTY'  | 'CS14701FE10'(!)        = ''              | ''                 | 'CS14701FE10'           |'R0201'| '(SMR0201AW)'                  | '470'     | '1%'    | '1/20W'  | 'IO'       | 'RES CHIP 470 1/20W +-1% (0201)YGO'                | 'CHIPR0201'    | ''          | ''            | '20220818'
 '0'          | ''        | '1/16W'  | '0402LF'  | 'CHIP'   | 'CS00002TB04'(!)        = ''              | ''                 | 'CS00002TB04'           |'R0402'| '(R0402-0201)'                 | '0'       | ''      | '1/16W'  | 'DISCRETE' | 'RES CHIP 0 1/16W(0402)WTC'                        | 'CHIPR0402'    | ''          | ''            | '20220824'
 '0'          | ''        | '1/16W'  | '0402LF'  | 'EMPTY'  | 'CS00002TB04'(!)        = ''              | ''                 | 'CS00002TB04'           |'R0402'| '(R0402-0201)'                 | '0'       | ''      | '1/16W'  | 'IO'       | 'RES CHIP 0 1/16W(0402)WTC'                        | 'CHIPR0402'    | ''          | ''            | '20220824'
 '0.2'        | '1%'      | '1/16W'  | '0402LF'  | 'CHIP'   | 'CS+2002FB00'(!)        = ''              | ''                 | 'CS+2002FB00'           |'R0402'| '(R0402-0201)'                 | '0.2'     | '1%'    | '1/16W'  | 'DISCRETE' | 'RES CHIP 0.2 1/16W +-1%(0402)'                    | 'CHIPR0402'    | ''          | ''            | '20220829'
 '0.2'        | '1%'      | '1/16W'  | '0402LF'  | 'EMPTY'  | 'CS+2002FB00'(!)        = ''              | ''                 | 'CS+2002FB00'           |'R0402'| '(R0402-0201)'                 | '0.2'     | '1%'    | '1/16W'  | 'IO'       | 'RES CHIP 0.2 1/16W +-1%(0402)'                    | 'CHIPR0402'    | ''          | ''            | '20220829'
 '56.2K'      | '1%'      | '1/10W'  | '0603LF'  | 'CHIP'   | 'CS35623F924'(!)        = ''              | ''                 | 'CS35623F924'           |'R0603'| '(SMR0603AW)'                  | '56.2K'   | '1%'    | '1/10W'  | 'DISCRETE' | 'RESISTOR CHIP 56.2K,1/10W,+-1%(0603)'             | 'CHIPR0603'    | ''          | ''            | '20220829'
 '56.2K'      | '1%'      | '1/10W'  | '0603LF'  | 'EMPTY'  | 'CS35623F924'(!)        = ''              | ''                 | 'CS35623F924'           |'R0603'| '(SMR0603AW)'                  | '56.2K'   | '1%'    | '1/10W'  | 'IO'       | 'RESISTOR CHIP 56.2K,1/10W,+-1%(0603)'             | 'CHIPR0603'    | ''          | ''            | '20220829'
 '42.2K'      | '1%'      | '1/16W'  | '0402LF'  | 'CHIP'   | 'CS34222FB06'(!)        = ''              | ''                 | 'CS34222FB06'           |'R0402'| '(R0402-0201)'                 | '42.2K'   | '1%'    | '1/16W'  | 'DISCRETE' | 'RES CHIP 42.2K 1/16W +-1%(0402)EF'                | 'CHIPR0402'    | ''          | ''            | '20220905'
 '42.2K'      | '1%'      | '1/16W'  | '0402LF'  | 'EMPTY'  | 'CS34222FB06'(!)        = ''              | ''                 | 'CS34222FB06'           |'R0402'| '(R0402-0201)'                 | '42.2K'   | '1%'    | '1/16W'  | 'IO'       | 'RES CHIP 42.2K 1/16W +-1%(0402)EF'                | 'CHIPR0402'    | ''          | ''            | '20220905'
 '2.94K'      | '1%'      | '1/16W'  | '0402LF'  | 'CHIP'   | 'CS22942FB03'(!)        = 'End of Design' | 'Comp-Approve'     | 'CS22942FB03'           |'R0402'| '(R0402-0201)'                 | '2.94K'   | '1%'    | '1/16W'  | 'DISCRETE' | 'RES CHIP 2.94K 1/16W +-1%(0402)EF'                | 'CHIPR0402'    | ''          | ''            | '20220927'
 '2.94K'      | '1%'      | '1/16W'  | '0402LF'  | 'EMPTY'  | 'CS22942FB03'(!)        = 'End of Design' | 'Comp-Approve'     | 'CS22942FB03'           |'R0402'| '(R0402-0201)'                 | '2.94K'   | '1%'    | '1/16W'  | 'IO'       | 'RES CHIP 2.94K 1/16W +-1%(0402)EF'                | 'CHIPR0402'    | ''          | ''            | '20220927'
 '45.3K'      | '0.1%'    | '1/16W'  | '0402LF'  | 'CHIP'   | 'CS34532BB01'(!)        = ''              | ''                 | 'CS34532BB01'           |'R0402'| '(R0402-0201)'                 | '45.3K'   | '0.1%'  | '1/16W'  | 'DISCRETE' | 'RES CHIP 45.3K 1/16W +-0.1%(0402)'                | 'CHIPR0402'    | ''          | ''            | '20220928'
 '45.3K'      | '0.1%'    | '1/16W'  | '0402LF'  | 'EMPTY'  | 'CS34532BB01'(!)        = ''              | ''                 | 'CS34532BB01'           |'R0402'| '(R0402-0201)'                 | '45.3K'   | '0.1%'  | '1/16W'  | 'IO'       | 'RES CHIP 45.3K 1/16W +-0.1%(0402)'                | 'CHIPR0402'    | ''          | ''            | '20220928'
 '383K'       | '1%'      | '1/16W'  | '0402LF'  | 'CHIP'   | 'CS43832FB00'(!)        = 'End of Design' | 'Comp-Approve'     | 'CS43832FB00'           |'R0402'| '(R0402-0201)'                 | '383K'    | '1%'    | '1/16W'  | 'DISCRETE' | 'RES CHIP 383K 1/16W +-1% (0402)'                  | 'CHIPR0402'    | ''          | ''            | '20220929'
 '383K'       | '1%'      | '1/16W'  | '0402LF'  | 'EMPTY'  | 'CS43832FB00'(!)        = 'End of Design' | 'Comp-Approve'     | 'CS43832FB00'           |'R0402'| '(R0402-0201)'                 | '383K'    | '1%'    | '1/16W'  | 'IO'       | 'RES CHIP 383K 1/16W +-1% (0402)'                  | 'CHIPR0402'    | ''          | ''            | '20220929'
 '5.1'        | '1%'      | '1/8W'   | '0805LF'  | 'CHIP'   | 'CS-5104FA21'(!)        = ''              | ''                 | 'CS-5104FA21'           |'R0805_H26'| '(SMR0805AW)'                  | '5.1'     | '1%'    | '1/8W'   | 'DISCRETE' | 'RES CHIP 5.1 1/8W +-1%(0805)'                     | 'CHIPR0805'    | ''          | ''            | '20221003'
 '5.1'        | '1%'      | '1/8W'   | '0805LF'  | 'EMPTY'  | 'CS-5104FA21'(!)        = ''              | ''                 | 'CS-5104FA21'           |'R0805_H26'| '(SMR0805AW)'                  | '5.1'     | '1%'    | '1/8W'   | 'IO'       | 'RES CHIP 5.1 1/8W +-1%(0805)'                     | 'CHIPR0805'    | ''          | ''            | '20221003'
 '5.6'        | '1%'      | '1/16W'  | '0402LF'  | 'CHIP'   | 'CS-5602FB00'(!)        = 'End of Design' | 'Comp-Approve'     | 'CS-5602FB00'           |'R0402'| '(R0402-0201)'                 | '5.6'     | '1%'    | '1/16W'  | 'DISCRETE' | 'RES CHIP 5.6 1/16W 1%(0402)'                      | 'CHIPR0402'    | ''          | ''            | '20221007'
 '5.6'        | '1%'      | '1/16W'  | '0402LF'  | 'EMPTY'  | 'CS-5602FB00'(!)        = 'End of Design' | 'Comp-Approve'     | 'CS-5602FB00'           |'R0402'| '(R0402-0201)'                 | '5.6'     | '1%'    | '1/16W'  | 'IO'       | 'RES CHIP 5.6 1/16W 1%(0402)'                      | 'CHIPR0402'    | ''          | ''            | '20221007'
 '3.83K'      | '0.1%'    | '1/16W'  | '0402LF'  | 'CHIP'   | 'CS23832BB01'(!)        = ''              | ''                 | 'CS23832BB01'           |'R0402'| '(R0402-0201)'                 | '3.83K'   | '0.1%'  | '1/16W'  | 'DISCRETE' | 'RES CHIP 3.83K 1/16W +-0.1% (0402)'               | 'CHIPR0402'    | ''          | ''            | '20221011'
 '3.83K'      | '0.1%'    | '1/16W'  | '0402LF'  | 'EMPTY'  | 'CS23832BB01'(!)        = ''              | ''                 | 'CS23832BB01'           |'R0402'| '(R0402-0201)'                 | '3.83K'   | '0.1%'  | '1/16W'  | 'IO'       | 'RES CHIP 3.83K 1/16W +-0.1% (0402)'               | 'CHIPR0402'    | ''          | ''            | '20221011'
 '0'          | '5%'      | '1/16W'  | '0402LF'  | 'CHIP'   | 'CS00002JB15'(!)        = ''              | ''                 | 'CS00002JB15'           |'R0402'| '(R0402-0201)'                 | '0'       | '5%'    | '1/16W'  | 'DISCRETE' | 'RES CHIP 0(5%,1/16W,0402)YGO'                     | 'CHIPR0402'    | ''          | ''            | '20221017'
 '0'          | '5%'      | '1/16W'  | '0402LF'  | 'EMPTY'  | 'CS00002JB15'(!)        = ''              | ''                 | 'CS00002JB15'           |'R0402'| '(R0402-0201)'                 | '0'       | '5%'    | '1/16W'  | 'IO'       | 'RES CHIP 0(5%,1/16W,0402)YGO'                     | 'CHIPR0402'    | ''          | ''            | '20221017'
 '1K'         | '5%'      | '1/16W'  | '0402LF'  | 'CHIP'   | 'CS21002JB25'(!)        = ''              | ''                 | 'CS21002JB25'           |'R0402'| '(R0402-0201)'                 | '1K'      | '5%'    | '1/16W'  | 'DISCRETE' | 'RES CHIP 1K 1/16W 5%(0402) WTC'                   | 'CHIPR0402'    | ''          | ''            | '20221017'
 '1K'         | '5%'      | '1/16W'  | '0402LF'  | 'EMPTY'  | 'CS21002JB25'(!)        = ''              | ''                 | 'CS21002JB25'           |'R0402'| '(R0402-0201)'                 | '1K'      | '5%'    | '1/16W'  | 'IO'       | 'RES CHIP 1K 1/16W 5%(0402) WTC'                   | 'CHIPR0402'    | ''          | ''            | '20221017'
 '4.7K'       | '5%'      | '1/16W'  | '0402LF'  | 'CHIP'   | 'CS24702JB18'(!)        = ''              | ''                 | 'CS24702JB18'           |'R0402'| '(R0402-0201)'                 | '4.7K'    | '5%'    | '1/16W'  | 'DISCRETE' | 'RES CHIP 4.7K 1/16W +-5% (0402)WTC'               | 'CHIPR0402'    | ''          | ''            | '20221017'
 '4.7K'       | '5%'      | '1/16W'  | '0402LF'  | 'EMPTY'  | 'CS24702JB18'(!)        = ''              | ''                 | 'CS24702JB18'           |'R0402'| '(R0402-0201)'                 | '4.7K'    | '5%'    | '1/16W'  | 'IO'       | 'RES CHIP 4.7K 1/16W +-5% (0402)WTC'               | 'CHIPR0402'    | ''          | ''            | '20221017'
 '10'         | '1%'      | '1/16W'  | '0402LF'  | 'CHIP'   | 'CS01002FB29'(!)        = ''              | ''                 | 'CS01002FB29'           |'R0402'| '(R0402-0201)'                 | '10'      | '1%'    | '1/16W'  | 'DISCRETE' | 'RES CHIP 10 1/16W +-1%(0402)CYN'                  | 'CHIPR0402'    | ''          | ''            | '20221017'
 '10'         | '1%'      | '1/16W'  | '0402LF'  | 'EMPTY'  | 'CS01002FB29'(!)        = ''              | ''                 | 'CS01002FB29'           |'R0402'| '(R0402-0201)'                 | '10'      | '1%'    | '1/16W'  | 'IO'       | 'RES CHIP 10 1/16W +-1%(0402)CYN'                  | 'CHIPR0402'    | ''          | ''            | '20221017'
 '10'         | '1%'      | '1/16W'  | '0402LF'  | 'CHIP'   | 'CS01002FB28'(!)        = ''              | ''                 | 'CS01002FB28'           |'R0402'| '(R0402-0201)'                 | '10'      | '1%'    | '1/16W'  | 'DISCRETE' | 'RES CHIP 10 1/16W +-1%(0402)WTC'                  | 'CHIPR0402'    | ''          | ''            | '20221017'
 '10'         | '1%'      | '1/16W'  | '0402LF'  | 'EMPTY'  | 'CS01002FB28'(!)        = ''              | ''                 | 'CS01002FB28'           |'R0402'| '(R0402-0201)'                 | '10'      | '1%'    | '1/16W'  | 'IO'       | 'RES CHIP 10 1/16W +-1%(0402)WTC'                  | 'CHIPR0402'    | ''          | ''            | '20221017'
 '1K'         | '1%'      | '1/16W'  | '0402LF'  | 'CHIP'   | 'CS21002FB27'(!)        = ''              | ''                 | 'CS21002FB27'           |'R0402'| '(R0402-0201)'                 | '1K'      | '1%'    | '1/16W'  | 'DISCRETE' | 'RES CHIP 1K 1/16W +-1% (0402)WTC'                 | 'CHIPR0402'    | ''          | ''            | '20221017'
 '1K'         | '1%'      | '1/16W'  | '0402LF'  | 'EMPTY'  | 'CS21002FB27'(!)        = ''              | ''                 | 'CS21002FB27'           |'R0402'| '(R0402-0201)'                 | '1K'      | '1%'    | '1/16W'  | 'IO'       | 'RES CHIP 1K 1/16W +-1% (0402)WTC'                 | 'CHIPR0402'    | ''          | ''            | '20221017'
 '6.81K'      | '1%'      | '1/16W'  | '0402LF'  | 'CHIP'   | 'CS26812FB10'(!)        = ''              | ''                 | 'CS26812FB10'           |'R0402'| '(R0402-0201)'                 | '6.81K'   | '1%'    | '1/16W'  | 'DISCRETE' | 'RES CHIP 6.81K 1/16W +-1% (0402)WTC'              | 'CHIPR0402'    | ''          | ''            | '20221017'
 '6.81K'      | '1%'      | '1/16W'  | '0402LF'  | 'EMPTY'  | 'CS26812FB10'(!)        = ''              | ''                 | 'CS26812FB10'           |'R0402'| '(R0402-0201)'                 | '6.81K'   | '1%'    | '1/16W'  | 'IO'       | 'RES CHIP 6.81K 1/16W +-1% (0402)WTC'              | 'CHIPR0402'    | ''          | ''            | '20221017'
 '13K'        | '1%'      | '1/16W'  | '0402LF'  | 'CHIP'   | 'CS31302FB10'(!)        = ''              | ''                 | 'CS31302FB10'           |'R0402'| '(R0402-0201)'                 | '13K'     | '1%'    | '1/16W'  | 'DISCRETE' | 'RES CHIP 13K 1/16W +-1%( 0402)WTC'                | 'CHIPR0402'    | ''          | ''            | '20221017'
 '13K'        | '1%'      | '1/16W'  | '0402LF'  | 'EMPTY'  | 'CS31302FB10'(!)        = ''              | ''                 | 'CS31302FB10'           |'R0402'| '(R0402-0201)'                 | '13K'     | '1%'    | '1/16W'  | 'IO'       | 'RES CHIP 13K 1/16W +-1%( 0402)WTC'                | 'CHIPR0402'    | ''          | ''            | '20221017'
 '100K'       | '1%'      | '1/16W'  | '0402LF'  | 'CHIP'   | 'CS41002FB14'(!)        = ''              | ''                 | 'CS41002FB14'           |'R0402'| '(R0402-0201)'                 | '100K'    | '1%'    | '1/16W'  | 'DISCRETE' | 'RES CHIP 100K(1%,1/16W,0402)WTC'                  | 'CHIPR0402'    | ''          | ''            | '20221017'
 '100K'       | '1%'      | '1/16W'  | '0402LF'  | 'EMPTY'  | 'CS41002FB14'(!)        = ''              | ''                 | 'CS41002FB14'           |'R0402'| '(R0402-0201)'                 | '100K'    | '1%'    | '1/16W'  | 'IO'       | 'RES CHIP 100K(1%,1/16W,0402)WTC'                  | 'CHIPR0402'    | ''          | ''            | '20221017'
 '33'         | '5%'      | '1/16W'  | '0402LF'  | 'CHIP'   | 'CS03302JB22'(!)        = ''              | ''                 | 'CS03302JB22'           |'R0402'| '(R0402-0201)'                 | '33'      | '5%'    | '1/16W'  | 'DISCRETE' | 'RES CHIP 33 1/16W +-5% (0402)WTC'                 | 'CHIPR0402'    | ''          | ''            | '20221017'
 '33'         | '5%'      | '1/16W'  | '0402LF'  | 'EMPTY'  | 'CS03302JB22'(!)        = ''              | ''                 | 'CS03302JB22'           |'R0402'| '(R0402-0201)'                 | '33'      | '5%'    | '1/16W'  | 'IO'       | 'RES CHIP 33 1/16W +-5% (0402)WTC'                 | 'CHIPR0402'    | ''          | ''            | '20221017'
 '60.4K'      | '1%'      | '1/16W'  | '0402LF'  | 'CHIP'   | 'CS36042FB11'(!)        = ''              | ''                 | 'CS36042FB11'           |'R0402'| '(R0402-0201)'                 | '60.4K'   | '1%'    | '1/16W'  | 'DISCRETE' | 'RES CHIP 60.4K 1/16W +-1%(0402)WTC'               | 'CHIPR0402'    | ''          | ''            | '20221017'
 '60.4K'      | '1%'      | '1/16W'  | '0402LF'  | 'EMPTY'  | 'CS36042FB11'(!)        = ''              | ''                 | 'CS36042FB11'           |'R0402'| '(R0402-0201)'                 | '60.4K'   | '1%'    | '1/16W'  | 'IO'       | 'RES CHIP 60.4K 1/16W +-1%(0402)WTC'               | 'CHIPR0402'    | ''          | ''            | '20221017'
 '6.81K'      | '1%'      | '1/16W'  | '0402LF'  | 'CHIP'   | 'CS26812FB11'(!)        = ''              | ''                 | 'CS26812FB11'           |'R0402'| '(R0402-0201)'                 | '6.81K'   | '1%'    | '1/16W'  | 'DISCRETE' | 'RES CHIP 6.81K 1/16W +-1% (0402)YGO'              | 'CHIPR0402'    | ''          | ''            | '20221017'
 '6.81K'      | '1%'      | '1/16W'  | '0402LF'  | 'EMPTY'  | 'CS26812FB11'(!)        = ''              | ''                 | 'CS26812FB11'           |'R0402'| '(R0402-0201)'                 | '6.81K'   | '1%'    | '1/16W'  | 'IO'       | 'RES CHIP 6.81K 1/16W +-1% (0402)YGO'              | 'CHIPR0402'    | ''          | ''            | '20221017'
 '13K'        | '1%'      | '1/16W'  | '0402LF'  | 'CHIP'   | 'CS31302FB09'(!)        = ''              | ''                 | 'CS31302FB09'           |'R0402'| '(R0402-0201)'                 | '13K'     | '1%'    | '1/16W'  | 'DISCRETE' | 'RES CHIP 13K 1/16W +-1%( 0402)YGO'                | 'CHIPR0402'    | ''          | ''            | '20221017'
 '13K'        | '1%'      | '1/16W'  | '0402LF'  | 'EMPTY'  | 'CS31302FB09'(!)        = ''              | ''                 | 'CS31302FB09'           |'R0402'| '(R0402-0201)'                 | '13K'     | '1%'    | '1/16W'  | 'IO'       | 'RES CHIP 13K 1/16W +-1%( 0402)YGO'                | 'CHIPR0402'    | ''          | ''            | '20221017'
 '48.7K'      | '1%'      | '1/16W'  | '0402LF'  | 'CHIP'   | 'CS34872FB13'(!)        = ''              | ''                 | 'CS34872FB13'           |'R0402'| '(R0402-0201)'                 | '48.7K'   | '1%'    | '1/16W'  | 'DISCRETE' | 'RES CHIP 48.7K 1/16W +-1% (0402)YGO'              | 'CHIPR0402'    | ''          | ''            | '20221017'
 '48.7K'      | '1%'      | '1/16W'  | '0402LF'  | 'EMPTY'  | 'CS34872FB13'(!)        = ''              | ''                 | 'CS34872FB13'           |'R0402'| '(R0402-0201)'                 | '48.7K'   | '1%'    | '1/16W'  | 'IO'       | 'RES CHIP 48.7K 1/16W +-1% (0402)YGO'              | 'CHIPR0402'    | ''          | ''            | '20221017'
 '54.9K'      | '1%'      | '1/16W'  | '0402LF'  | 'CHIP'   | 'CS35492FB12'(!)        = ''              | ''                 | 'CS35492FB12'           |'R0402'| '(R0402-0201)'                 | '54.9K'   | '1%'    | '1/16W'  | 'DISCRETE' | 'RES CHIP 54.9K 1/16W +-1%(0402)YGO'               | 'CHIPR0402'    | ''          | ''            | '20221017'
 '54.9K'      | '1%'      | '1/16W'  | '0402LF'  | 'EMPTY'  | 'CS35492FB12'(!)        = ''              | ''                 | 'CS35492FB12'           |'R0402'| '(R0402-0201)'                 | '54.9K'   | '1%'    | '1/16W'  | 'IO'       | 'RES CHIP 54.9K 1/16W +-1%(0402)YGO'               | 'CHIPR0402'    | ''          | ''            | '20221017'
 '0'          | '5%'      | '1/8W'   | '0805LF'  | 'CHIP'   | 'CS00004JA09'(!)        = ''              | ''                 | 'CS00004JA09'           |'R0805'| '(SMR0805AW)'                  | '0'       | '5%'    | '1/8W'   | 'DISCRETE' | 'RES CHIP 0 1/8W +-5%(0805)YGO'                    | 'CHIPR0805'    | ''          | ''            | '20221017'
 '0'          | '5%'      | '1/8W'   | '0805LF'  | 'EMPTY'  | 'CS00004JA09'(!)        = ''              | ''                 | 'CS00004JA09'           |'R0805'| '(SMR0805AW)'                  | '0'       | '5%'    | '1/8W'   | 'IO'       | 'RES CHIP 0 1/8W +-5%(0805)YGO'                    | 'CHIPR0805'    | ''          | ''            | '20221017'
 '10'         | '1%'      | '1/10W'  | '0603LF'  | 'CHIP'   | 'CS01003F912'(!)        = ''              | ''                 | 'CS01003F912'           |'R0603'| '(SMR0603AW)'                  | '10'      | '1%'    | '1/10W'  | 'DISCRETE' | 'RES CHIP 10 1/10W +-1%(0603)YGO'                  | 'CHIPR0603'    | ''          | ''            | '20221017'
 '10'         | '1%'      | '1/10W'  | '0603LF'  | 'EMPTY'  | 'CS01003F912'(!)        = ''              | ''                 | 'CS01003F912'           |'R0603'| '(SMR0603AW)'                  | '10'      | '1%'    | '1/10W'  | 'IO'       | 'RES CHIP 10 1/10W +-1%(0603)YGO'                  | 'CHIPR0603'    | ''          | ''            | '20221017'
 '33'         | '5%'      | '1/16W'  | '0402LF'  | 'CHIP'   | 'CS03302JB23'(!)        = ''              | ''                 | 'CS03302JB23'           |'R0402'| '(R0402-0201)'                 | '33'      | '5%'    | '1/16W'  | 'DISCRETE' | 'RES CHIP 33 1/16W +-5% (0402)YGO'                 | 'CHIPR0402'    | ''          | ''            | '20221017'
 '33'         | '5%'      | '1/16W'  | '0402LF'  | 'EMPTY'  | 'CS03302JB23'(!)        = ''              | ''                 | 'CS03302JB23'           |'R0402'| '(R0402-0201)'                 | '33'      | '5%'    | '1/16W'  | 'IO'       | 'RES CHIP 33 1/16W +-5% (0402)YGO'                 | 'CHIPR0402'    | ''          | ''            | '20221017'
 '60.4K'      | '1%'      | '1/16W'  | '0402LF'  | 'CHIP'   | 'CS36042FB09'(!)        = ''              | ''                 | 'CS36042FB09'           |'R0402'| '(R0402-0201)'                 | '60.4K'   | '1%'    | '1/16W'  | 'DISCRETE' | 'RES CHIP 60.4K 1/16W +-1%(0402)YGO'               | 'CHIPR0402'    | ''          | ''            | '20221017'
 '60.4K'      | '1%'      | '1/16W'  | '0402LF'  | 'EMPTY'  | 'CS36042FB09'(!)        = ''              | ''                 | 'CS36042FB09'           |'R0402'| '(R0402-0201)'                 | '60.4K'   | '1%'    | '1/16W'  | 'IO'       | 'RES CHIP 60.4K 1/16W +-1%(0402)YGO'               | 'CHIPR0402'    | ''          | ''            | '20221017'
 '0'          | ''        | '1/8W'   | '0805LF'  | 'CHIP'   | 'CS00004TA05'(!)        = ''              | ''                 | 'CS00004TA05'           |'R0805_H26'| '(SMR0805AW)'                  | '0'       | ''      | '1/8W'   | 'DISCRETE' | 'RES CHIP 0 1/8W(0805)WTC'                         | 'CHIPR0805'    | ''          | ''            | '20221018'
 '0'          | ''        | '1/8W'   | '0805LF'  | 'EMPTY'  | 'CS00004TA05'(!)        = ''              | ''                 | 'CS00004TA05'           |'R0805_H26'| '(SMR0805AW)'                  | '0'       | ''      | '1/8W'   | 'IO'       | 'RES CHIP 0 1/8W(0805)WTC'                         | 'CHIPR0805'    | ''          | ''            | '20221018'
 '330'        | '1%'      | '1/10W'  | '0603LF'  | 'CHIP'   | 'CS13303F906'(!)        = ''              | ''                 | 'CS13303F906'           |'R0603_H24'| '(SMR0603AW)'                  | '330'     | '1%'    | '1/10W'  | 'DISCRETE' | 'RES CHIP 330 1/10W +-1%(0603)WTC'                 | 'CHIPR0603'    | ''          | ''            | '20221018'
 '330'        | '1%'      | '1/10W'  | '0603LF'  | 'EMPTY'  | 'CS13303F906'(!)        = ''              | ''                 | 'CS13303F906'           |'R0603_H24'| '(SMR0603AW)'                  | '330'     | '1%'    | '1/10W'  | 'IO'       | 'RES CHIP 330 1/10W +-1%(0603)WTC'                 | 'CHIPR0603'    | ''          | ''            | '20221018'
 '10M'        | '5%'      | '1/16W'  | '0402LF'  | 'CHIP'   | 'CS61002JB17'(!)        = ''              | ''                 | 'CS61002JB17'           |'R0402'| '(R0402-0201)'                 | '10M'     | '5%'    | '1/16W'  | 'DISCRETE' | 'RES CHIP 10M 1/16W +-5% (0402)WTC'                | 'CHIPR0402'    | ''          | ''            | '20221019'
 '10M'        | '5%'      | '1/16W'  | '0402LF'  | 'EMPTY'  | 'CS61002JB17'(!)        = ''              | ''                 | 'CS61002JB17'           |'R0402'| '(R0402-0201)'                 | '10M'     | '5%'    | '1/16W'  | 'IO'       | 'RES CHIP 10M 1/16W +-5% (0402)WTC'                | 'CHIPR0402'    | ''          | ''            | '20221019'
 '49.9'       | '1%'      | '1/16W'  | '0402LF'  | 'CHIP'   | 'CS04992FB23'(!)        = ''              | ''                 | 'CS04992FB23'           |'R0402'| '(R0402-0201)'                 | '49.9'    | '1%'    | '1/16W'  | 'DISCRETE' | 'RES CHIP 49.9 1/16W +-1% (0402)WTC'               | 'CHIPR0402'    | ''          | ''            | '20221019'
 '49.9'       | '1%'      | '1/16W'  | '0402LF'  | 'EMPTY'  | 'CS04992FB23'(!)        = ''              | ''                 | 'CS04992FB23'           |'R0402'| '(R0402-0201)'                 | '49.9'    | '1%'    | '1/16W'  | 'IO'       | 'RES CHIP 49.9 1/16W +-1% (0402)WTC'               | 'CHIPR0402'    | ''          | ''            | '20221019'
 '1'          | '1%'      | '1/16W'  | '0402LF'  | 'CHIP'   | 'CS-1002FB26'(!)        = ''              | ''                 | 'CS-1002FB26'           |'R0402'| '(R0402-0201)'                 | '1'       | '1%'    | '1/16W'  | 'DISCRETE' | 'RES CHIP 1 1/16W +-1%(0402)WTC'                   | 'CHIPR0402'    | ''          | ''            | '20221019'
 '1'          | '1%'      | '1/16W'  | '0402LF'  | 'EMPTY'  | 'CS-1002FB26'(!)        = ''              | ''                 | 'CS-1002FB26'           |'R0402'| '(R0402-0201)'                 | '1'       | '1%'    | '1/16W'  | 'IO'       | 'RES CHIP 1 1/16W +-1%(0402)WTC'                   | 'CHIPR0402'    | ''          | ''            | '20221019'
 '4.53K'      | '1%'      | '1/16W'  | '0402LF'  | 'CHIP'   | 'CS24532FB06'(!)        = ''              | ''                 | 'CS24532FB06'           |'R0402'| '(R0402-0201)'                 | '4.53K'   | '1%'    | '1/16W'  | 'DISCRETE' | 'RES CHIP 4.53K 1/16W +-1%(0402)WTC'               | 'CHIPR0402'    | ''          | ''            | '20221019'
 '4.53K'      | '1%'      | '1/16W'  | '0402LF'  | 'EMPTY'  | 'CS24532FB06'(!)        = ''              | ''                 | 'CS24532FB06'           |'R0402'| '(R0402-0201)'                 | '4.53K'   | '1%'    | '1/16W'  | 'IO'       | 'RES CHIP 4.53K 1/16W +-1%(0402)WTC'               | 'CHIPR0402'    | ''          | ''            | '20221019'
 '10K'        | '1%'      | '1/16W'  | '0402LF'  | 'CHIP'   | 'CS31002FB20'(!)        = ''              | ''                 | 'CS31002FB20'           |'R0402'| '(R0402-0201)'                 | '10K'     | '1%'    | '1/16W'  | 'DISCRETE' | 'RES CHIP 10K 1/16W +-1%(0402)WTC'                 | 'CHIPR0402'    | ''          | ''            | '20221019'
 '10K'        | '1%'      | '1/16W'  | '0402LF'  | 'EMPTY'  | 'CS31002FB20'(!)        = ''              | ''                 | 'CS31002FB20'           |'R0402'| '(R0402-0201)'                 | '10K'     | '1%'    | '1/16W'  | 'IO'       | 'RES CHIP 10K 1/16W +-1%(0402)WTC'                 | 'CHIPR0402'    | ''          | ''            | '20221019'
 '24.9K'      | '1%'      | '1/16W'  | '0402LF'  | 'CHIP'   | 'CS32492FB13'(!)        = ''              | ''                 | 'CS32492FB13'           |'R0402'| '(R0402-0201)'                 | '24.9K'   | '1%'    | '1/16W'  | 'DISCRETE' | 'RES CHIP 24.9K 1/16W +-1%(0402)WTC'               | 'CHIPR0402'    | ''          | ''            | '20221019'
 '24.9K'      | '1%'      | '1/16W'  | '0402LF'  | 'EMPTY'  | 'CS32492FB13'(!)        = ''              | ''                 | 'CS32492FB13'           |'R0402'| '(R0402-0201)'                 | '24.9K'   | '1%'    | '1/16W'  | 'IO'       | 'RES CHIP 24.9K 1/16W +-1%(0402)WTC'               | 'CHIPR0402'    | ''          | ''            | '20221019'
 '40.2K'      | '1%'      | '1/16W'  | '0402LF'  | 'CHIP'   | 'CS34022FB14'(!)        = ''              | ''                 | 'CS34022FB14'           |'R0402'| '(R0402-0201)'                 | '40.2K'   | '1%'    | '1/16W'  | 'DISCRETE' | 'RES CHIP 40.2K 1/16W +-1%(0402)WTC'               | 'CHIPR0402'    | ''          | ''            | '20221019'
 '40.2K'      | '1%'      | '1/16W'  | '0402LF'  | 'EMPTY'  | 'CS34022FB14'(!)        = ''              | ''                 | 'CS34022FB14'           |'R0402'| '(R0402-0201)'                 | '40.2K'   | '1%'    | '1/16W'  | 'IO'       | 'RES CHIP 40.2K 1/16W +-1%(0402)WTC'               | 'CHIPR0402'    | ''          | ''            | '20221019'
 '1.13K'      | '1%'      | '1/16W'  | '0402LF'  | 'CHIP'   | 'CS21132FB03'(!)        = ''              | ''                 | 'CS21132FB03'           |'R0402'| '(R0402-0201)'                 | '1.13K'   | '1%'    | '1/16W'  | 'DISCRETE' | 'RES CHIP 1.13K 1/16W +-1% (0402)YGO'              | 'CHIPR0402'    | ''          | ''            | '20221019'
 '1.13K'      | '1%'      | '1/16W'  | '0402LF'  | 'EMPTY'  | 'CS21132FB03'(!)        = ''              | ''                 | 'CS21132FB03'           |'R0402'| '(R0402-0201)'                 | '1.13K'   | '1%'    | '1/16W'  | 'IO'       | 'RES CHIP 1.13K 1/16W +-1% (0402)YGO'              | 'CHIPR0402'    | ''          | ''            | '20221019'
 '1'          | '1%'      | '1/16W'  | '0402LF'  | 'CHIP'   | 'CS-1002FB06'(!)        = ''              | ''                 | 'CS-1002FB06'           |'R0402'| '(R0402-0201)'                 | '1'       | '1%'    | '1/16W'  | 'DISCRETE' | 'RES CHIP 1(+-1%,1/16W,0402)YGO'                   | 'CHIPR0402'    | ''          | ''            | '20221019'
 '1'          | '1%'      | '1/16W'  | '0402LF'  | 'EMPTY'  | 'CS-1002FB06'(!)        = ''              | ''                 | 'CS-1002FB06'           |'R0402'| '(R0402-0201)'                 | '1'       | '1%'    | '1/16W'  | 'IO'       | 'RES CHIP 1(+-1%,1/16W,0402)YGO'                   | 'CHIPR0402'    | ''          | ''            | '20221019'
 '4.53K'      | '1%'      | '1/16W'  | '0402LF'  | 'CHIP'   | 'CS24532FB07'(!)        = ''              | ''                 | 'CS24532FB07'           |'R0402'| '(R0402-0201)'                 | '4.53K'   | '1%'    | '1/16W'  | 'DISCRETE' | 'RES CHIP 4.53K 1/16W +-1%(0402)YGO'               | 'CHIPR0402'    | ''          | ''            | '20221019'
 '4.53K'      | '1%'      | '1/16W'  | '0402LF'  | 'EMPTY'  | 'CS24532FB07'(!)        = ''              | ''                 | 'CS24532FB07'           |'R0402'| '(R0402-0201)'                 | '4.53K'   | '1%'    | '1/16W'  | 'IO'       | 'RES CHIP 4.53K 1/16W +-1%(0402)YGO'               | 'CHIPR0402'    | ''          | ''            | '20221019'
 '11.8K'      | '1%'      | '1/16W'  | '0402LF'  | 'CHIP'   | 'CS31182FB10'(!)        = ''              | ''                 | 'CS31182FB10'           |'R0402'| '(R0402-0201)'                 | '11.8K'   | '1%'    | '1/16W'  | 'DISCRETE' | 'RES CHIP 11.8K 1/16W +-1% (0402)YGO'              | 'CHIPR0402'    | ''          | ''            | '20221019'
 '11.8K'      | '1%'      | '1/16W'  | '0402LF'  | 'EMPTY'  | 'CS31182FB10'(!)        = ''              | ''                 | 'CS31182FB10'           |'R0402'| '(R0402-0201)'                 | '11.8K'   | '1%'    | '1/16W'  | 'IO'       | 'RES CHIP 11.8K 1/16W +-1% (0402)YGO'              | 'CHIPR0402'    | ''          | ''            | '20221019'
 '24.9K'      | '1%'      | '1/16W'  | '0402LF'  | 'CHIP'   | 'CS32492FB12'(!)        = ''              | ''                 | 'CS32492FB12'           |'R0402'| '(R0402-0201)'                 | '24.9K'   | '1%'    | '1/16W'  | 'DISCRETE' | 'RES CHIP 24.9K 1/16W +-1%(0402)YGO'               | 'CHIPR0402'    | ''          | ''            | '20221019'
 '24.9K'      | '1%'      | '1/16W'  | '0402LF'  | 'EMPTY'  | 'CS32492FB12'(!)        = ''              | ''                 | 'CS32492FB12'           |'R0402'| '(R0402-0201)'                 | '24.9K'   | '1%'    | '1/16W'  | 'IO'       | 'RES CHIP 24.9K 1/16W +-1%(0402)YGO'               | 'CHIPR0402'    | ''          | ''            | '20221019'
 '40.2K'      | '1%'      | '1/16W'  | '0402LF'  | 'CHIP'   | 'CS34022FB13'(!)        = ''              | ''                 | 'CS34022FB13'           |'R0402'| '(R0402-0201)'                 | '40.2K'   | '1%'    | '1/16W'  | 'DISCRETE' | 'RES CHIP 40.2K 1/16W +-1% (0402)YGO'              | 'CHIPR0402'    | ''          | ''            | '20221019'
 '40.2K'      | '1%'      | '1/16W'  | '0402LF'  | 'EMPTY'  | 'CS34022FB13'(!)        = ''              | ''                 | 'CS34022FB13'           |'R0402'| '(R0402-0201)'                 | '40.2K'   | '1%'    | '1/16W'  | 'IO'       | 'RES CHIP 40.2K 1/16W +-1% (0402)YGO'              | 'CHIPR0402'    | ''          | ''            | '20221019'
 '80.6K'      | '1%'      | '1/16W'  | '0402LF'  | 'CHIP'   | 'CS38062FB13'(!)        = ''              | ''                 | 'CS38062FB13'           |'R0402'| '(R0402-0201)'                 | '80.6K'   | '1%'    | '1/16W'  | 'DISCRETE' | 'RES CHIP 80.6K 1/16W +-1% (0402)YGO'              | 'CHIPR0402'    | ''          | ''            | '20221019'
 '80.6K'      | '1%'      | '1/16W'  | '0402LF'  | 'EMPTY'  | 'CS38062FB13'(!)        = ''              | ''                 | 'CS38062FB13'           |'R0402'| '(R0402-0201)'                 | '80.6K'   | '1%'    | '1/16W'  | 'IO'       | 'RES CHIP 80.6K 1/16W +-1% (0402)YGO'              | 'CHIPR0402'    | ''          | ''            | '20221019'
 '15'         | '1%'      | '1/16W'  | '0402LF'  | 'CHIP'   | 'CS01502FB08'(!)        = ''              | ''                 | 'CS01502FB08'           |'R0402'| '(R0402-0201)'                 | '15'      | '1%'    | '1/16W'  | 'DISCRETE' | 'RES CHIP 15 1/16W +-1% (0402)YGO'                 | 'CHIPR0402'    | ''          | ''            | '20221019'
 '15'         | '1%'      | '1/16W'  | '0402LF'  | 'EMPTY'  | 'CS01502FB08'(!)        = ''              | ''                 | 'CS01502FB08'           |'R0402'| '(R0402-0201)'                 | '15'      | '1%'    | '1/16W'  | 'IO'       | 'RES CHIP 15 1/16W +-1% (0402)YGO'                 | 'CHIPR0402'    | ''          | ''            | '20221019'
 '10M'        | '5%'      | '1/16W'  | '0402LF'  | 'CHIP'   | 'CS61002JB16'(!)        = ''              | ''                 | 'CS61002JB16'           |'R0402'| '(R0402-0201)'                 | '10M'     | '5%'    | '1/16W'  | 'DISCRETE' | 'RES CHIP 10M 1/16W +-5% (0402)YGO'                | 'CHIPR0402'    | ''          | ''            | '20221019'
 '10M'        | '5%'      | '1/16W'  | '0402LF'  | 'EMPTY'  | 'CS61002JB16'(!)        = ''              | ''                 | 'CS61002JB16'           |'R0402'| '(R0402-0201)'                 | '10M'     | '5%'    | '1/16W'  | 'IO'       | 'RES CHIP 10M 1/16W +-5% (0402)YGO'                | 'CHIPR0402'    | ''          | ''            | '20221019'
 '49.9'       | '1%'      | '1/10W'  | '0603LF'  | 'CHIP'   | 'CS04993F918'(!)        = ''              | ''                 | 'CS04993F918'           |'R0603'| '(SMR0603AW)'                  | '49.9'    | '1%'    | '1/10W'  | 'DISCRETE' | 'RES CHIP 49.9 1/10W +-1%(0603)YGO'                | 'CHIPR0603'    | ''          | ''            | '20221019'
 '49.9'       | '1%'      | '1/10W'  | '0603LF'  | 'EMPTY'  | 'CS04993F918'(!)        = ''              | ''                 | 'CS04993F918'           |'R0603'| '(SMR0603AW)'                  | '49.9'    | '1%'    | '1/10W'  | 'IO'       | 'RES CHIP 49.9 1/10W +-1%(0603)YGO'                | 'CHIPR0603'    | ''          | ''            | '20221019'
 '330'        | '1%'      | '1/10W'  | '0603LF'  | 'CHIP'   | 'CS13303F903'(!)        = ''              | ''                 | 'CS13303F903'           |'R0603'| '(SMR0603AW)'                  | '330'     | '1%'    | '1/10W'  | 'DISCRETE' | 'RES CHIP 330 1/10W +-1%(0603)YGO'                 | 'CHIPR0603'    | ''          | ''            | '20221019'
 '330'        | '1%'      | '1/10W'  | '0603LF'  | 'EMPTY'  | 'CS13303F903'(!)        = ''              | ''                 | 'CS13303F903'           |'R0603'| '(SMR0603AW)'                  | '330'     | '1%'    | '1/10W'  | 'IO'       | 'RES CHIP 330 1/10W +-1%(0603)YGO'                 | 'CHIPR0603'    | ''          | ''            | '20221019'
 '5.6'        | '1%'      | '1/16W'  | '0402LF'  | 'CHIP'   | 'CS-5602FB01'(!)        = ''              | ''                 | 'CS-5602FB01'           |'R0402'| '(R0402-0201)'                 | '5.6'     | '1%'    | '1/16W'  | 'DISCRETE' | 'RES CHIP 5.6 1/16W 1%(0402)EF'                    | 'CHIPR0402'    | ''          | ''            | '20221018'
 '5.6'        | '1%'      | '1/16W'  | '0402LF'  | 'EMPTY'  | 'CS-5602FB01'(!)        = ''              | ''                 | 'CS-5602FB01'           |'R0402'| '(R0402-0201)'                 | '5.6'     | '1%'    | '1/16W'  | 'IO'       | 'RES CHIP 5.6 1/16W 1%(0402)EF'                    | 'CHIPR0402'    | ''          | ''            | '20221018'
 '10K'        | '5%'      | '1/16W'  | '0402LF'  | 'CHIP'   | 'CS31002JB26'(!)        = ''              | ''                 | 'CS31002JB26'           |'R0402'| '(R0402-0201)'                 | '10K'     | '5%'    | '1/16W'  | 'DISCRETE' | 'RES CHIP 10K 1/16W 5%(0402)WTC'                   | 'CHIPR0402'    | ''          | ''            | '20221021'
 '10K'        | '5%'      | '1/16W'  | '0402LF'  | 'EMPTY'  | 'CS31002JB26'(!)        = ''              | ''                 | 'CS31002JB26'           |'R0402'| '(R0402-0201)'                 | '10K'     | '5%'    | '1/16W'  | 'IO'       | 'RES CHIP 10K 1/16W 5%(0402)WTC'                   | 'CHIPR0402'    | ''          | ''            | '20221021'
 '11K'        | '1%'      | '1/16W'  | '0402LF'  | 'CHIP'   | 'CS31102FB16'(!)        = ''              | ''                 | 'CS31102FB16'           |'R0402'| '(R0402-0201)'                 | '11K'     | '1%'    | '1/16W'  | 'DISCRETE' | 'RES CHIP 11K 1/16W +-1% (0402)WTC'                | 'CHIPR0402'    | ''          | ''            | '20221021'
 '11K'        | '1%'      | '1/16W'  | '0402LF'  | 'EMPTY'  | 'CS31102FB16'(!)        = ''              | ''                 | 'CS31102FB16'           |'R0402'| '(R0402-0201)'                 | '11K'     | '1%'    | '1/16W'  | 'IO'       | 'RES CHIP 11K 1/16W +-1% (0402)WTC'                | 'CHIPR0402'    | ''          | ''            | '20221021'
 '562K'       | '1%'      | '1/16W'  | '0402LF'  | 'CHIP'   | 'CS45622FB13'(!)        = ''              | ''                 | 'CS45622FB13'           |'R0402'| '(R0402-0201)'                 | '562K'    | '1%'    | '1/16W'  | 'DISCRETE' | 'RES CHIP 562K 1/16W +-1%(0402)WTC'                | 'CHIPR0402'    | ''          | ''            | '20221021'
 '562K'       | '1%'      | '1/16W'  | '0402LF'  | 'EMPTY'  | 'CS45622FB13'(!)        = ''              | ''                 | 'CS45622FB13'           |'R0402'| '(R0402-0201)'                 | '562K'    | '1%'    | '1/16W'  | 'IO'       | 'RES CHIP 562K 1/16W +-1%(0402)WTC'                | 'CHIPR0402'    | ''          | ''            | '20221021'
 '1M'         | '5%'      | '1/16W'  | '0402LF'  | 'CHIP'   | 'CS51002JB10'(!)        = ''              | ''                 | 'CS51002JB10'           |'R0402'| '(R0402-0201)'                 | '1M'      | '5%'    | '1/16W'  | 'DISCRETE' | 'RES CHIP 1M 1/16W +-5% (0402)WTC'                 | 'CHIPR0402'    | ''          | ''            | '20221021'
 '1M'         | '5%'      | '1/16W'  | '0402LF'  | 'EMPTY'  | 'CS51002JB10'(!)        = ''              | ''                 | 'CS51002JB10'           |'R0402'| '(R0402-0201)'                 | '1M'      | '5%'    | '1/16W'  | 'IO'       | 'RES CHIP 1M 1/16W +-5% (0402)WTC'                 | 'CHIPR0402'    | ''          | ''            | '20221021'
 '100'        | '1%'      | '1/16W'  | '0402LF'  | 'CHIP'   | 'CS11002FB29'(!)        = ''              | ''                 | 'CS11002FB29'           |'R0402'| '(R0402-0201)'                 | '100'     | '1%'    | '1/16W'  | 'DISCRETE' | 'RES CHIP 100 1/16W +-1%(0402)WTC'                 | 'CHIPR0402'    | ''          | ''            | '20221021'
 '100'        | '1%'      | '1/16W'  | '0402LF'  | 'EMPTY'  | 'CS11002FB29'(!)        = ''              | ''                 | 'CS11002FB29'           |'R0402'| '(R0402-0201)'                 | '100'     | '1%'    | '1/16W'  | 'IO'       | 'RES CHIP 100 1/16W +-1%(0402)WTC'                 | 'CHIPR0402'    | ''          | ''            | '20221021'
 '220'        | '5%'      | '1/16W'  | '0402LF'  | 'CHIP'   | 'CS12202JB11'(!)        = ''              | ''                 | 'CS12202JB11'           |'R0402'| '(R0402-0201)'                 | '220'     | '5%'    | '1/16W'  | 'DISCRETE' | 'RES CHIP 220 1/16W +-5%(0402)WTC'                 | 'CHIPR0402'    | ''          | ''            | '20221021'
 '220'        | '5%'      | '1/16W'  | '0402LF'  | 'EMPTY'  | 'CS12202JB11'(!)        = ''              | ''                 | 'CS12202JB11'           |'R0402'| '(R0402-0201)'                 | '220'     | '5%'    | '1/16W'  | 'IO'       | 'RES CHIP 220 1/16W +-5%(0402)WTC'                 | 'CHIPR0402'    | ''          | ''            | '20221021'
 '2.7K'       | '5%'      | '1/16W'  | '0402LF'  | 'CHIP'   | 'CS22702JB09'(!)        = ''              | ''                 | 'CS22702JB09'           |'R0402'| '(R0402-0201)'                 | '2.7K'    | '5%'    | '1/16W'  | 'DISCRETE' | 'RES CHIP 2.7K 1/16W +-5%(0402)WTC'                | 'CHIPR0402'    | ''          | ''            | '20221021'
 '2.7K'       | '5%'      | '1/16W'  | '0402LF'  | 'EMPTY'  | 'CS22702JB09'(!)        = ''              | ''                 | 'CS22702JB09'           |'R0402'| '(R0402-0201)'                 | '2.7K'    | '5%'    | '1/16W'  | 'IO'       | 'RES CHIP 2.7K 1/16W +-5%(0402)WTC'                | 'CHIPR0402'    | ''          | ''            | '20221021'
 '100'        | '5%'      | '1/16W'  | '0402LF'  | 'CHIP'   | 'CS11002JB19'(!)        = ''              | ''                 | 'CS11002JB19'           |'R0402'| '(R0402-0201)'                 | '100'     | '5%'    | '1/16W'  | 'DISCRETE' | 'RES CHIP 100 1/16W +-5%(0402)EF YGO'              | 'CHIPR0402'    | ''          | ''            | '20221024'
 '100'        | '5%'      | '1/16W'  | '0402LF'  | 'EMPTY'  | 'CS11002JB19'(!)        = ''              | ''                 | 'CS11002JB19'           |'R0402'| '(R0402-0201)'                 | '100'     | '5%'    | '1/16W'  | 'IO'       | 'RES CHIP 100 1/16W +-5%(0402)EF YGO'              | 'CHIPR0402'    | ''          | ''            | '20221024'
 '100'        | '5%'      | '1/16W'  | '0402LF'  | 'CHIP'   | 'CS11002JB18'(!)        = ''              | ''                 | 'CS11002JB18'           |'R0402'| '(R0402-0201)'                 | '100'     | '5%'    | '1/16W'  | 'DISCRETE' | 'RES CHIP 100 1/16W +-5%(0402)EF WTC'              | 'CHIPR0402'    | ''          | ''            | '20221024'
 '100'        | '5%'      | '1/16W'  | '0402LF'  | 'EMPTY'  | 'CS11002JB18'(!)        = ''              | ''                 | 'CS11002JB18'           |'R0402'| '(R0402-0201)'                 | '100'     | '5%'    | '1/16W'  | 'IO'       | 'RES CHIP 100 1/16W +-5%(0402)EF WTC'              | 'CHIPR0402'    | ''          | ''            | '20221024'
 '22'         | '1%'      | '1/16W'  | '0402LF'  | 'CHIP'   | 'CS02202FB10'(!)        = ''              | ''                 | 'CS02202FB10'           |'R0402'| '(R0402-0201)'                 | '22'      | '1%'    | '1/16W'  | 'DISCRETE' | 'RES CHIP 22 1/16W +-1%(0402)WTC'                  | 'CHIPR0402'    | ''          | ''            | '20221024'
 '22'         | '1%'      | '1/16W'  | '0402LF'  | 'EMPTY'  | 'CS02202FB10'(!)        = ''              | ''                 | 'CS02202FB10'           |'R0402'| '(R0402-0201)'                 | '22'      | '1%'    | '1/16W'  | 'IO'       | 'RES CHIP 22 1/16W +-1%(0402)WTC'                  | 'CHIPR0402'    | ''          | ''            | '20221024'
 '22'         | '1%'      | '1/16W'  | '0402LF'  | 'CHIP'   | 'CS02202FB11'(!)        = ''              | ''                 | 'CS02202FB11'           |'R0402'| '(R0402-0201)'                 | '22'      | '1%'    | '1/16W'  | 'DISCRETE' | 'RES CHIP 22 1/16W +-1%(0402)YGO'                  | 'CHIPR0402'    | ''          | ''            | '20221024'
 '22'         | '1%'      | '1/16W'  | '0402LF'  | 'EMPTY'  | 'CS02202FB11'(!)        = ''              | ''                 | 'CS02202FB11'           |'R0402'| '(R0402-0201)'                 | '22'      | '1%'    | '1/16W'  | 'IO'       | 'RES CHIP 22 1/16W +-1%(0402)YGO'                  | 'CHIPR0402'    | ''          | ''            | '20221024'
 '69.8K'      | '1%'      | '1/16W'  | '0402LF'  | 'CHIP'   | 'CS36982FB10'(!)        = ''              | ''                 | 'CS36982FB10'           |'R0402'| '(R0402-0201)'                 | '69.8K'   | '1%'    | '1/16W'  | 'DISCRETE' | 'RES CHIP 69.8K 1/16W +-1% (0402)YGO'              | 'CHIPR0402'    | ''          | ''            | '20221024'
 '69.8K'      | '1%'      | '1/16W'  | '0402LF'  | 'EMPTY'  | 'CS36982FB10'(!)        = ''              | ''                 | 'CS36982FB10'           |'R0402'| '(R0402-0201)'                 | '69.8K'   | '1%'    | '1/16W'  | 'IO'       | 'RES CHIP 69.8K 1/16W +-1% (0402)YGO'              | 'CHIPR0402'    | ''          | ''            | '20221024'
 '47.5K'      | '1%'      | '1/16W'  | '0402LF'  | 'CHIP'   | 'CS34752FB11'(!)        = ''              | ''                 | 'CS34752FB11'           |'R0402'| '(R0402-0201)'                 | '47.5K'   | '1%'    | '1/16W'  | 'DISCRETE' | 'RES CHIP 47.5K 1/16W +-1% (0402)WTC'              | 'CHIPR0402'    | ''          | ''            | '20221025'
 '47.5K'      | '1%'      | '1/16W'  | '0402LF'  | 'EMPTY'  | 'CS34752FB11'(!)        = ''              | ''                 | 'CS34752FB11'           |'R0402'| '(R0402-0201)'                 | '47.5K'   | '1%'    | '1/16W'  | 'IO'       | 'RES CHIP 47.5K 1/16W +-1% (0402)WTC'              | 'CHIPR0402'    | ''          | ''            | '20221025'
 '10.5K'      | '1%'      | '1/16W'  | '0402LF'  | 'CHIP'   | 'CS31052FB07'(!)        = ''              | ''                 | 'CS31052FB07'           |'R0402'| '(R0402-0201)'                 | '10.5K'   | '1%'    | '1/16W'  | 'DISCRETE' | 'RES CHIP 10.5K 1/16W +-1%( 0402)YGO'              | 'CHIPR0402'    | ''          | ''            | '20221025'
 '10.5K'      | '1%'      | '1/16W'  | '0402LF'  | 'EMPTY'  | 'CS31052FB07'(!)        = ''              | ''                 | 'CS31052FB07'           |'R0402'| '(R0402-0201)'                 | '10.5K'   | '1%'    | '1/16W'  | 'IO'       | 'RES CHIP 10.5K 1/16W +-1%( 0402)YGO'              | 'CHIPR0402'    | ''          | ''            | '20221025'
 '1'          | '5%'      | '1/16W'  | '0402LF'  | 'CHIP'   | 'CS-1002JB16'(!)        = ''              | ''                 | 'CS-1002JB16'           |'R0402'| '(R0402-0201)'                 | '1'       | '5%'    | '1/16W'  | 'DISCRETE' | 'RES CHIP 1 1/16W +-5%(0402)WTC'                   | 'CHIPR0402'    | ''          | ''            | '20221025'
 '1'          | '5%'      | '1/16W'  | '0402LF'  | 'EMPTY'  | 'CS-1002JB16'(!)        = ''              | ''                 | 'CS-1002JB16'           |'R0402'| '(R0402-0201)'                 | '1'       | '5%'    | '1/16W'  | 'IO'       | 'RES CHIP 1 1/16W +-5%(0402)WTC'                   | 'CHIPR0402'    | ''          | ''            | '20221025'
 '1K'         | '5%'      | '1/16W'  | '0402LF'  | 'CHIP'   | 'CS21002JB27'(!)        = ''              | ''                 | 'CS21002JB27'           |'R0402'| '(R0402-0201)'                 | '1K'      | '5%'    | '1/16W'  | 'DISCRETE' | 'RES CHIP 1K 1/16W 5%(0402) YGO'                   | 'CHIPR0402'    | ''          | ''            | '20221017'
 '1K'         | '5%'      | '1/16W'  | '0402LF'  | 'EMPTY'  | 'CS21002JB27'(!)        = ''              | ''                 | 'CS21002JB27'           |'R0402'| '(R0402-0201)'                 | '1K'      | '5%'    | '1/16W'  | 'IO'       | 'RES CHIP 1K 1/16W 5%(0402) YGO'                   | 'CHIPR0402'    | ''          | ''            | '20221017'
 '4.7K'       | '5%'      | '1/16W'  | '0402LF'  | 'CHIP'   | 'CS24702JB19'(!)        = ''              | ''                 | 'CS24702JB19'           |'R0402'| '(R0402-0201)'                 | '4.7K'    | '5%'    | '1/16W'  | 'DISCRETE' | 'RES CHIP 4.7K 1/16W +-5% (0402)YGO'               | 'CHIPR0402'    | ''          | ''            | '20221103'
 '4.7K'       | '5%'      | '1/16W'  | '0402LF'  | 'EMPTY'  | 'CS24702JB19'(!)        = ''              | ''                 | 'CS24702JB19'           |'R0402'| '(R0402-0201)'                 | '4.7K'    | '5%'    | '1/16W'  | 'IO'       | 'RES CHIP 4.7K 1/16W +-5% (0402)YGO'               | 'CHIPR0402'    | ''          | ''            | '20221103'
 '1K'         | '1%'      | '1/16W'  | '0402LF'  | 'CHIP'   | 'CS21002FB28'(!)        = ''              | ''                 | 'CS21002FB28'           |'R0402'| '(R0402-0201)'                 | '1K'      | '1%'    | '1/16W'  | 'DISCRETE' | 'RES CHIP 1K 1/16W +-1% (0402)YGO'                 | 'CHIPR0402'    | ''          | ''            | '20221103'
 '1K'         | '1%'      | '1/16W'  | '0402LF'  | 'EMPTY'  | 'CS21002FB28'(!)        = ''              | ''                 | 'CS21002FB28'           |'R0402'| '(R0402-0201)'                 | '1K'      | '1%'    | '1/16W'  | 'IO'       | 'RES CHIP 1K 1/16W +-1% (0402)YGO'                 | 'CHIPR0402'    | ''          | ''            | '20221103'
 '10K'        | '1%'      | '1/16W'  | '0402LF'  | 'CHIP'   | 'CS31002FB28'(!)        = ''              | ''                 | 'CS31002FB28'           |'R0402'| '(R0402-0201)'                 | '10K'     | '1%'    | '1/16W'  | 'DISCRETE' | 'RES CHIP 10K 1/16W +-1% (0402)YGO'                | 'CHIPR0402'    | ''          | ''            | '20221103'
 '10K'        | '1%'      | '1/16W'  | '0402LF'  | 'EMPTY'  | 'CS31002FB28'(!)        = ''              | ''                 | 'CS31002FB28'           |'R0402'| '(R0402-0201)'                 | '10K'     | '1%'    | '1/16W'  | 'IO'       | 'RES CHIP 10K 1/16W +-1% (0402)YGO'                | 'CHIPR0402'    | ''          | ''            | '20221103'
 '15.4K'      | '1%'      | '1/16W'  | '0402LF'  | 'CHIP'   | 'CS31542FB10'(!)        = ''              | ''                 | 'CS31542FB10'           |'R0402'| '(R0402-0201)'                 | '15.4K'   | '1%'    | '1/16W'  | 'DISCRETE' | 'RES CHIP 15.4K 1/16W +-1%(0402)WTC'               | 'CHIPR0402'    | ''          | ''            | '20221114'
 '15.4K'      | '1%'      | '1/16W'  | '0402LF'  | 'EMPTY'  | 'CS31542FB10'(!)        = ''              | ''                 | 'CS31542FB10'           |'R0402'| '(R0402-0201)'                 | '15.4K'   | '1%'    | '1/16W'  | 'IO'       | 'RES CHIP 15.4K 1/16W +-1%(0402)WTC'               | 'CHIPR0402'    | ''          | ''            | '20221114'
 '20M'        | '5%'      | '1/16W'  | '0402LF'  | 'CHIP'   | 'CS62002JB03'(!)        = ''              | ''                 | 'CS62002JB03'           |'R0402'| '(R0402-0201)'                 | '20M'     | '5%'    | '1/16W'  | 'DISCRETE' | 'RES CHIP 20M 1/16W +-5%(0402)WTC'                 | 'CHIPR0402'    | ''          | ''            | '20221114'
 '20M'        | '5%'      | '1/16W'  | '0402LF'  | 'EMPTY'  | 'CS62002JB03'(!)        = ''              | ''                 | 'CS62002JB03'           |'R0402'| '(R0402-0201)'                 | '20M'     | '5%'    | '1/16W'  | 'IO'       | 'RES CHIP 20M 1/16W +-5%(0402)WTC'                 | 'CHIPR0402'    | ''          | ''            | '20221114'
 '2K'         | '5%'      | '1/16W'  | '0402LF'  | 'CHIP'   | 'CS22002JB09'(!)        = ''              | ''                 | 'CS22002JB09'           |'R0402'| '(R0402-0201)'                 | '2K'      | '5%'    | '1/16W'  | 'DISCRETE' | 'RES CHIP 2K 1/16W +-5% 0402)WTC'                  | 'CHIPR0402'    | ''          | ''            | '20221114'
 '2K'         | '5%'      | '1/16W'  | '0402LF'  | 'EMPTY'  | 'CS22002JB09'(!)        = ''              | ''                 | 'CS22002JB09'           |'R0402'| '(R0402-0201)'                 | '2K'      | '5%'    | '1/16W'  | 'IO'       | 'RES CHIP 2K 1/16W +-5% 0402)WTC'                  | 'CHIPR0402'    | ''          | ''            | '20221114'
 '8.2K'       | '5%'      | '1/16W'  | '0402LF'  | 'CHIP'   | 'CS28202JB10'(!)        = ''              | ''                 | 'CS28202JB10'           |'R0402'| '(R0402-0201)'                 | '8.2K'    | '5%'    | '1/16W'  | 'DISCRETE' | 'RES CHIP 8.2K 1/16W +-5% (0402)WTC'               | 'CHIPR0402'    | ''          | ''            | '20221114'
 '8.2K'       | '5%'      | '1/16W'  | '0402LF'  | 'EMPTY'  | 'CS28202JB10'(!)        = ''              | ''                 | 'CS28202JB10'           |'R0402'| '(R0402-0201)'                 | '8.2K'    | '5%'    | '1/16W'  | 'IO'       | 'RES CHIP 8.2K 1/16W +-5% (0402)WTC'               | 'CHIPR0402'    | ''          | ''            | '20221114'
 '12.1K'      | '1%'      | '1/16W'  | '0402LF'  | 'CHIP'   | 'CS31212FB12'(!)        = ''              | ''                 | 'CS31212FB12'           |'R0402'| '(R0402-0201)'                 | '12.1K'   | '1%'    | '1/16W'  | 'DISCRETE' | 'RES CHIP 12.1K 1/16W +-1%(0402)WTC'               | 'CHIPR0402'    | ''          | ''            | '20221114'
 '12.1K'      | '1%'      | '1/16W'  | '0402LF'  | 'EMPTY'  | 'CS31212FB12'(!)        = ''              | ''                 | 'CS31212FB12'           |'R0402'| '(R0402-0201)'                 | '12.1K'   | '1%'    | '1/16W'  | 'IO'       | 'RES CHIP 12.1K 1/16W +-1%(0402)WTC'               | 'CHIPR0402'    | ''          | ''            | '20221114'
 '20K'        | '1%'      | '1/16W'  | '0402LF'  | 'CHIP'   | 'CS32002FB25'(!)        = ''              | ''                 | 'CS32002FB25'           |'R0402'| '(R0402-0201)'                 | '20K'     | '1%'    | '1/16W'  | 'DISCRETE' | 'RES CHIP 20K 1/16W +-1%(0402)WTC'                 | 'CHIPR0402'    | ''          | ''            | '20221114'
 '20K'        | '1%'      | '1/16W'  | '0402LF'  | 'EMPTY'  | 'CS32002FB25'(!)        = ''              | ''                 | 'CS32002FB25'           |'R0402'| '(R0402-0201)'                 | '20K'     | '1%'    | '1/16W'  | 'IO'       | 'RES CHIP 20K 1/16W +-1%(0402)WTC'                 | 'CHIPR0402'    | ''          | ''            | '20221114'
 '25.5K'      | '1%'      | '1/16W'  | '0402LF'  | 'CHIP'   | 'CS32552FB13'(!)        = ''              | ''                 | 'CS32552FB13'           |'R0402'| '(R0402-0201)'                 | '25.5K'   | '1%'    | '1/16W'  | 'DISCRETE' | 'RES CHIP 25.5K 1/16W +-1%(0402)WTC'               | 'CHIPR0402'    | ''          | ''            | '20221114'
 '25.5K'      | '1%'      | '1/16W'  | '0402LF'  | 'EMPTY'  | 'CS32552FB13'(!)        = ''              | ''                 | 'CS32552FB13'           |'R0402'| '(R0402-0201)'                 | '25.5K'   | '1%'    | '1/16W'  | 'IO'       | 'RES CHIP 25.5K 1/16W +-1%(0402)WTC'               | 'CHIPR0402'    | ''          | ''            | '20221114'
 '86.6K'      | '1%'      | '1/16W'  | '0402LF'  | 'CHIP'   | 'CS38662FB07'(!)        = ''              | ''                 | 'CS38662FB07'           |'R0402'| '(R0402-0201)'                 | '86.6K'   | '1%'    | '1/16W'  | 'DISCRETE' | 'RES CHIP 86.6K 1/16W +-1% (0402)WTC'              | 'CHIPR0402'    | ''          | ''            | '20221114'
 '86.6K'      | '1%'      | '1/16W'  | '0402LF'  | 'EMPTY'  | 'CS38662FB07'(!)        = ''              | ''                 | 'CS38662FB07'           |'R0402'| '(R0402-0201)'                 | '86.6K'   | '1%'    | '1/16W'  | 'IO'       | 'RES CHIP 86.6K 1/16W +-1% (0402)WTC'              | 'CHIPR0402'    | ''          | ''            | '20221114'
 '1'          | '1%'      | '1/10W'  | '0603LF'  | 'CHIP'   | 'CS-1003F907'(!)        = ''              | ''                 | 'CS-1003F907'           |'R0603_H24'| '(SMR0603AW)'                  | '1'       | '1%'    | '1/10W'  | 'DISCRETE' | 'RES CHIP 1 1/10W +-1%(0603)WTC'                   | 'CHIPR0603'    | ''          | ''            | '20221114'
 '1'          | '1%'      | '1/10W'  | '0603LF'  | 'EMPTY'  | 'CS-1003F907'(!)        = ''              | ''                 | 'CS-1003F907'           |'R0603_H24'| '(SMR0603AW)'                  | '1'       | '1%'    | '1/10W'  | 'IO'       | 'RES CHIP 1 1/10W +-1%(0603)WTC'                   | 'CHIPR0603'    | ''          | ''            | '20221114'
 '2.2K'       | '5%'      | '1/16W'  | '0402LF'  | 'CHIP'   | 'CS22202JB26'(!)        = ''              | ''                 | 'CS22202JB26'           |'R0402'| '(R0402-0201)'                 | '2.2K'    | '5%'    | '1/16W'  | 'DISCRETE' | 'RES CHIP 2.2K 1/16W +-5%(0402)WTC'                | 'CHIPR0402'    | ''          | ''            | '20221115'
 '2.2K'       | '5%'      | '1/16W'  | '0402LF'  | 'EMPTY'  | 'CS22202JB26'(!)        = ''              | ''                 | 'CS22202JB26'           |'R0402'| '(R0402-0201)'                 | '2.2K'    | '5%'    | '1/16W'  | 'IO'       | 'RES CHIP 2.2K 1/16W +-5%(0402)WTC'                | 'CHIPR0402'    | ''          | ''            | '20221115'
 '12.7K'      | '1%'      | '1/16W'  | '0402LF'  | 'CHIP'   | 'CS31272FB11'(!)        = ''              | ''                 | 'CS31272FB11'           |'R0402'| '(R0402-0201)'                 | '12.7K'   | '1%'    | '1/16W'  | 'DISCRETE' | 'RES CHIP 12.7K 1/16W +-1% (0402)WTC'              | 'CHIPR0402'    | ''          | ''            | '20221125'
 '12.7K'      | '1%'      | '1/16W'  | '0402LF'  | 'EMPTY'  | 'CS31272FB11'(!)        = ''              | ''                 | 'CS31272FB11'           |'R0402'| '(R0402-0201)'                 | '12.7K'   | '1%'    | '1/16W'  | 'IO'       | 'RES CHIP 12.7K 1/16W +-1% (0402)WTC'              | 'CHIPR0402'    | ''          | ''            | '20221125'
 '82K'        | '1%'      | '1/16W'  | '0402LF'  | 'CHIP'   | 'CS38202FB05'(!)        = ''              | ''                 | 'CS38202FB05'           |'R0402'| '(R0402-0201)'                 | '82K'     | '1%'    | '1/16W'  | 'DISCRETE' | 'RES CHIP 82K  1/16W +-1% (0402)WTC'               | 'CHIPR0402'    | ''          | ''            | '20221125'
 '82K'        | '1%'      | '1/16W'  | '0402LF'  | 'EMPTY'  | 'CS38202FB05'(!)        = ''              | ''                 | 'CS38202FB05'           |'R0402'| '(R0402-0201)'                 | '82K'     | '1%'    | '1/16W'  | 'IO'       | 'RES CHIP 82K  1/16W +-1% (0402)WTC'               | 'CHIPR0402'    | ''          | ''            | '20221125'
 '3.3K'       | '5%'      | '1/16W'  | '0402LF'  | 'CHIP'   | 'CS23302JB11'(!)        = ''              | ''                 | 'CS23302JB11'           |'R0402'| '(R0402-0201)'                 | '3.3K'    | '5%'    | '1/16W'  | 'DISCRETE' | 'RES CHIP 3.3K 1/16W +-5%(0402)WTC'                | 'CHIPR0402'    | ''          | ''            | '20221125'
 '3.3K'       | '5%'      | '1/16W'  | '0402LF'  | 'EMPTY'  | 'CS23302JB11'(!)        = ''              | ''                 | 'CS23302JB11'           |'R0402'| '(R0402-0201)'                 | '3.3K'    | '5%'    | '1/16W'  | 'IO'       | 'RES CHIP 3.3K 1/16W +-5%(0402)WTC'                | 'CHIPR0402'    | ''          | ''            | '20221125'
 '3.9K'       | '1%'      | '1/16W'  | '0402LF'  | 'CHIP'   | 'CS23902FB09'(!)        = ''              | ''                 | 'CS23902FB09'           |'R0402'| '(R0402-0201)'                 | '3.9K'    | '1%'    | '1/16W'  | 'DISCRETE' | 'RES CHIP 3.9K 1/16W+-1%(0402)WTC'                 | 'CHIPR0402'    | ''          | ''            | '20221125'
 '3.9K'       | '1%'      | '1/16W'  | '0402LF'  | 'EMPTY'  | 'CS23902FB09'(!)        = ''              | ''                 | 'CS23902FB09'           |'R0402'| '(R0402-0201)'                 | '3.9K'    | '1%'    | '1/16W'  | 'IO'       | 'RES CHIP 3.9K 1/16W+-1%(0402)WTC'                 | 'CHIPR0402'    | ''          | ''            | '20221125'
 '8.06K'      | '1%'      | '1/16W'  | '0402LF'  | 'CHIP'   | 'CS28062FB13'(!)        = ''              | ''                 | 'CS28062FB13'           |'R0402'| '(R0402-0201)'                 | '8.06K'   | '1%'    | '1/16W'  | 'DISCRETE' | 'RES CHIP 8.06K 1/16W +-1%(0402)WTC'               | 'CHIPR0402'    | ''          | ''            | '20221125'
 '8.06K'      | '1%'      | '1/16W'  | '0402LF'  | 'EMPTY'  | 'CS28062FB13'(!)        = ''              | ''                 | 'CS28062FB13'           |'R0402'| '(R0402-0201)'                 | '8.06K'   | '1%'    | '1/16W'  | 'IO'       | 'RES CHIP 8.06K 1/16W +-1%(0402)WTC'               | 'CHIPR0402'    | ''          | ''            | '20221125'
 '8.25K'      | '1%'      | '1/16W'  | '0402LF'  | 'CHIP'   | 'CS28252FB13'(!)        = ''              | ''                 | 'CS28252FB13'           |'R0402'| '(R0402-0201)'                 | '8.25K'   | '1%'    | '1/16W'  | 'DISCRETE' | 'RES CHIP 8.25K 1/16W+-1%(0402)WTC'                | 'CHIPR0402'    | ''          | ''            | '20221125'
 '8.25K'      | '1%'      | '1/16W'  | '0402LF'  | 'EMPTY'  | 'CS28252FB13'(!)        = ''              | ''                 | 'CS28252FB13'           |'R0402'| '(R0402-0201)'                 | '8.25K'   | '1%'    | '1/16W'  | 'IO'       | 'RES CHIP 8.25K 1/16W+-1%(0402)WTC'                | 'CHIPR0402'    | ''          | ''            | '20221125'
 '9.09K'      | '1%'      | '1/16W'  | '0402LF'  | 'CHIP'   | 'CS29092FB11'(!)        = ''              | ''                 | 'CS29092FB11'           |'R0402'| '(R0402-0201)'                 | '9.09K'   | '1%'    | '1/16W'  | 'DISCRETE' | 'RES CHIP 9.09K 1/16W +-1%(0402)WTC'               | 'CHIPR0402'    | ''          | ''            | '20221125'
 '9.09K'      | '1%'      | '1/16W'  | '0402LF'  | 'EMPTY'  | 'CS29092FB11'(!)        = ''              | ''                 | 'CS29092FB11'           |'R0402'| '(R0402-0201)'                 | '9.09K'   | '1%'    | '1/16W'  | 'IO'       | 'RES CHIP 9.09K 1/16W +-1%(0402)WTC'               | 'CHIPR0402'    | ''          | ''            | '20221125'
 '9.31K'      | '1%'      | '1/16W'  | '0402LF'  | 'CHIP'   | 'CS29312FB09'(!)        = ''              | ''                 | 'CS29312FB09'           |'R0402'| '(R0402-0201)'                 | '9.31K'   | '1%'    | '1/16W'  | 'DISCRETE' | 'RES CHIP 9.31K 1/16W +-1%(0402)WTC'               | 'CHIPR0402'    | ''          | ''            | '20221125'
 '9.31K'      | '1%'      | '1/16W'  | '0402LF'  | 'EMPTY'  | 'CS29312FB09'(!)        = ''              | ''                 | 'CS29312FB09'           |'R0402'| '(R0402-0201)'                 | '9.31K'   | '1%'    | '1/16W'  | 'IO'       | 'RES CHIP 9.31K 1/16W +-1%(0402)WTC'               | 'CHIPR0402'    | ''          | ''            | '20221125'
 '11.5K'      | '1%'      | '1/16W'  | '0402LF'  | 'CHIP'   | 'CS31152FB12'(!)        = ''              | ''                 | 'CS31152FB12'           |'R0402'| '(R0402-0201)'                 | '11.5K'   | '1%'    | '1/16W'  | 'DISCRETE' | 'RES CHIP 11.5K 1/16W +-1%( 0402)WTC'              | 'CHIPR0402'    | ''          | ''            | '20221125'
 '11.5K'      | '1%'      | '1/16W'  | '0402LF'  | 'EMPTY'  | 'CS31152FB12'(!)        = ''              | ''                 | 'CS31152FB12'           |'R0402'| '(R0402-0201)'                 | '11.5K'   | '1%'    | '1/16W'  | 'IO'       | 'RES CHIP 11.5K 1/16W +-1%( 0402)WTC'              | 'CHIPR0402'    | ''          | ''            | '20221125'
 '56K'        | '1%'      | '1/16W'  | '0402LF'  | 'CHIP'   | 'CS35602FB07'(!)        = ''              | ''                 | 'CS35602FB07'           |'R0402'| '(R0402-0201)'                 | '56K'     | '1%'    | '1/16W'  | 'DISCRETE' | 'RES CHIP 56K 1/16W +-1%(0402)WTC'                 | 'CHIPR0402'    | ''          | ''            | '20221125'
 '56K'        | '1%'      | '1/16W'  | '0402LF'  | 'EMPTY'  | 'CS35602FB07'(!)        = ''              | ''                 | 'CS35602FB07'           |'R0402'| '(R0402-0201)'                 | '56K'     | '1%'    | '1/16W'  | 'IO'       | 'RES CHIP 56K 1/16W +-1%(0402)WTC'                 | 'CHIPR0402'    | ''          | ''            | '20221125'
 '68.1K'      | '1%'      | '1/16W'  | '0402LF'  | 'CHIP'   | 'CS36812FB09'(!)        = ''              | ''                 | 'CS36812FB09'           |'R0402'| '(R0402-0201)'                 | '68.1K'   | '1%'    | '1/16W'  | 'DISCRETE' | 'RES CHIP 68.1K 1/16W +-1%(0402)WTC'               | 'CHIPR0402'    | ''          | ''            | '20221125'
 '68.1K'      | '1%'      | '1/16W'  | '0402LF'  | 'EMPTY'  | 'CS36812FB09'(!)        = ''              | ''                 | 'CS36812FB09'           |'R0402'| '(R0402-0201)'                 | '68.1K'   | '1%'    | '1/16W'  | 'IO'       | 'RES CHIP 68.1K 1/16W +-1%(0402)WTC'               | 'CHIPR0402'    | ''          | ''            | '20221125'
 '4.99K'      | '1%'      | '1/16W'  | '0402LF'  | 'CHIP'   | 'CS24992FB17'(!)        = ''              | ''                 | 'CS24992FB17'           |'R0402'| '(R0402-0201)'                 | '4.99K'   | '1%'    | '1/16W'  | 'DISCRETE' | 'RES CHIP 4.99K 1/16W +-1% (0402)WTC'              | 'CHIPR0402'    | ''          | ''            | '20221125'
 '4.99K'      | '1%'      | '1/16W'  | '0402LF'  | 'EMPTY'  | 'CS24992FB17'(!)        = ''              | ''                 | 'CS24992FB17'           |'R0402'| '(R0402-0201)'                 | '4.99K'   | '1%'    | '1/16W'  | 'IO'       | 'RES CHIP 4.99K 1/16W +-1% (0402)WTC'              | 'CHIPR0402'    | ''          | ''            | '20221125'
 '402'        | '1%'      | '1/16W'  | '0402LF'  | 'CHIP'   | 'CS14022FB14'(!)        = ''              | ''                 | 'CS14022FB14'           |'R0402'| '(R0402-0201)'                 | '402'     | '1%'    | '1/16W'  | 'DISCRETE' | 'RES CHIP 402 1/16W +-1%( 0402)WTC'                | 'CHIPR0402'    | ''          | ''            | '20221129'
 '402'        | '1%'      | '1/16W'  | '0402LF'  | 'EMPTY'  | 'CS14022FB14'(!)        = ''              | ''                 | 'CS14022FB14'           |'R0402'| '(R0402-0201)'                 | '402'     | '1%'    | '1/16W'  | 'IO'       | 'RES CHIP 402 1/16W +-1%( 0402)WTC'                | 'CHIPR0402'    | ''          | ''            | '20221129'
 '150K'       | '1%'      | '1/16W'  | '0402LF'  | 'CHIP'   | 'CS41502FB16'(!)        = ''              | ''                 | 'CS41502FB16'           |'R0402'| '(R0402-0201)'                 | '150K'    | '1%'    | '1/16W'  | 'DISCRETE' | 'RES CHIP 150K 1/16W +-1%(0402)WTC'                | 'CHIPR0402'    | ''          | ''            | '20221129'
 '150K'       | '1%'      | '1/16W'  | '0402LF'  | 'EMPTY'  | 'CS41502FB16'(!)        = ''              | ''                 | 'CS41502FB16'           |'R0402'| '(R0402-0201)'                 | '150K'    | '1%'    | '1/16W'  | 'IO'       | 'RES CHIP 150K 1/16W +-1%(0402)WTC'                | 'CHIPR0402'    | ''          | ''            | '20221129'
 '442'        | '1%'      | '1/16W'  | '0402LF'  | 'CHIP'   | 'CS14422FB03'(!)        = ''              | ''                 | 'CS14422FB03'           |'R0402'| '(R0402-0201)'                 | '442'     | '1%'    | '1/16W'  | 'DISCRETE' | 'RES CHIP 442 1/16W +-1% (0402)YGO'                | 'CHIPR0402'    | ''          | ''            | '20221129'
 '442'        | '1%'      | '1/16W'  | '0402LF'  | 'EMPTY'  | 'CS14422FB03'(!)        = ''              | ''                 | 'CS14422FB03'           |'R0402'| '(R0402-0201)'                 | '442'     | '1%'    | '1/16W'  | 'IO'       | 'RES CHIP 442 1/16W +-1% (0402)YGO'                | 'CHIPR0402'    | ''          | ''            | '20221129'
 '2K'         | '1%'      | '1/16W'  | '0402LF'  | 'CHIP'   | 'CS22002FB15'(!)        = ''              | ''                 | 'CS22002FB15'           |'R0402'| '(R0402-0201)'                 | '2K'      | '1%'    | '1/16W'  | 'DISCRETE' | 'RES CHIP 2K 1/16W +-1%(0402)WTC'                  | 'CHIPR0402'    | ''          | ''            | '20221129'
 '2K'         | '1%'      | '1/16W'  | '0402LF'  | 'EMPTY'  | 'CS22002FB15'(!)        = ''              | ''                 | 'CS22002FB15'           |'R0402'| '(R0402-0201)'                 | '2K'      | '1%'    | '1/16W'  | 'IO'       | 'RES CHIP 2K 1/16W +-1%(0402)WTC'                  | 'CHIPR0402'    | ''          | ''            | '20221129'
 '0.003'      | '1%'      | '3W'     | '2512LF'  | 'CHIP'   | 'CS+003DFR04'(!)        = ''              | ''                 | 'CS+003DFR04'           |'R2512XF'| '(SMR2512AW)'                  | '0.003'   | '1%'    | '3W'     | 'DISCRETE' | 'RES CHIP 0.003 3W +-1%(2512)TAI'                  | 'CHIPR2512'    | ''          | ''            | '20221201'
 '0.003'      | '1%'      | '3W'     | '2512LF'  | 'EMPTY'  | 'CS+003DFR04'(!)        = ''              | ''                 | 'CS+003DFR04'           |'R2512XF'| '(SMR2512AW)'                  | '0.003'   | '1%'    | '3W'     | 'IO'       | 'RES CHIP 0.003 3W +-1%(2512)TAI'                  | 'CHIPR2512'    | ''          | ''            | '20221201'
 '200'        | '1%'      | '1/20W'  | '0201LF'  | 'CHIP'   | 'CS12001FE12'(!)        = ''              | ''                 | 'CS12001FE12'           |'R0201'| '(SMR0201AW)'                  | '200'     | '1%'    | '1/20W'  | 'DISCRETE' | 'RES CHIP 200 1/20W +-1%(0201)EF'                  | 'CHIPR0201'    | ''          | ''            | '20221202'
 '200'        | '1%'      | '1/20W'  | '0201LF'  | 'EMPTY'  | 'CS12001FE12'(!)        = ''              | ''                 | 'CS12001FE12'           |'R0201'| '(SMR0201AW)'                  | '200'     | '1%'    | '1/20W'  | 'IO'       | 'RES CHIP 200 1/20W +-1%(0201)EF'                  | 'CHIPR0201'    | ''          | ''            | '20221202'
 '33.2'       | '1%'      | '1/20W'  | '0201LF'  | 'CHIP'   | 'CS03321FE09'(!)        = ''              | ''                 | 'CS03321FE09'           |'R0201'| '(SMR0201AW)'                  | '33.2'    | '1%'    | '1/20W'  | 'DISCRETE' | 'RES CHIP 33.2 1/20W +-1%(0201)EF'                 | 'CHIPR0201'    | ''          | ''            | '20221202'
 '33.2'       | '1%'      | '1/20W'  | '0201LF'  | 'EMPTY'  | 'CS03321FE09'(!)        = ''              | ''                 | 'CS03321FE09'           |'R0201'| '(SMR0201AW)'                  | '33.2'    | '1%'    | '1/20W'  | 'IO'       | 'RES CHIP 33.2 1/20W +-1%(0201)EF'                 | 'CHIPR0201'    | ''          | ''            | '20221202'
 '0.002'      | '1%'      | '3W'     | '2512LF'  | 'CHIP'   | 'CS+002DFR08'(!)        = ''              | ''                 | 'CS+002DFR08'           |'R2512XJ'| '(SMR2512AW)'                  | '0.002'   | '1%'    | '3W'     | 'DISCRETE' | 'RES CHIP 0.002 3W +-1%(2512)RLC'                  | 'CHIPR2512'    | ''          | ''            | '20221215'
 '0.002'      | '1%'      | '3W'     | '2512LF'  | 'EMPTY'  | 'CS+002DFR08'(!)        = ''              | ''                 | 'CS+002DFR08'           |'R2512XJ'| '(SMR2512AW)'                  | '0.002'   | '1%'    | '3W'     | 'IO'       | 'RES CHIP 0.002 3W +-1%(2512)RLC'                  | 'CHIPR2512'    | ''          | ''            | '20221215'
 '0.002'      | '1%'      | '3W'     | '2512LF'  | 'CHIP'   | 'CS+002DFR09'(!)        = ''              | ''                 | 'CS+002DFR09'           |'R2512XF'| '(SMR2512AW)'                  | '0.002'   | '1%'    | '3W'     | 'DISCRETE' | 'RES CHIP 0.002 3W +-1%(2512)TAI'                  | 'CHIPR2512'    | ''          | ''            | '20221215'
 '0.002'      | '1%'      | '3W'     | '2512LF'  | 'EMPTY'  | 'CS+002DFR09'(!)        = ''              | ''                 | 'CS+002DFR09'           |'R2512XF'| '(SMR2512AW)'                  | '0.002'   | '1%'    | '3W'     | 'IO'       | 'RES CHIP 0.002 3W +-1%(2512)TAI'                  | 'CHIPR2512'    | ''          | ''            | '20221215'
 '0.002'      | '1%'      | '3W'     | '2512LF'  | 'CHIP'   | 'CS+002DFR10'(!)        = ''              | ''                 | 'CS+002DFR10'           |'R2512XAC'| '(SMR2512AW)'                  | '0.002'   | '1%'    | '3W'     | 'DISCRETE' | 'RES CHIP 0.002 3W +-1%(2512)ERO'                  | 'CHIPR2512'    | ''          | ''            | '20221215'
 '0.002'      | '1%'      | '3W'     | '2512LF'  | 'EMPTY'  | 'CS+002DFR10'(!)        = ''              | ''                 | 'CS+002DFR10'           |'R2512XAC'| '(SMR2512AW)'                  | '0.002'   | '1%'    | '3W'     | 'IO'       | 'RES CHIP 0.002 3W +-1%(2512)ERO'                  | 'CHIPR2512'    | ''          | ''            | '20221215'
 '0.003'      | '1%'      | '3W'     | '2512LF'  | 'CHIP'   | 'CS+003DFR05'(!)        = ''              | ''                 | 'CS+003DFR05'           |'R2512XAD'| '(SMR2512AW)'                  | '0.003'   | '1%'    | '3W'     | 'DISCRETE' | 'RES CHIP 0.003 3W +-1%(2512)ERO'                  | 'CHIPR2512'    | ''          | ''            | '20221216'
 '0.003'      | '1%'      | '3W'     | '2512LF'  | 'EMPTY'  | 'CS+003DFR05'(!)        = ''              | ''                 | 'CS+003DFR05'           |'R2512XAD'| '(SMR2512AW)'                  | '0.003'   | '1%'    | '3W'     | 'IO'       | 'RES CHIP 0.003 3W +-1%(2512)ERO'                  | 'CHIPR2512'    | ''          | ''            | '20221216'
 '56K'        | '0.1%'    | '1/16W'  | '0402LF'  | 'CHIP'   | 'CS35602BB01'(!)        = 'End of Design' | 'Comp-Approve'     | 'CS35602BB01'           |'R0402'| '(R0402-0201)'                 | '56K'     | '0.1%'  | '1/16W'  | 'DISCRETE' | 'RES CHIP 56K 1/16W +-0.1%(0402)EF'                | 'CHIPR0402'    | ''          | ''            | '20221214'
 '56K'        | '0.1%'    | '1/16W'  | '0402LF'  | 'EMPTY'  | 'CS35602BB01'(!)        = 'End of Design' | 'Comp-Approve'     | 'CS35602BB01'           |'R0402'| '(R0402-0201)'                 | '56K'     | '0.1%'  | '1/16W'  | 'IO'       | 'RES CHIP 56K 1/16W +-0.1%(0402)EF'                | 'CHIPR0402'    | ''          | ''            | '20221214'
 '549'        | '1%'      | '1/16W'  | '0402LF'  | 'CHIP'   | 'CS15492FB09'(!)        = ''              | ''                 | 'CS15492FB09'           |'R0402'| '(R0402-0201)'                 | '549'     | '1%'    | '1/16W'  | 'DISCRETE' | 'RES CHIP 549 1/16W +-1%(0402)WTC'                 | 'CHIPR0402'    | ''          | ''            | '20221219'
 '549'        | '1%'      | '1/16W'  | '0402LF'  | 'EMPTY'  | 'CS15492FB09'(!)        = ''              | ''                 | 'CS15492FB09'           |'R0402'| '(R0402-0201)'                 | '549'     | '1%'    | '1/16W'  | 'IO'       | 'RES CHIP 549 1/16W +-1%(0402)WTC'                 | 'CHIPR0402'    | ''          | ''            | '20221219'
 '14.7K'      | '1%'      | '1/16W'  | '0402LF'  | 'CHIP'   | 'CS31472FB02'(!)        = 'End of Design' | 'Comp-Approve'     | 'CS31472FB02'           |'R0402'| '(R0402-0201)'                 | '14.7K'   | '1%'    | '1/16W'  | 'DISCRETE' | 'RES CHIP 14.7K 1/16W +-1%(0402)EF'                | 'CHIPR0402'    | ''          | ''            | '20221220'
 '14.7K'      | '1%'      | '1/16W'  | '0402LF'  | 'EMPTY'  | 'CS31472FB02'(!)        = 'End of Design' | 'Comp-Approve'     | 'CS31472FB02'           |'R0402'| '(R0402-0201)'                 | '14.7K'   | '1%'    | '1/16W'  | 'IO'       | 'RES CHIP 14.7K 1/16W +-1%(0402)EF'                | 'CHIPR0402'    | ''          | ''            | '20221220'
 '1.05K'      | '1%'      | '1/16W'  | '0402LF'  | 'CHIP'   | 'CS21052FB06'(!)        = ''              | ''                 | 'CS21052FB06'           |'R0402'| '(R0402-0201)'                 | '1.05K'   | '1%'    | '1/16W'  | 'DISCRETE' | 'RES CHIP 1.05K 1/16W +-1%(0402)EF'                | 'CHIPR0402'    | ''          | ''            | '20221221'
 '1.05K'      | '1%'      | '1/16W'  | '0402LF'  | 'EMPTY'  | 'CS21052FB06'(!)        = ''              | ''                 | 'CS21052FB06'           |'R0402'| '(R0402-0201)'                 | '1.05K'   | '1%'    | '1/16W'  | 'IO'       | 'RES CHIP 1.05K 1/16W +-1%(0402)EF'                | 'CHIPR0402'    | ''          | ''            | '20221221'
 '27'         | '1%'      | '1/16W'  | '0402LF'  | 'CHIP'   | 'CS02702FB01'(!)        = ''              | ''                 | 'CS02702FB01'           |'R0402'| '(R0402-0201)'                 | '27'      | '1%'    | '1/16W'  | 'DISCRETE' | 'RES CHIP 27 1/16W +-1%(0402)EF'                   | 'CHIPR0402'    | ''          | ''            | '20221222'
 '27'         | '1%'      | '1/16W'  | '0402LF'  | 'EMPTY'  | 'CS02702FB01'(!)        = ''              | ''                 | 'CS02702FB01'           |'R0402'| '(R0402-0201)'                 | '27'      | '1%'    | '1/16W'  | 'IO'       | 'RES CHIP 27 1/16W +-1%(0402)EF'                   | 'CHIPR0402'    | ''          | ''            | '20221222'
 '301'        | '1%'      | '1/16W'  | '0402LF'  | 'CHIP'   | 'CS13012FB10'(!)        = ''              | ''                 | 'CS13012FB10'           |'R0402'| '(R0402-0201)'                 | '301'     | '1%'    | '1/16W'  | 'DISCRETE' | 'RES CHIP 301 1/16W +-1%(0402)WTC'                 | 'CHIPR0402'    | ''          | ''            | '20221226'
 '301'        | '1%'      | '1/16W'  | '0402LF'  | 'EMPTY'  | 'CS13012FB10'(!)        = ''              | ''                 | 'CS13012FB10'           |'R0402'| '(R0402-0201)'                 | '301'     | '1%'    | '1/16W'  | 'IO'       | 'RES CHIP 301 1/16W +-1%(0402)WTC'                 | 'CHIPR0402'    | ''          | ''            | '20221226'
 '0.015'      | '0.5%'    | '7W'     | '2818LF'  | 'CHIP'   | 'CS+015LDX00'(!)        = ''              | ''                 | 'CS+015LDX00'           |'R2818XA'| '(SMR2818AW)'                  | '0.015'   | '0.5%'  | '7W'     | 'DISCRETE' | 'RES CHIP 0.015 7W +-0.5%(2818)SIL AEC'            | 'CHIPR2818'    | ''          | ''            | '20230118'
 '0.015'      | '0.5%'    | '7W'     | '2818LF'  | 'EMPTY'  | 'CS+015LDX00'(!)        = ''              | ''                 | 'CS+015LDX00'           |'R2818XA'| '(SMR2818AW)'                  | '0.015'   | '0.5%'  | '7W'     | 'IO'       | 'RES CHIP 0.015 7W +-0.5%(2818)SIL AEC'            | 'CHIPR2818'    | ''          | ''            | '20230118'
 '174K'       | '0.1%'    | '1/8W'   | '0805LF'  | 'CHIP'   | 'CS41744BA00'(!)        = ''              | ''                 | 'CS41744BA00'           |'R0805_H26'| '(SMR0805AW)'                  | '174K'    | '0.1%'  | '1/8W'   | 'DISCRETE' | 'RES CHIP 174K 1/8W +-0.1%(0805)EF'                | 'CHIPR0805'    | ''          | ''            | '20230218'
 '174K'       | '0.1%'    | '1/8W'   | '0805LF'  | 'EMPTY'  | 'CS41744BA00'(!)        = ''              | ''                 | 'CS41744BA00'           |'R0805_H26'| '(SMR0805AW)'                  | '174K'    | '0.1%'  | '1/8W'   | 'IO'       | 'RES CHIP 174K 1/8W +-0.1%(0805)EF'                | 'CHIPR0805'    | ''          | ''            | '20230218'
 '82K'        | '0.1%'    | '1/8W'   | '0805LF'  | 'CHIP'   | 'CS38204BA00'(!)        = ''              | ''                 | 'CS38204BA00'           |'R0805_H26'| '(SMR0805AW)'                  | '82K'     | '0.1%'  | '1/8W'   | 'DISCRETE' | 'RES CHIP 82K 1/8W +-0.1%(0805)EF'                 | 'CHIPR0805'    | ''          | ''            | '20230218'
 '82K'        | '0.1%'    | '1/8W'   | '0805LF'  | 'EMPTY'  | 'CS38204BA00'(!)        = ''              | ''                 | 'CS38204BA00'           |'R0805_H26'| '(SMR0805AW)'                  | '82K'     | '0.1%'  | '1/8W'   | 'IO'       | 'RES CHIP 82K 1/8W +-0.1%(0805)EF'                 | 'CHIPR0805'    | ''          | ''            | '20230218'
 '11.5K'      | '0.1%'    | '1/16W'  | '0402LF'  | 'CHIP'   | 'CS31152BB05'(!)        = ''              | ''                 | 'CS31152BB05'           |'R0402'| '(R0402-0201)'                 | '11.5K'   | '0.1%'  | '1/16W'  | 'DISCRETE' | 'RES CHIP 11.5K 1/16W +-0.1%(0402)EF'              | 'CHIPR0402'    | ''          | ''            | '20230218'
 '11.5K'      | '0.1%'    | '1/16W'  | '0402LF'  | 'EMPTY'  | 'CS31152BB05'(!)        = ''              | ''                 | 'CS31152BB05'           |'R0402'| '(R0402-0201)'                 | '11.5K'   | '0.1%'  | '1/16W'  | 'IO'       | 'RES CHIP 11.5K 1/16W +-0.1%(0402)EF'              | 'CHIPR0402'    | ''          | ''            | '20230218'
 '5.49K'      | '0.1%'    | '1/16W'  | '0402LF'  | 'CHIP'   | 'CS25492BB00'(!)        = ''              | ''                 | 'CS25492BB00'           |'R0402'| '(R0402-0201)'                 | '5.49K'   | '0.1%'  | '1/16W'  | 'DISCRETE' | 'RES CHIP 5.49K 1/16W +-0.1%(0402)EF'              | 'CHIPR0402'    | ''          | ''            | '20230218'
 '5.49K'      | '0.1%'    | '1/16W'  | '0402LF'  | 'EMPTY'  | 'CS25492BB00'(!)        = ''              | ''                 | 'CS25492BB00'           |'R0402'| '(R0402-0201)'                 | '5.49K'   | '0.1%'  | '1/16W'  | 'IO'       | 'RES CHIP 5.49K 1/16W +-0.1%(0402)EF'              | 'CHIPR0402'    | ''          | ''            | '20230218'
 '120K'       | '0.1%'    | '1/16W'  | '0402LF'  | 'CHIP'   | 'CS41202BB01'(!)        = ''              | ''                 | 'CS41202BB01'           |'R0402'| '(R0402-0201)'                 | '120K'    | '0.1%'  | '1/16W'  | 'DISCRETE' | 'RES CHIP 120K 1/16W +-0.1%(0402)EF'               | 'CHIPR0402'    | ''          | ''            | '20230218'
 '120K'       | '0.1%'    | '1/16W'  | '0402LF'  | 'EMPTY'  | 'CS41202BB01'(!)        = ''              | ''                 | 'CS41202BB01'           |'R0402'| '(R0402-0201)'                 | '120K'    | '0.1%'  | '1/16W'  | 'IO'       | 'RES CHIP 120K 1/16W +-0.1%(0402)EF'               | 'CHIPR0402'    | ''          | ''            | '20230218'
 '10.5K'      | '0.1%'    | '1/16W'  | '0402LF'  | 'CHIP'   | 'CS31052BB05'(!)        = ''              | ''                 | 'CS31052BB05'           |'R0402'| '(R0402-0201)'                 | '10.5K'   | '0.1%'  | '1/16W'  | 'DISCRETE' | 'RES CHIP 10.5K 1/16W +-0.1%(0402)EF'              | 'CHIPR0402'    | ''          | ''            | '20230218'
 '10.5K'      | '0.1%'    | '1/16W'  | '0402LF'  | 'EMPTY'  | 'CS31052BB05'(!)        = ''              | ''                 | 'CS31052BB05'           |'R0402'| '(R0402-0201)'                 | '10.5K'   | '0.1%'  | '1/16W'  | 'IO'       | 'RES CHIP 10.5K 1/16W +-0.1%(0402)EF'              | 'CHIPR0402'    | ''          | ''            | '20230218'
 '324K'       | '1%'      | '1/16W'  | '0402LF'  | 'CHIP'   | 'CS43242FB11'(!)        = 'End of Design' | 'Comp-Release Qty' | 'CS43242FB11'           |'R0402'| '(R0402-0201)'                 | '324K'    | '1%'    | '1/16W'  | 'DISCRETE' | 'RES CHIP 324K 1/16W +-1% (0402)'                  | 'CHIPR0402'    | ''          | ''            | '20230307'
 '324K'       | '1%'      | '1/16W'  | '0402LF'  | 'EMPTY'  | 'CS43242FB11'(!)        = 'End of Design' | 'Comp-Release Qty' | 'CS43242FB11'           |'R0402'| '(R0402-0201)'                 | '324K'    | '1%'    | '1/16W'  | 'IO'       | 'RES CHIP 324K 1/16W +-1% (0402)'                  | 'CHIPR0402'    | ''          | ''            | '20230307'
 '49.9'       | '1%'      | '1/20W'  | '0201LF'  | 'CHIP'   | 'CS04991FE06'(!)        = 'End of Design' | 'Comp-Approve'     | 'CS04991FE06'           |'R0201'| '(SMR0201AW)'                  | '49.9'    | '1%'    | '1/20W'  | 'DISCRETE' | 'RES CHIP 49.9 1/20W +-1%(0201)EF'                 | 'CHIPR0201'    | ''          | ''            | '20230307'
 '49.9'       | '1%'      | '1/20W'  | '0201LF'  | 'EMPTY'  | 'CS04991FE06'(!)        = 'End of Design' | 'Comp-Approve'     | 'CS04991FE06'           |'R0201'| '(SMR0201AW)'                  | '49.9'    | '1%'    | '1/20W'  | 'IO'       | 'RES CHIP 49.9 1/20W +-1%(0201)EF'                 | 'CHIPR0201'    | ''          | ''            | '20230307'
 '4.64K'      | '1%'      | '1/16W'  | '0402LF'  | 'CHIP'   | 'CS24642FB14'(!)        = 'End of Design' | 'Comp-Approve'     | 'CS24642FB14'           |'R0402'| '(R0402-0201)'                 | '4.64K'   | '1%'    | '1/16W'  | 'DISCRETE' | 'RES CHIP 4.64K 1/16W +-1% (0402)'                 | 'CHIPR0402'    | ''          | ''            | '20230316'
 '4.64K'      | '1%'      | '1/16W'  | '0402LF'  | 'EMPTY'  | 'CS24642FB14'(!)        = 'End of Design' | 'Comp-Approve'     | 'CS24642FB14'           |'R0402'| '(R0402-0201)'                 | '4.64K'   | '1%'    | '1/16W'  | 'IO'       | 'RES CHIP 4.64K 1/16W +-1% (0402)'                 | 'CHIPR0402'    | ''          | ''            | '20230316'
 '16.9'       | '1%'      | '1/16W'  | '0402LF'  | 'CHIP'   | 'CS01692FB07'(!)        = 'End of Design' | 'Comp-Approve'     | 'CS01692FB07'           |'R0402'| '(R0402-0201)'                 | '16.9'    | '1%'    | '1/16W'  | 'DISCRETE' | 'RES CHIP 16.9 1/16W +-1%(0402)'                   | 'CHIPR0402'    | ''          | ''            | '20230330'
 '16.9'       | '1%'      | '1/16W'  | '0402LF'  | 'EMPTY'  | 'CS01692FB07'(!)        = 'End of Design' | 'Comp-Approve'     | 'CS01692FB07'           |'R0402'| '(R0402-0201)'                 | '16.9'    | '1%'    | '1/16W'  | 'IO'       | 'RES CHIP 16.9 1/16W +-1%(0402)'                   | 'CHIPR0402'    | ''          | ''            | '20230330'
 '402K'       | '1%'      | '1/8W'   | '0805LF'  | 'CHIP'   | 'CS44024FA00'(!)        = ''              | ''                 | 'CS44024FA00'           |'R0805'| '(SMR0805AW)'                  | '402K'    | '1%'    | '1/8W'   | 'DISCRETE' | 'RES CHIP 402K 1/8W +-1%(0805)EF'                  | 'CHIPR0805'    | ''          | ''            | '20230426'
 '402K'       | '1%'      | '1/8W'   | '0805LF'  | 'EMPTY'  | 'CS44024FA00'(!)        = ''              | ''                 | 'CS44024FA00'           |'R0805'| '(SMR0805AW)'                  | '402K'    | '1%'    | '1/8W'   | 'IO'       | 'RES CHIP 402K 1/8W +-1%(0805)EF'                  | 'CHIPR0805'    | ''          | ''            | '20230426'
 '422K'       | '1%'      | '1/8W'   | '0805LF'  | 'CHIP'   | 'CS44224FA00'(!)        = ''              | ''                 | 'CS44224FA00'           |'R0805'| '(SMR0805AW)'                  | '422K'    | '1%'    | '1/8W'   | 'DISCRETE' | 'RES CHIP 422K 1/8W +-1%(0805)EF'                  | 'CHIPR0805'    | ''          | ''            | '20230426'
 '422K'       | '1%'      | '1/8W'   | '0805LF'  | 'EMPTY'  | 'CS44224FA00'(!)        = ''              | ''                 | 'CS44224FA00'           |'R0805'| '(SMR0805AW)'                  | '422K'    | '1%'    | '1/8W'   | 'IO'       | 'RES CHIP 422K 1/8W +-1%(0805)EF'                  | 'CHIPR0805'    | ''          | ''            | '20230426'
 '0'          | '1%'      | '1/8W'   | '0805LF'  | 'CHIP'   | 'CS00004FA00'(!)        = 'End of Design' | 'Comp-Approve'     | 'CS00004FA00'           |'R0805'| '(SMR0805AW)'                  | '0'       | '1%'    | '1/8W'   | 'DISCRETE' | 'RES CHIP 0 1/8W +-1% ( 0805 )'                    | 'CHIPR0805 '   | ''          | ''            | '20230509'
 '0'          | '1%'      | '1/8W'   | '0805LF'  | 'EMPTY'  | 'CS00004FA00'(!)        = 'End of Design' | 'Comp-Approve'     | 'CS00004FA00'           |'R0805'| '(SMR0805AW)'                  | '0'       | '1%'    | '1/8W'   | 'IO'       | 'RES CHIP 0 1/8W +-1% ( 0805 )'                    | 'CHIPR0805 '   | ''          | ''            | '20230509'
 '29.4K'      | '1%'      | '1/4W'   | '1206LF'  | 'CHIP'   | 'CS32946F200'(!)        = 'End of Design' | 'Comp-Approve'     | 'CS32946F200'           |'R1206XN'| '(SMR1206AW)'                  | '29.4K'   | '1%'    | '1/4W'   | 'DISCRETE' | 'RES CHIP 29.4K 1/4W +-1%(1206)'                   | 'CHIPR1206'    | ''          | ''            | '20230518'
 '29.4K'      | '1%'      | '1/4W'   | '1206LF'  | 'EMPTY'  | 'CS32946F200'(!)        = 'End of Design' | 'Comp-Approve'     | 'CS32946F200'           |'R1206XN'| '(SMR1206AW)'                  | '29.4K'   | '1%'    | '1/4W'   | 'IO'       | 'RES CHIP 29.4K 1/4W +-1%(1206)'                   | 'CHIPR1206'    | ''          | ''            | '20230518'
 '22'         | '1%'      | '1/20W'  | '0201LF'  | 'CHIP'   | 'CS02201FE11'(!)        = ''              | ''                 | 'CS02201FE11'           |'R0201'| '(SMR0201AW)'                  | '22'      | '1%'    | '1/20W'  | 'DISCRETE' | 'RES CHIP 22 1/20W +-1%(0201)EF'                   | 'CHIPR0201'    | ''          | ''            | '20230530'
 '22'         | '1%'      | '1/20W'  | '0201LF'  | 'EMPTY'  | 'CS02201FE11'(!)        = ''              | ''                 | 'CS02201FE11'           |'R0201'| '(SMR0201AW)'                  | '22'      | '1%'    | '1/20W'  | 'IO'       | 'RES CHIP 22 1/20W +-1%(0201)EF'                   | 'CHIPR0201'    | ''          | ''            | '20230530'
 '6.2K'       | '5%'      | '4W'     | '2512LF'  | 'CHIP'   | 'CS2620FJR00'(!)        = ''              | ''                 | 'CS2620FJR00'           |'R2512XAE'| '(SMR2512AW)'                  | '6.2K'    | '5%'    | '4W'     | 'DISCRETE' | 'RES CHIP 6.2K 4W +-5%(2512)'                      | 'CHIPR2512'    | ''          | ''            | '20230609'
 '6.2K'       | '5%'      | '4W'     | '2512LF'  | 'EMPTY'  | 'CS2620FJR00'(!)        = ''              | ''                 | 'CS2620FJR00'           |'R2512XAE'| '(SMR2512AW)'                  | '6.2K'    | '5%'    | '4W'     | 'IO'       | 'RES CHIP 6.2K 4W +-5%(2512)'                      | 'CHIPR2512'    | ''          | ''            | '20230609'
 '4.7K'       | '5%'      | '4W'     | '2512LF'  | 'CHIP'   | 'CS2470FJR00'(!)        = ''              | ''                 | 'CS2470FJR00'           |'R2512XAE'| '(SMR2512AW)'                  | '4.7K'    | '5%'    | '4W'     | 'DISCRETE' | 'RES CHIP 4.7K 4W +-5%(2512)'                      | 'CHIPR2512'    | ''          | ''            | '20230609'
 '4.7K'       | '5%'      | '4W'     | '2512LF'  | 'EMPTY'  | 'CS2470FJR00'(!)        = ''              | ''                 | 'CS2470FJR00'           |'R2512XAE'| '(SMR2512AW)'                  | '4.7K'    | '5%'    | '4W'     | 'IO'       | 'RES CHIP 4.7K 4W +-5%(2512)'                      | 'CHIPR2512'    | ''          | ''            | '20230609'
 '3.6K'       | '5%'      | '4W'     | '2512LF'  | 'CHIP'   | 'CS2360FJR00'(!)        = ''              | ''                 | 'CS2360FJR00'           |'R2512XAE'| '(SMR2512AW)'                  | '3.6K'    | '5%'    | '4W'     | 'DISCRETE' | 'RES CHIP 3.6K 4W +-5%(2512)'                      | 'CHIPR2512'    | ''          | ''            | '20230609'
 '3.6K'       | '5%'      | '4W'     | '2512LF'  | 'EMPTY'  | 'CS2360FJR00'(!)        = ''              | ''                 | 'CS2360FJR00'           |'R2512XAE'| '(SMR2512AW)'                  | '3.6K'    | '5%'    | '4W'     | 'IO'       | 'RES CHIP 3.6K 4W +-5%(2512)'                      | 'CHIPR2512'    | ''          | ''            | '20230609'
 '2K'         | '5%'      | '4W'     | '2512LF'  | 'CHIP'   | 'CS2200FJR00'(!)        = ''              | ''                 | 'CS2200FJR00'           |'R2512XAE'| '(SMR2512AW)'                  | '2K'      | '5%'    | '4W'     | 'DISCRETE' | 'RES CHIP 2K 4W +-5%(2512)'                        | 'CHIPR2512'    | ''          | ''            | '20230612'
 '2K'         | '5%'      | '4W'     | '2512LF'  | 'EMPTY'  | 'CS2200FJR00'(!)        = ''              | ''                 | 'CS2200FJR00'           |'R2512XAE'| '(SMR2512AW)'                  | '2K'      | '5%'    | '4W'     | 'IO'       | 'RES CHIP 2K 4W +-5%(2512)'                        | 'CHIPR2512'    | ''          | ''            | '20230612'
 '1.8K'       | '5%'      | '4W'     | '2512LF'  | 'CHIP'   | 'CS2180FJR00'(!)        = ''              | ''                 | 'CS2180FJR00'           |'R2512XAE'| '(SMR2512AW)'                  | '1.8K'    | '5%'    | '4W'     | 'DISCRETE' | 'RES CHIP 1.8K 4W +-5%(2512)'                      | 'CHIPR2512'    | ''          | ''            | '20230612'
 '1.8K'       | '5%'      | '4W'     | '2512LF'  | 'EMPTY'  | 'CS2180FJR00'(!)        = ''              | ''                 | 'CS2180FJR00'           |'R2512XAE'| '(SMR2512AW)'                  | '1.8K'    | '5%'    | '4W'     | 'IO'       | 'RES CHIP 1.8K 4W +-5%(2512)'                      | 'CHIPR2512'    | ''          | ''            | '20230612'
 '750'        | '5%'      | '4W'     | '2512LF'  | 'CHIP'   | 'CS1750FJR00'(!)        = ''              | ''                 | 'CS1750FJR00'           |'R2512XAE'| '(SMR2512AW)'                  | '750'     | '5%'    | '4W'     | 'DISCRETE' | 'RES CHIP 750 4W +-5%(2512)'                       | 'CHIPR2512'    | ''          | ''            | '20230612'
 '750'        | '5%'      | '4W'     | '2512LF'  | 'EMPTY'  | 'CS1750FJR00'(!)        = ''              | ''                 | 'CS1750FJR00'           |'R2512XAE'| '(SMR2512AW)'                  | '750'     | '5%'    | '4W'     | 'IO'       | 'RES CHIP 750 4W +-5%(2512)'                       | 'CHIPR2512'    | ''          | ''            | '20230612'
 '560'        | '5%'      | '4W'     | '2512LF'  | 'CHIP'   | 'CS1560FJR00'(!)        = ''              | ''                 | 'CS1560FJR00'           |'R2512XAE'| '(SMR2512AW)'                  | '560'     | '5%'    | '4W'     | 'DISCRETE' | 'RES CHIP 560 4W +-5%(2512)'                       | 'CHIPR2512'    | ''          | ''            | '20230612'
 '560'        | '5%'      | '4W'     | '2512LF'  | 'EMPTY'  | 'CS1560FJR00'(!)        = ''              | ''                 | 'CS1560FJR00'           |'R2512XAE'| '(SMR2512AW)'                  | '560'     | '5%'    | '4W'     | 'IO'       | 'RES CHIP 560 4W +-5%(2512)'                       | 'CHIPR2512'    | ''          | ''            | '20230612'
 '620'        | '5%'      | '4W'     | '2512LF'  | 'CHIP'   | 'CS1620FJR00'(!)        = ''              | ''                 | 'CS1620FJR00'           |'R2512XAE'| '(SMR2512AW)'                  | '620'     | '5%'    | '4W'     | 'DISCRETE' | 'RES CHIP 620 4W +-5%(2512)'                       | 'CHIPR2512'    | ''          | ''            | '20230612'
 '620'        | '5%'      | '4W'     | '2512LF'  | 'EMPTY'  | 'CS1620FJR00'(!)        = ''              | ''                 | 'CS1620FJR00'           |'R2512XAE'| '(SMR2512AW)'                  | '620'     | '5%'    | '4W'     | 'IO'       | 'RES CHIP 620 4W +-5%(2512)'                       | 'CHIPR2512'    | ''          | ''            | '20230612'
 '1.2K'       | '5%'      | '4W'     | '2512LF'  | 'CHIP'   | 'CS2120FJR00'(!)        = ''              | ''                 | 'CS2120FJR00'           |'R2512XAE'| '(SMR2512AW)'                  | '1.2K'    | '5%'    | '4W'     | 'DISCRETE' | 'RES CHIP 1.2K 4W +-5%(2512)'                      | 'CHIPR2512'    | ''          | ''            | '20230612'
 '1.2K'       | '5%'      | '4W'     | '2512LF'  | 'EMPTY'  | 'CS2120FJR00'(!)        = ''              | ''                 | 'CS2120FJR00'           |'R2512XAE'| '(SMR2512AW)'                  | '1.2K'    | '5%'    | '4W'     | 'IO'       | 'RES CHIP 1.2K 4W +-5%(2512)'                      | 'CHIPR2512'    | ''          | ''            | '20230612'
 '1.3K'       | '5%'      | '4W'     | '2512LF'  | 'CHIP'   | 'CS2130FJR00'(!)        = ''              | ''                 | 'CS2130FJR00'           |'R2512XAE'| '(SMR2512AW)'                  | '1.3K'    | '5%'    | '4W'     | 'DISCRETE' | 'RES CHIP 1.3K 4W +-5%(2512)'                      | 'CHIPR2512'    | ''          | ''            | '20230612'
 '1.3K'       | '5%'      | '4W'     | '2512LF'  | 'EMPTY'  | 'CS2130FJR00'(!)        = ''              | ''                 | 'CS2130FJR00'           |'R2512XAE'| '(SMR2512AW)'                  | '1.3K'    | '5%'    | '4W'     | 'IO'       | 'RES CHIP 1.3K 4W +-5%(2512)'                      | 'CHIPR2512'    | ''          | ''            | '20230612'
 '1.5K'       | '5%'      | '4W'     | '2512LF'  | 'CHIP'   | 'CS2150FJR00'(!)        = ''              | ''                 | 'CS2150FJR00'           |'R2512XAE'| '(SMR2512AW)'                  | '1.5K'    | '5%'    | '4W'     | 'DISCRETE' | 'RES CHIP 1.5K 4W +-5%(2512)'                      | 'CHIPR2512'    | ''          | ''            | '20230612'
 '1.5K'       | '5%'      | '4W'     | '2512LF'  | 'EMPTY'  | 'CS2150FJR00'(!)        = ''              | ''                 | 'CS2150FJR00'           |'R2512XAE'| '(SMR2512AW)'                  | '1.5K'    | '5%'    | '4W'     | 'IO'       | 'RES CHIP 1.5K 4W +-5%(2512)'                      | 'CHIPR2512'    | ''          | ''            | '20230612'
 '680'        | '5%'      | '4W'     | '2512LF'  | 'CHIP'   | 'CS1680FJR00'(!)        = ''              | ''                 | 'CS1680FJR00'           |'R2512XAE'| '(SMR2512AW)'                  | '680'     | '5%'    | '4W'     | 'DISCRETE' | 'RES CHIP 680 4W +-5%(2512)'                       | 'CHIPR2512'    | ''          | ''            | '20230614'
 '680'        | '5%'      | '4W'     | '2512LF'  | 'EMPTY'  | 'CS1680FJR00'(!)        = ''              | ''                 | 'CS1680FJR00'           |'R2512XAE'| '(SMR2512AW)'                  | '680'     | '5%'    | '4W'     | 'IO'       | 'RES CHIP 680 4W +-5%(2512)'                       | 'CHIPR2512'    | ''          | ''            | '20230614'
 '10'         | '1%'      | '1W'     | '2512LF'  | 'CHIP'   | 'CS01008FR02'(!)        = ''              | ''                 | 'CS01008FR02'           |'R2512XAA'| '(SMR2512AW)'                  | '10'      | '1%'    | '1W'     | 'DISCRETE' | 'RES CHIP 10 1W +-1%(2512)EF'                      | 'CHIPR2512'    | ''          | ''            | '20230728'
 '10'         | '1%'      | '1W'     | '2512LF'  | 'EMPTY'  | 'CS01008FR02'(!)        = ''              | ''                 | 'CS01008FR02'           |'R2512XAA'| '(SMR2512AW)'                  | '10'      | '1%'    | '1W'     | 'IO'       | 'RES CHIP 10 1W +-1%(2512)EF'                      | 'CHIPR2512'    | ''          | ''            | '20230728'
 '10'         | '1%'      | '2W'     | '2512LF'  | 'CHIP'   | 'CS0100AFR02'(!)        = ''              | ''                 | 'CS0100AFR02'           |'R2512XAE'| '(SMR2512AW)'                  | '10'      | '1%'    | '2W'     | 'DISCRETE' | 'RES CHIP 10 2W +-1%(2512)EF'                      | 'CHIPR2512'    | ''          | ''            | '20230728'
 '10'         | '1%'      | '2W'     | '2512LF'  | 'EMPTY'  | 'CS0100AFR02'(!)        = ''              | ''                 | 'CS0100AFR02'           |'R2512XAE'| '(SMR2512AW)'                  | '10'      | '1%'    | '2W'     | 'IO'       | 'RES CHIP 10 2W +-1%(2512)EF'                      | 'CHIPR2512'    | ''          | ''            | '20230728'
 '0.25'       | '1%'      | '1/2W'   | '1206LF'  | 'CHIP'   | 'CS+2507F202'(!)        = ''              | ''                 | 'CS+2507F202'           |'R1206XU'| '(SMR1206AW)'                  | '0.25'    | '1%'    | '1/2W'   | 'DISCRETE' | 'RES CHIP 0.25 1/2W +-1%(1206)EF'                  | 'CHIPR1206'    | ''          | ''            | '20230728'
 '0.25'       | '1%'      | '1/2W'   | '1206LF'  | 'EMPTY'  | 'CS+2507F202'(!)        = ''              | ''                 | 'CS+2507F202'           |'R1206XU'| '(SMR1206AW)'                  | '0.25'    | '1%'    | '1/2W'   | 'IO'       | 'RES CHIP 0.25 1/2W +-1%(1206)EF'                  | 'CHIPR1206'    | ''          | ''            | '20230728'
 '0.25'       | '1%'      | '1/8W'   | '0805LF'  | 'CHIP'   | 'CS+2504FA00'(!)        = ''              | ''                 | 'CS+2504FA00'           |'R0805'| '(SMR0805AW)'                  | '0.25'    | '1%'    | '1/8W'   | 'DISCRETE' | 'RES CHIP 0.25 1/8W +-1%(0805)EF'                  | 'CHIPR0805'    | ''          | ''            | '20230728'
 '0.25'       | '1%'      | '1/8W'   | '0805LF'  | 'EMPTY'  | 'CS+2504FA00'(!)        = ''              | ''                 | 'CS+2504FA00'           |'R0805'| '(SMR0805AW)'                  | '0.25'    | '1%'    | '1/8W'   | 'IO'       | 'RES CHIP 0.25 1/8W +-1%(0805)EF'                  | 'CHIPR0805'    | ''          | ''            | '20230728'
 '0.25'       | '1%'      | '1/4W'   | '0805LF'  | 'CHIP'   | 'CS+2506FA01'(!)        = ''              | ''                 | 'CS+2506FA01'           |'R0805'| '(SMR0805AW)'                  | '0.25'    | '1%'    | '1/4W'   | 'DISCRETE' | 'RES CHIP 0.25 1/4W +-1%(0805)EF'                  | 'CHIPR0805'    | ''          | ''            | '20230728'
 '0.25'       | '1%'      | '1/4W'   | '0805LF'  | 'EMPTY'  | 'CS+2506FA01'(!)        = ''              | ''                 | 'CS+2506FA01'           |'R0805'| '(SMR0805AW)'                  | '0.25'    | '1%'    | '1/4W'   | 'IO'       | 'RES CHIP 0.25 1/4W +-1%(0805)EF'                  | 'CHIPR0805'    | ''          | ''            | '20230728'
 '84.5'       | '1%'      | '1/10W'  | '0603LF'  | 'CHIP'   | 'CS08453F900'(!)        = ''              | ''                 | 'CS08453F900'           |'R0603_W0-95'| '(SMR0603AW)'                  | '84.5'    | '1%'    | '1/10W'  | 'DISCRETE' | 'RES CHIP 84.5 1/10W +-1%(0603)EF'                 | 'CHIPR0603'    | ''          | ''            | '20230728'
 '84.5'       | '1%'      | '1/10W'  | '0603LF'  | 'EMPTY'  | 'CS08453F900'(!)        = ''              | ''                 | 'CS08453F900'           |'R0603_W0-95'| '(SMR0603AW)'                  | '84.5'    | '1%'    | '1/10W'  | 'IO'       | 'RES CHIP 84.5 1/10W +-1%(0603)EF'                 | 'CHIPR0603'    | ''          | ''            | '20230728'
 '5.1'        | '1%'      | '1/10W'  | '0603LF'  | 'CHIP'   | 'CS-5103F904'(!)        = ''              | ''                 | 'CS-5103F904'           |'R0603_W0-95'| '(SMR0603AW)'                  | '5.1'     | '1%'    | '1/10W'  | 'DISCRETE' | 'RES CHIP 5.1 1/10W +-1%(0603)EF'                  | 'CHIPR0603'    | ''          | ''            | '20230728'
 '5.1'        | '1%'      | '1/10W'  | '0603LF'  | 'EMPTY'  | 'CS-5103F904'(!)        = ''              | ''                 | 'CS-5103F904'           |'R0603_W0-95'| '(SMR0603AW)'                  | '5.1'     | '1%'    | '1/10W'  | 'IO'       | 'RES CHIP 5.1 1/10W +-1%(0603)EF'                  | 'CHIPR0603'    | ''          | ''            | '20230728'
 '124'        | '1%'      | '1/10W'  | '0603LF'  | 'CHIP'   | 'CS11243F900'(!)        = ''              | ''                 | 'CS11243F900'           |'R0603_W0-95'| '(SMR0603AW)'                  | '124'     | '1%'    | '1/10W'  | 'DISCRETE' | 'RES CHIP 124 1/10W +-1%(0603)EF'                  | 'CHIPR0603'    | ''          | ''            | '20230731'
 '124'        | '1%'      | '1/10W'  | '0603LF'  | 'EMPTY'  | 'CS11243F900'(!)        = ''              | ''                 | 'CS11243F900'           |'R0603_W0-95'| '(SMR0603AW)'                  | '124'     | '1%'    | '1/10W'  | 'IO'       | 'RES CHIP 124 1/10W +-1%(0603)EF'                  | 'CHIPR0603'    | ''          | ''            | '20230731'
 '768'        | '1%'      | '1/16W'  | '0402LF'  | 'CHIP'   | 'CS17682FB00'(!)        = 'End of Design'  | 'Comp-Approve'     | 'CS17682FB00'           |'R0402'| '(R0402-0201)'                 | '768'     | '1%'    | '1/16W'  | 'DISCRETE' | 'RES CHIP 768 1/16W +-1%(0402)'                    | 'CHIPR0402'    | ''          | ''            | '20230821'
 '768'        | '1%'      | '1/16W'  | '0402LF'  | 'EMPTY'  | 'CS17682FB00'(!)        = 'End of Design'  | 'Comp-Approve'     | 'CS17682FB00'           |'R0402'| '(R0402-0201)'                 | '768'     | '1%'    | '1/16W'  | 'IO'       | 'RES CHIP 768 1/16W +-1%(0402)'                    | 'CHIPR0402'    | ''          | ''            | '20230821'

END_PART

END.

